(kicad_pcb
	(version 20260206)
	(generator "pcbnew")
	(generator_version "10.0")
	(general
		(thickness 1.6)
		(legacy_teardrops no)
	)
	(paper "A4")
	(layers
		(0 "F.Cu" signal "TOP")
		(4 "In1.Cu" signal "L2")
		(6 "In2.Cu" signal "L3")
		(8 "In3.Cu" signal "L4")
		(10 "In4.Cu" signal "L5")
		(12 "In5.Cu" signal "L6")
		(14 "In6.Cu" signal "L7")
		(16 "In7.Cu" signal "L8")
		(18 "In8.Cu" signal "L9")
		(20 "In9.Cu" signal "L10")
		(22 "In10.Cu" signal "L11")
		(2 "B.Cu" signal "BOTTOM")
		(9 "F.Adhes" user "F.Adhesive")
		(11 "B.Adhes" user "B.Adhesive")
		(13 "F.Paste" user "Package Geometry/Pastemask Top")
		(15 "B.Paste" user "Package Geometry/Pastemask Bottom")
		(5 "F.SilkS" user "Ref Des/Silkscreen Top")
		(7 "B.SilkS" user "Ref Des/Silkscreen Bottom")
		(1 "F.Mask" user "Board Geometry/Soldermask Top")
		(3 "B.Mask" user "Board Geometry/Soldermask Bottom")
		(17 "Dwgs.User" user "User.Drawings")
		(19 "Cmts.User" user "User.Comments")
		(21 "Eco1.User" user "User.Eco1")
		(23 "Eco2.User" user "User.Eco2")
		(25 "Edge.Cuts" user "Board Geometry/Outline")
		(27 "Margin" user)
		(31 "F.CrtYd" user "Package Geometry/Place Bound Top")
		(29 "B.CrtYd" user "Package Geometry/Place Bound Bottom")
		(35 "F.Fab" user "Ref Des/Assembly Top")
		(33 "B.Fab" user "Ref Des/Assembly Bottom")
	)
	(setup
		(pad_to_mask_clearance 0)
		(allow_soldermask_bridges_in_footprints no)
		(tenting
			(front yes)
			(back yes)
		)
		(covering
			(front no)
			(back no)
		)
		(plugging
			(front no)
			(back no)
		)
		(capping no)
		(filling no)
		(pcbplotparams
			(layerselection 0x00000000_00000000_55555555_5755f5ff)
			(plot_on_all_layers_selection 0x00000000_00000000_00000000_00000000)
			(disableapertmacros no)
			(usegerberextensions no)
			(usegerberattributes yes)
			(usegerberadvancedattributes yes)
			(creategerberjobfile yes)
			(dashed_line_dash_ratio 12)
			(dashed_line_gap_ratio 3)
			(svgprecision 4)
			(plotframeref no)
			(mode 1)
			(useauxorigin no)
			(pdf_front_fp_property_popups yes)
			(pdf_back_fp_property_popups yes)
			(pdf_metadata yes)
			(pdf_single_document no)
			(dxfpolygonmode yes)
			(dxfimperialunits yes)
			(dxfusepcbnewfont yes)
			(psnegative no)
			(psa4output no)
			(plot_black_and_white yes)
			(sketchpadsonfab no)
			(plotpadnumbers no)
			(hidednponfab no)
			(sketchdnponfab yes)
			(crossoutdnponfab yes)
			(subtractmaskfromsilk no)
			(outputformat 1)
			(mirror no)
			(drillshape 1)
			(scaleselection 1)
			(outputdirectory "")
		)
	)
	(footprint ""
		(layer "F.Cu")
		(at 86.849966 -4.100068)
		(property "Reference" "GF1"
			(at 0 0 0)
			(layer "F.SilkS")
			(hide yes)
			(effects
				(font
					(size 1.27 1.27)
				)
			)
		)
		(property "Value" "GF-PCIE-164P-15-GP"
			(at 15.2654 -6.2992 0)
			(unlocked yes)
			(layer "F.Fab")
			(hide yes)
			(effects
				(font
					(size 1.016 1.016)
					(thickness 0.1524)
				)
			)
		)
		(property "Device Type" "GF-PCIE-164P-15"
			(at 15.2654 -7.8232 0)
			(unlocked yes)
			(layer "F.Fab")
			(hide yes)
			(effects
				(font
					(size 1.016 1.016)
					(thickness 0.1524)
				)
			)
		)
		(duplicate_pad_numbers_are_jumpers no)
		(fp_rect
			(start -73.8886 2.032)
			(end 13.8938 -6.223)
			(stroke
				(width 0)
				(type default)
			)
			(fill no)
			(layer "B.CrtYd")
		)
		(fp_rect
			(start -73.8886 2.032)
			(end 13.8938 -6.223)
			(stroke
				(width 0)
				(type default)
			)
			(fill no)
			(layer "F.CrtYd")
		)
		(fp_rect
			(start -73.8886 2.032)
			(end 13.8938 -6.223)
			(stroke
				(width 0)
				(type default)
			)
			(fill no)
			(layer "B.Fab")
		)
		(fp_rect
			(start -73.8886 2.032)
			(end 13.8938 -6.223)
			(stroke
				(width 0)
				(type default)
			)
			(fill no)
			(layer "F.Fab")
		)
		(fp_text user "02 Do not mirror"
			(at -11.811 3.4798 0)
			(unlocked yes)
			(layer "F.Fab")
			(effects
				(font
					(size 1.016 1.016)
					(thickness 0.1524)
				)
				(justify left)
			)
		)
		(pad "A1" smd rect
			(at 11.500104 -2.5908)
			(size 0.7112 3.2004)
			(layers "F.Cu" "F.Mask" "F.Paste")
			(net "BOARD_PRSNT#")
		)
		(pad "A2" smd rect
			(at 10.500106 -2.0955)
			(size 0.7112 4.191)
			(layers "F.Cu" "F.Mask" "F.Paste")
			(net "P12V")
		)
		(pad "A3" smd rect
			(at 9.500108 -2.0955)
			(size 0.7112 4.191)
			(layers "F.Cu" "F.Mask" "F.Paste")
			(net "P12V")
		)
		(pad "A4" smd rect
			(at 8.50011 -2.0955)
			(size 0.7112 4.191)
			(layers "F.Cu" "F.Mask" "F.Paste")
			(net "GND")
		)
		(pad "A5" smd rect
			(at 7.500112 -2.0955)
			(size 0.7112 4.191)
			(layers "F.Cu" "F.Mask" "F.Paste")
			(net "SLOT_ID0")
		)
		(pad "A6" smd rect
			(at 6.500114 -2.0955)
			(size 0.7112 4.191)
			(layers "F.Cu" "F.Mask" "F.Paste")
			(net "SLOT_ID1")
		)
		(pad "A7" smd rect
			(at 5.500116 -2.0955)
			(size 0.7112 4.191)
			(layers "F.Cu" "F.Mask" "F.Paste")
			(net "GF_CPU_TXD")
		)
		(pad "A8" smd rect
			(at 4.500118 -2.0955)
			(size 0.7112 4.191)
			(layers "F.Cu" "F.Mask" "F.Paste")
			(net "GF_CPU_RXD")
		)
		(pad "A9" smd rect
			(at 3.50012 -2.0955)
			(size 0.7112 4.191)
			(layers "F.Cu" "F.Mask" "F.Paste")
			(net "SLOT_ID2")
		)
		(pad "A10" smd rect
			(at 2.500122 -2.0955)
			(size 0.7112 4.191)
			(layers "F.Cu" "F.Mask" "F.Paste")
			(net "SLOT_ID3")
		)
		(pad "A11" smd rect
			(at 1.500124 -2.0955)
			(size 0.7112 4.191)
			(layers "F.Cu" "F.Mask" "F.Paste")
			(net "PCIE_RESET#")
		)
		(pad "A12" smd rect
			(at -1.500124 -2.0955)
			(size 0.7112 4.191)
			(layers "F.Cu" "F.Mask" "F.Paste")
			(net "GND")
		)
		(pad "A13" smd rect
			(at -2.500122 -2.0955)
			(size 0.7112 4.191)
			(layers "F.Cu" "F.Mask" "F.Paste")
			(net "CLK_100M_PCIE_SAS_DP")
		)
		(pad "A14" smd rect
			(at -3.50012 -2.0955)
			(size 0.7112 4.191)
			(layers "F.Cu" "F.Mask" "F.Paste")
			(net "CLK_100M_PCIE_SAS_DN")
		)
		(pad "A15" smd rect
			(at -4.500118 -2.0955)
			(size 0.7112 4.191)
			(layers "F.Cu" "F.Mask" "F.Paste")
			(net "GND")
		)
		(pad "A16" smd rect
			(at -5.500116 -2.0955)
			(size 0.7112 4.191)
			(layers "F.Cu" "F.Mask" "F.Paste")
			(net "GND")
		)
		(pad "A17" smd rect
			(at -6.500114 -2.0955)
			(size 0.7112 4.191)
			(layers "F.Cu" "F.Mask" "F.Paste")
			(net "P2E_CPU_SAS_RX_DP0")
		)
		(pad "A18" smd rect
			(at -7.500112 -2.0955)
			(size 0.7112 4.191)
			(layers "F.Cu" "F.Mask" "F.Paste")
			(net "P2E_CPU_SAS_RX_DN0")
		)
		(pad "A19" smd rect
			(at -8.50011 -2.0955)
			(size 0.7112 4.191)
			(layers "F.Cu" "F.Mask" "F.Paste")
			(net "GND")
		)
		(pad "A20" smd rect
			(at -9.500108 -2.0955)
			(size 0.7112 4.191)
			(layers "F.Cu" "F.Mask" "F.Paste")
			(net "GND")
		)
		(pad "A21" smd rect
			(at -10.500106 -2.0955)
			(size 0.7112 4.191)
			(layers "F.Cu" "F.Mask" "F.Paste")
			(net "P2E_CPU_SAS_RX_DP1")
		)
		(pad "A22" smd rect
			(at -11.500104 -2.0955)
			(size 0.7112 4.191)
			(layers "F.Cu" "F.Mask" "F.Paste")
			(net "P2E_CPU_SAS_RX_DN1")
		)
		(pad "A23" smd rect
			(at -12.500102 -2.0955)
			(size 0.7112 4.191)
			(layers "F.Cu" "F.Mask" "F.Paste")
			(net "GND")
		)
		(pad "A24" smd rect
			(at -13.5001 -2.0955)
			(size 0.7112 4.191)
			(layers "F.Cu" "F.Mask" "F.Paste")
			(net "GND")
		)
		(pad "A25" smd rect
			(at -14.500098 -2.0955)
			(size 0.7112 4.191)
			(layers "F.Cu" "F.Mask" "F.Paste")
			(net "P2E_CPU_SAS_RX_DP2")
		)
		(pad "A26" smd rect
			(at -15.500096 -2.0955)
			(size 0.7112 4.191)
			(layers "F.Cu" "F.Mask" "F.Paste")
			(net "P2E_CPU_SAS_RX_DN2")
		)
		(pad "A27" smd rect
			(at -16.500094 -2.0955)
			(size 0.7112 4.191)
			(layers "F.Cu" "F.Mask" "F.Paste")
			(net "GND")
		)
		(pad "A28" smd rect
			(at -17.500092 -2.0955)
			(size 0.7112 4.191)
			(layers "F.Cu" "F.Mask" "F.Paste")
			(net "GND")
		)
		(pad "A29" smd rect
			(at -18.50009 -2.0955)
			(size 0.7112 4.191)
			(layers "F.Cu" "F.Mask" "F.Paste")
			(net "P2E_CPU_SAS_RX_DP3")
		)
		(pad "A30" smd rect
			(at -19.500088 -2.0955)
			(size 0.7112 4.191)
			(layers "F.Cu" "F.Mask" "F.Paste")
			(net "P2E_CPU_SAS_RX_DN3")
		)
		(pad "A31" smd rect
			(at -20.500086 -2.0955)
			(size 0.7112 4.191)
			(layers "F.Cu" "F.Mask" "F.Paste")
			(net "GND")
		)
		(pad "A32" smd rect
			(at -21.500084 -2.0955)
			(size 0.7112 4.191)
			(layers "F.Cu" "F.Mask" "F.Paste")
			(net "GND")
		)
		(pad "A33" smd rect
			(at -22.500082 -2.0955)
			(size 0.7112 4.191)
			(layers "F.Cu" "F.Mask" "F.Paste")
			(net "SATA2_RX_C_DP0")
		)
		(pad "A34" smd rect
			(at -23.50008 -2.0955)
			(size 0.7112 4.191)
			(layers "F.Cu" "F.Mask" "F.Paste")
			(net "SATA2_RX_C_DN0")
		)
		(pad "A35" smd rect
			(at -24.500078 -2.0955)
			(size 0.7112 4.191)
			(layers "F.Cu" "F.Mask" "F.Paste")
			(net "GND")
		)
		(pad "A36" smd rect
			(at -25.500076 -2.0955)
			(size 0.7112 4.191)
			(layers "F.Cu" "F.Mask" "F.Paste")
			(net "GND")
		)
		(pad "A37" smd rect
			(at -26.500074 -2.0955)
			(size 0.7112 4.191)
			(layers "F.Cu" "F.Mask" "F.Paste")
			(net "CLK_100M_PCIE2_REFCLK_DP")
		)
		(pad "A38" smd rect
			(at -27.500072 -2.0955)
			(size 0.7112 4.191)
			(layers "F.Cu" "F.Mask" "F.Paste")
			(net "CLK_100M_PCIE2_REFCLK_DN")
		)
		(pad "A39" smd rect
			(at -28.50007 -2.0955)
			(size 0.7112 4.191)
			(layers "F.Cu" "F.Mask" "F.Paste")
			(net "GND")
		)
		(pad "A40" smd rect
			(at -29.500068 -2.0955)
			(size 0.7112 4.191)
			(layers "F.Cu" "F.Mask" "F.Paste")
			(net "GND")
		)
		(pad "A41" smd rect
			(at -30.500066 -2.0955)
			(size 0.7112 4.191)
			(layers "F.Cu" "F.Mask" "F.Paste")
			(net "PCIE_RSVD_A41")
		)
		(pad "A42" smd rect
			(at -31.500064 -2.0955)
			(size 0.7112 4.191)
			(layers "F.Cu" "F.Mask" "F.Paste")
			(net "GBE_R_SMBALRT#")
		)
		(pad "A43" smd rect
			(at -32.500062 -2.0955)
			(size 0.7112 4.191)
			(layers "F.Cu" "F.Mask" "F.Paste")
			(net "GND")
		)
		(pad "A44" smd rect
			(at -33.50006 -2.0955)
			(size 0.7112 4.191)
			(layers "F.Cu" "F.Mask" "F.Paste")
			(net "GND")
		)
		(pad "A45" smd rect
			(at -34.500058 -2.0955)
			(size 0.7112 4.191)
			(layers "F.Cu" "F.Mask" "F.Paste")
			(net "CPU_GBE_RX_C_DP0")
		)
		(pad "A46" smd rect
			(at -35.500056 -2.0955)
			(size 0.7112 4.191)
			(layers "F.Cu" "F.Mask" "F.Paste")
			(net "CPU_GBE_RX_C_DN0")
		)
		(pad "A47" smd rect
			(at -36.500054 -2.0955)
			(size 0.7112 4.191)
			(layers "F.Cu" "F.Mask" "F.Paste")
			(net "GND")
		)
		(pad "A48" smd rect
			(at -37.500052 -2.0955)
			(size 0.7112 4.191)
			(layers "F.Cu" "F.Mask" "F.Paste")
			(net "GND")
		)
		(pad "A49" smd rect
			(at -38.50005 -2.0955)
			(size 0.7112 4.191)
			(layers "F.Cu" "F.Mask" "F.Paste")
			(net "P2E_CPU_SAS_RX_DP4")
		)
		(pad "A50" smd rect
			(at -39.500048 -2.0955)
			(size 0.7112 4.191)
			(layers "F.Cu" "F.Mask" "F.Paste")
			(net "P2E_CPU_SAS_RX_DN4")
		)
		(pad "A51" smd rect
			(at -40.500046 -2.0955)
			(size 0.7112 4.191)
			(layers "F.Cu" "F.Mask" "F.Paste")
			(net "GND")
		)
		(pad "A52" smd rect
			(at -41.500044 -2.0955)
			(size 0.7112 4.191)
			(layers "F.Cu" "F.Mask" "F.Paste")
			(net "GND")
		)
		(pad "A53" smd rect
			(at -42.500042 -2.0955)
			(size 0.7112 4.191)
			(layers "F.Cu" "F.Mask" "F.Paste")
			(net "P2E_CPU_SAS_RX_DP5")
		)
		(pad "A54" smd rect
			(at -43.50004 -2.0955)
			(size 0.7112 4.191)
			(layers "F.Cu" "F.Mask" "F.Paste")
			(net "P2E_CPU_SAS_RX_DN5")
		)
		(pad "A55" smd rect
			(at -44.500038 -2.0955)
			(size 0.7112 4.191)
			(layers "F.Cu" "F.Mask" "F.Paste")
			(net "GND")
		)
		(pad "A56" smd rect
			(at -45.500036 -2.0955)
			(size 0.7112 4.191)
			(layers "F.Cu" "F.Mask" "F.Paste")
			(net "GND")
		)
		(pad "A57" smd rect
			(at -46.500034 -2.0955)
			(size 0.7112 4.191)
			(layers "F.Cu" "F.Mask" "F.Paste")
			(net "P2E_CPU_SAS_RX_DP6")
		)
		(pad "A58" smd rect
			(at -47.500032 -2.0955)
			(size 0.7112 4.191)
			(layers "F.Cu" "F.Mask" "F.Paste")
			(net "P2E_CPU_SAS_RX_DN6")
		)
		(pad "A59" smd rect
			(at -48.50003 -2.0955)
			(size 0.7112 4.191)
			(layers "F.Cu" "F.Mask" "F.Paste")
			(net "GND")
		)
		(pad "A60" smd rect
			(at -49.500028 -2.0955)
			(size 0.7112 4.191)
			(layers "F.Cu" "F.Mask" "F.Paste")
			(net "GND")
		)
		(pad "A61" smd rect
			(at -50.500026 -2.0955)
			(size 0.7112 4.191)
			(layers "F.Cu" "F.Mask" "F.Paste")
			(net "P2E_CPU_SAS_RX_DP7")
		)
		(pad "A62" smd rect
			(at -51.500024 -2.0955)
			(size 0.7112 4.191)
			(layers "F.Cu" "F.Mask" "F.Paste")
			(net "P2E_CPU_SAS_RX_DN7")
		)
		(pad "A63" smd rect
			(at -52.500022 -2.0955)
			(size 0.7112 4.191)
			(layers "F.Cu" "F.Mask" "F.Paste")
			(net "GND")
		)
		(pad "A64" smd rect
			(at -53.50002 -2.0955)
			(size 0.7112 4.191)
			(layers "F.Cu" "F.Mask" "F.Paste")
			(net "GND")
		)
		(pad "A65" smd rect
			(at -54.500018 -2.0955)
			(size 0.7112 4.191)
			(layers "F.Cu" "F.Mask" "F.Paste")
			(net "P2E_CPU_ETH10G_RX_DP8")
		)
		(pad "A66" smd rect
			(at -55.500016 -2.0955)
			(size 0.7112 4.191)
			(layers "F.Cu" "F.Mask" "F.Paste")
			(net "P2E_CPU_ETH10G_RX_DN8")
		)
		(pad "A67" smd rect
			(at -56.500014 -2.0955)
			(size 0.7112 4.191)
			(layers "F.Cu" "F.Mask" "F.Paste")
			(net "GND")
		)
		(pad "A68" smd rect
			(at -57.500012 -2.0955)
			(size 0.7112 4.191)
			(layers "F.Cu" "F.Mask" "F.Paste")
			(net "GND")
		)
		(pad "A69" smd rect
			(at -58.50001 -2.0955)
			(size 0.7112 4.191)
			(layers "F.Cu" "F.Mask" "F.Paste")
			(net "P2E_CPU_ETH10G_RX_DP9")
		)
		(pad "A70" smd rect
			(at -59.500008 -2.0955)
			(size 0.7112 4.191)
			(layers "F.Cu" "F.Mask" "F.Paste")
			(net "P2E_CPU_ETH10G_RX_DN9")
		)
		(pad "A71" smd rect
			(at -60.500006 -2.0955)
			(size 0.7112 4.191)
			(layers "F.Cu" "F.Mask" "F.Paste")
			(net "GND")
		)
		(pad "A72" smd rect
			(at -61.500004 -2.0955)
			(size 0.7112 4.191)
			(layers "F.Cu" "F.Mask" "F.Paste")
			(net "GND")
		)
		(pad "A73" smd rect
			(at -62.500002 -2.0955)
			(size 0.7112 4.191)
			(layers "F.Cu" "F.Mask" "F.Paste")
			(net "P2E_CPU_ETH10G_RX_DP10")
		)
		(pad "A74" smd rect
			(at -63.5 -2.0955)
			(size 0.7112 4.191)
			(layers "F.Cu" "F.Mask" "F.Paste")
			(net "P2E_CPU_ETH10G_RX_DN10")
		)
		(pad "A75" smd rect
			(at -64.499998 -2.0955)
			(size 0.7112 4.191)
			(layers "F.Cu" "F.Mask" "F.Paste")
			(net "GND")
		)
		(pad "A76" smd rect
			(at -65.499996 -2.0955)
			(size 0.7112 4.191)
			(layers "F.Cu" "F.Mask" "F.Paste")
			(net "GND")
		)
		(pad "A77" smd rect
			(at -66.499994 -2.0955)
			(size 0.7112 4.191)
			(layers "F.Cu" "F.Mask" "F.Paste")
			(net "P2E_CPU_ETH10G_RX_DP11")
		)
		(pad "A78" smd rect
			(at -67.499992 -2.0955)
			(size 0.7112 4.191)
			(layers "F.Cu" "F.Mask" "F.Paste")
			(net "P2E_CPU_ETH10G_RX_DN11")
		)
		(pad "A79" smd rect
			(at -68.49999 -2.0955)
			(size 0.7112 4.191)
			(layers "F.Cu" "F.Mask" "F.Paste")
			(net "GND")
		)
		(pad "A80" smd rect
			(at -69.499988 -2.0955)
			(size 0.7112 4.191)
			(layers "F.Cu" "F.Mask" "F.Paste")
			(net "GND")
		)
		(pad "A81" smd rect
			(at -70.499986 -2.0955)
			(size 0.7112 4.191)
			(layers "F.Cu" "F.Mask" "F.Paste")
			(net "P12V")
		)
		(pad "A82" smd rect
			(at -71.499984 -2.0955)
			(size 0.7112 4.191)
			(layers "F.Cu" "F.Mask" "F.Paste")
			(net "P12V")
		)
		(pad "B1" smd rect
			(at 11.500104 -1.7145)
			(size 0.7112 4.191)
			(drill
				(offset 0 -0.381)
			)
			(layers "F.Cu" "F.Mask" "F.Paste")
			(net "P12V")
		)
		(pad "B2" smd rect
			(at 10.500106 -1.7145)
			(size 0.7112 4.191)
			(drill
				(offset 0 -0.381)
			)
			(layers "F.Cu" "F.Mask" "F.Paste")
			(net "P12V")
		)
		(pad "B3" smd rect
			(at 9.500108 -1.7145)
			(size 0.7112 4.191)
			(drill
				(offset 0 -0.381)
			)
			(layers "F.Cu" "F.Mask" "F.Paste")
			(net "P12V")
		)
		(pad "B4" smd rect
			(at 8.50011 -1.7145)
			(size 0.7112 4.191)
			(drill
				(offset 0 -0.381)
			)
			(layers "F.Cu" "F.Mask" "F.Paste")
			(net "GND")
		)
		(pad "B5" smd rect
			(at 7.500112 -1.7145)
			(size 0.7112 4.191)
			(drill
				(offset 0 -0.381)
			)
			(layers "F.Cu" "F.Mask" "F.Paste")
			(net "PCIE_GF_I2C_CLK")
		)
		(pad "B6" smd rect
			(at 6.500114 -1.7145)
			(size 0.7112 4.191)
			(drill
				(offset 0 -0.381)
			)
			(layers "F.Cu" "F.Mask" "F.Paste")
			(net "PCIE_GF_I2C_DATA")
		)
		(pad "B7" smd rect
			(at 5.500116 -1.7145)
			(size 0.7112 4.191)
			(drill
				(offset 0 -0.381)
			)
			(layers "F.Cu" "F.Mask" "F.Paste")
			(net "GND")
		)
		(pad "B8" smd rect
			(at 4.500118 -1.7145)
			(size 0.7112 4.191)
			(drill
				(offset 0 -0.381)
			)
			(layers "F.Cu" "F.Mask" "F.Paste")
			(net "PWR_BTN#")
		)
		(pad "B9" smd rect
			(at 3.50012 -1.7145)
			(size 0.7112 4.191)
			(drill
				(offset 0 -0.381)
			)
			(layers "F.Cu" "F.Mask" "F.Paste")
			(net "USB_P1_DP")
		)
		(pad "B10" smd rect
			(at 2.500122 -1.7145)
			(size 0.7112 4.191)
			(drill
				(offset 0 -0.381)
			)
			(layers "F.Cu" "F.Mask" "F.Paste")
			(net "USB_P1_DN")
		)
		(pad "B11" smd rect
			(at 1.500124 -1.7145)
			(size 0.7112 4.191)
			(drill
				(offset 0 -0.381)
			)
			(layers "F.Cu" "F.Mask" "F.Paste")
			(net "BMC_SYS_RESET#")
		)
		(pad "B12" smd rect
			(at -1.500124 -1.7145)
			(size 0.7112 4.191)
			(drill
				(offset 0 -0.381)
			)
			(layers "F.Cu" "F.Mask" "F.Paste")
			(net "PCIE_GF_I2C_R_ALERT#")
		)
		(pad "B13" smd rect
			(at -2.500122 -1.7145)
			(size 0.7112 4.191)
			(drill
				(offset 0 -0.381)
			)
			(layers "F.Cu" "F.Mask" "F.Paste")
			(net "GND")
		)
		(pad "B14" smd rect
			(at -3.50012 -1.7145)
			(size 0.7112 4.191)
			(drill
				(offset 0 -0.381)
			)
			(layers "F.Cu" "F.Mask" "F.Paste")
			(net "GND")
		)
		(pad "B15" smd rect
			(at -4.500118 -1.7145)
			(size 0.7112 4.191)
			(drill
				(offset 0 -0.381)
			)
			(layers "F.Cu" "F.Mask" "F.Paste")
			(net "P2E_CPU_SAS_TX_DP0")
		)
		(pad "B16" smd rect
			(at -5.500116 -1.7145)
			(size 0.7112 4.191)
			(drill
				(offset 0 -0.381)
			)
			(layers "F.Cu" "F.Mask" "F.Paste")
			(net "P2E_CPU_SAS_TX_DN0")
		)
		(pad "B17" smd rect
			(at -6.500114 -1.7145)
			(size 0.7112 4.191)
			(drill
				(offset 0 -0.381)
			)
			(layers "F.Cu" "F.Mask" "F.Paste")
			(net "GND")
		)
		(pad "B18" smd rect
			(at -7.500112 -1.7145)
			(size 0.7112 4.191)
			(drill
				(offset 0 -0.381)
			)
			(layers "F.Cu" "F.Mask" "F.Paste")
			(net "GND")
		)
		(pad "B19" smd rect
			(at -8.50011 -1.7145)
			(size 0.7112 4.191)
			(drill
				(offset 0 -0.381)
			)
			(layers "F.Cu" "F.Mask" "F.Paste")
			(net "P2E_CPU_SAS_TX_DP1")
		)
		(pad "B20" smd rect
			(at -9.500108 -1.7145)
			(size 0.7112 4.191)
			(drill
				(offset 0 -0.381)
			)
			(layers "F.Cu" "F.Mask" "F.Paste")
			(net "P2E_CPU_SAS_TX_DN1")
		)
		(pad "B21" smd rect
			(at -10.500106 -1.7145)
			(size 0.7112 4.191)
			(drill
				(offset 0 -0.381)
			)
			(layers "F.Cu" "F.Mask" "F.Paste")
			(net "GND")
		)
		(pad "B22" smd rect
			(at -11.500104 -1.7145)
			(size 0.7112 4.191)
			(drill
				(offset 0 -0.381)
			)
			(layers "F.Cu" "F.Mask" "F.Paste")
			(net "GND")
		)
		(pad "B23" smd rect
			(at -12.500102 -1.7145)
			(size 0.7112 4.191)
			(drill
				(offset 0 -0.381)
			)
			(layers "F.Cu" "F.Mask" "F.Paste")
			(net "P2E_CPU_SAS_TX_DP2")
		)
		(pad "B24" smd rect
			(at -13.5001 -1.7145)
			(size 0.7112 4.191)
			(drill
				(offset 0 -0.381)
			)
			(layers "F.Cu" "F.Mask" "F.Paste")
			(net "P2E_CPU_SAS_TX_DN2")
		)
		(pad "B25" smd rect
			(at -14.500098 -1.7145)
			(size 0.7112 4.191)
			(drill
				(offset 0 -0.381)
			)
			(layers "F.Cu" "F.Mask" "F.Paste")
			(net "GND")
		)
		(pad "B26" smd rect
			(at -15.500096 -1.7145)
			(size 0.7112 4.191)
			(drill
				(offset 0 -0.381)
			)
			(layers "F.Cu" "F.Mask" "F.Paste")
			(net "GND")
		)
		(pad "B27" smd rect
			(at -16.500094 -1.7145)
			(size 0.7112 4.191)
			(drill
				(offset 0 -0.381)
			)
			(layers "F.Cu" "F.Mask" "F.Paste")
			(net "P2E_CPU_SAS_TX_DP3")
		)
		(pad "B28" smd rect
			(at -17.500092 -1.7145)
			(size 0.7112 4.191)
			(drill
				(offset 0 -0.381)
			)
			(layers "F.Cu" "F.Mask" "F.Paste")
			(net "P2E_CPU_SAS_TX_DN3")
		)
		(pad "B29" smd rect
			(at -18.50009 -1.7145)
			(size 0.7112 4.191)
			(drill
				(offset 0 -0.381)
			)
			(layers "F.Cu" "F.Mask" "F.Paste")
			(net "GND")
		)
		(pad "B30" smd rect
			(at -19.500088 -1.7145)
			(size 0.7112 4.191)
			(drill
				(offset 0 -0.381)
			)
			(layers "F.Cu" "F.Mask" "F.Paste")
			(net "GND")
		)
		(pad "B31" smd rect
			(at -20.500086 -1.7145)
			(size 0.7112 4.191)
			(drill
				(offset 0 -0.381)
			)
			(layers "F.Cu" "F.Mask" "F.Paste")
			(net "SATA2_TX_C_DP0")
		)
		(pad "B32" smd rect
			(at -21.500084 -1.7145)
			(size 0.7112 4.191)
			(drill
				(offset 0 -0.381)
			)
			(layers "F.Cu" "F.Mask" "F.Paste")
			(net "SATA2_TX_C_DN0")
		)
		(pad "B33" smd rect
			(at -22.500082 -1.7145)
			(size 0.7112 4.191)
			(drill
				(offset 0 -0.381)
			)
			(layers "F.Cu" "F.Mask" "F.Paste")
			(net "GND")
		)
		(pad "B34" smd rect
			(at -23.50008 -1.7145)
			(size 0.7112 4.191)
			(drill
				(offset 0 -0.381)
			)
			(layers "F.Cu" "F.Mask" "F.Paste")
			(net "GND")
		)
		(pad "B35" smd rect
			(at -24.500078 -1.7145)
			(size 0.7112 4.191)
			(drill
				(offset 0 -0.381)
			)
			(layers "F.Cu" "F.Mask" "F.Paste")
			(net "CLK_100M_CLKBUFF_ENET_DP")
		)
		(pad "B36" smd rect
			(at -25.500076 -1.7145)
			(size 0.7112 4.191)
			(drill
				(offset 0 -0.381)
			)
			(layers "F.Cu" "F.Mask" "F.Paste")
			(net "CLK_100M_CLKBUFF_ENET_DN")
		)
		(pad "B37" smd rect
			(at -26.500074 -1.7145)
			(size 0.7112 4.191)
			(drill
				(offset 0 -0.381)
			)
			(layers "F.Cu" "F.Mask" "F.Paste")
			(net "GND")
		)
		(pad "B38" smd rect
			(at -27.500072 -1.7145)
			(size 0.7112 4.191)
			(drill
				(offset 0 -0.381)
			)
			(layers "F.Cu" "F.Mask" "F.Paste")
			(net "GND")
		)
		(pad "B39" smd rect
			(at -28.50007 -1.7145)
			(size 0.7112 4.191)
			(drill
				(offset 0 -0.381)
			)
			(layers "F.Cu" "F.Mask" "F.Paste")
			(net "PCIE1_RESET#")
		)
		(pad "B40" smd rect
			(at -29.500068 -1.7145)
			(size 0.7112 4.191)
			(drill
				(offset 0 -0.381)
			)
			(layers "F.Cu" "F.Mask" "F.Paste")
			(net "PCIE2_RESET#")
		)
		(pad "B41" smd rect
			(at -30.500066 -1.7145)
			(size 0.7112 4.191)
			(drill
				(offset 0 -0.381)
			)
			(layers "F.Cu" "F.Mask" "F.Paste")
			(net "GND")
		)
		(pad "B42" smd rect
			(at -31.500064 -1.7145)
			(size 0.7112 4.191)
			(drill
				(offset 0 -0.381)
			)
			(layers "F.Cu" "F.Mask" "F.Paste")
			(net "GND")
		)
		(pad "B43" smd rect
			(at -32.500062 -1.7145)
			(size 0.7112 4.191)
			(drill
				(offset 0 -0.381)
			)
			(layers "F.Cu" "F.Mask" "F.Paste")
			(net "GBE_R_SMBCLK")
		)
		(pad "B44" smd rect
			(at -33.50006 -1.7145)
			(size 0.7112 4.191)
			(drill
				(offset 0 -0.381)
			)
			(layers "F.Cu" "F.Mask" "F.Paste")
			(net "GBE_R_SMDATA")
		)
		(pad "B45" smd rect
			(at -34.500058 -1.7145)
			(size 0.7112 4.191)
			(drill
				(offset 0 -0.381)
			)
			(layers "F.Cu" "F.Mask" "F.Paste")
			(net "GND")
		)
		(pad "B46" smd rect
			(at -35.500056 -1.7145)
			(size 0.7112 4.191)
			(drill
				(offset 0 -0.381)
			)
			(layers "F.Cu" "F.Mask" "F.Paste")
			(net "GND")
		)
		(pad "B47" smd rect
			(at -36.500054 -1.7145)
			(size 0.7112 4.191)
			(drill
				(offset 0 -0.381)
			)
			(layers "F.Cu" "F.Mask" "F.Paste")
			(net "CPU_GBE_TX_C_DP0")
		)
		(pad "B48" smd rect
			(at -37.500052 -1.7145)
			(size 0.7112 4.191)
			(drill
				(offset 0 -0.381)
			)
			(layers "F.Cu" "F.Mask" "F.Paste")
			(net "CPU_GBE_TX_C_DN0")
		)
		(pad "B49" smd rect
			(at -38.50005 -1.7145)
			(size 0.7112 4.191)
			(drill
				(offset 0 -0.381)
			)
			(layers "F.Cu" "F.Mask" "F.Paste")
			(net "GND")
		)
		(pad "B50" smd rect
			(at -39.500048 -1.7145)
			(size 0.7112 4.191)
			(drill
				(offset 0 -0.381)
			)
			(layers "F.Cu" "F.Mask" "F.Paste")
			(net "GND")
		)
		(pad "B51" smd rect
			(at -40.500046 -1.7145)
			(size 0.7112 4.191)
			(drill
				(offset 0 -0.381)
			)
			(layers "F.Cu" "F.Mask" "F.Paste")
			(net "P2E_CPU_SAS_TX_DP4")
		)
		(pad "B52" smd rect
			(at -41.500044 -1.7145)
			(size 0.7112 4.191)
			(drill
				(offset 0 -0.381)
			)
			(layers "F.Cu" "F.Mask" "F.Paste")
			(net "P2E_CPU_SAS_TX_DN4")
		)
		(pad "B53" smd rect
			(at -42.500042 -1.7145)
			(size 0.7112 4.191)
			(drill
				(offset 0 -0.381)
			)
			(layers "F.Cu" "F.Mask" "F.Paste")
			(net "GND")
		)
		(pad "B54" smd rect
			(at -43.50004 -1.7145)
			(size 0.7112 4.191)
			(drill
				(offset 0 -0.381)
			)
			(layers "F.Cu" "F.Mask" "F.Paste")
			(net "GND")
		)
		(pad "B55" smd rect
			(at -44.500038 -1.7145)
			(size 0.7112 4.191)
			(drill
				(offset 0 -0.381)
			)
			(layers "F.Cu" "F.Mask" "F.Paste")
			(net "P2E_CPU_SAS_TX_DP5")
		)
		(pad "B56" smd rect
			(at -45.500036 -1.7145)
			(size 0.7112 4.191)
			(drill
				(offset 0 -0.381)
			)
			(layers "F.Cu" "F.Mask" "F.Paste")
			(net "P2E_CPU_SAS_TX_DN5")
		)
		(pad "B57" smd rect
			(at -46.500034 -1.7145)
			(size 0.7112 4.191)
			(drill
				(offset 0 -0.381)
			)
			(layers "F.Cu" "F.Mask" "F.Paste")
			(net "GND")
		)
		(pad "B58" smd rect
			(at -47.500032 -1.7145)
			(size 0.7112 4.191)
			(drill
				(offset 0 -0.381)
			)
			(layers "F.Cu" "F.Mask" "F.Paste")
			(net "GND")
		)
		(pad "B59" smd rect
			(at -48.50003 -1.7145)
			(size 0.7112 4.191)
			(drill
				(offset 0 -0.381)
			)
			(layers "F.Cu" "F.Mask" "F.Paste")
			(net "P2E_CPU_SAS_TX_DP6")
		)
		(pad "B60" smd rect
			(at -49.500028 -1.7145)
			(size 0.7112 4.191)
			(drill
				(offset 0 -0.381)
			)
			(layers "F.Cu" "F.Mask" "F.Paste")
			(net "P2E_CPU_SAS_TX_DN6")
		)
		(pad "B61" smd rect
			(at -50.500026 -1.7145)
			(size 0.7112 4.191)
			(drill
				(offset 0 -0.381)
			)
			(layers "F.Cu" "F.Mask" "F.Paste")
			(net "GND")
		)
		(pad "B62" smd rect
			(at -51.500024 -1.7145)
			(size 0.7112 4.191)
			(drill
				(offset 0 -0.381)
			)
			(layers "F.Cu" "F.Mask" "F.Paste")
			(net "GND")
		)
		(pad "B63" smd rect
			(at -52.500022 -1.7145)
			(size 0.7112 4.191)
			(drill
				(offset 0 -0.381)
			)
			(layers "F.Cu" "F.Mask" "F.Paste")
			(net "P2E_CPU_SAS_TX_DP7")
		)
		(pad "B64" smd rect
			(at -53.50002 -1.7145)
			(size 0.7112 4.191)
			(drill
				(offset 0 -0.381)
			)
			(layers "F.Cu" "F.Mask" "F.Paste")
			(net "P2E_CPU_SAS_TX_DN7")
		)
		(pad "B65" smd rect
			(at -54.500018 -1.7145)
			(size 0.7112 4.191)
			(drill
				(offset 0 -0.381)
			)
			(layers "F.Cu" "F.Mask" "F.Paste")
			(net "GND")
		)
		(pad "B66" smd rect
			(at -55.500016 -1.7145)
			(size 0.7112 4.191)
			(drill
				(offset 0 -0.381)
			)
			(layers "F.Cu" "F.Mask" "F.Paste")
			(net "GND")
		)
		(pad "B67" smd rect
			(at -56.500014 -1.7145)
			(size 0.7112 4.191)
			(drill
				(offset 0 -0.381)
			)
			(layers "F.Cu" "F.Mask" "F.Paste")
			(net "P2E_CPU_ETH10G_TX_DP8")
		)
		(pad "B68" smd rect
			(at -57.500012 -1.7145)
			(size 0.7112 4.191)
			(drill
				(offset 0 -0.381)
			)
			(layers "F.Cu" "F.Mask" "F.Paste")
			(net "P2E_CPU_ETH10G_TX_DN8")
		)
		(pad "B69" smd rect
			(at -58.50001 -1.7145)
			(size 0.7112 4.191)
			(drill
				(offset 0 -0.381)
			)
			(layers "F.Cu" "F.Mask" "F.Paste")
			(net "GND")
		)
		(pad "B70" smd rect
			(at -59.500008 -1.7145)
			(size 0.7112 4.191)
			(drill
				(offset 0 -0.381)
			)
			(layers "F.Cu" "F.Mask" "F.Paste")
			(net "GND")
		)
		(pad "B71" smd rect
			(at -60.500006 -1.7145)
			(size 0.7112 4.191)
			(drill
				(offset 0 -0.381)
			)
			(layers "F.Cu" "F.Mask" "F.Paste")
			(net "P2E_CPU_ETH10G_TX_DP9")
		)
		(pad "B72" smd rect
			(at -61.500004 -1.7145)
			(size 0.7112 4.191)
			(drill
				(offset 0 -0.381)
			)
			(layers "F.Cu" "F.Mask" "F.Paste")
			(net "P2E_CPU_ETH10G_TX_DN9")
		)
		(pad "B73" smd rect
			(at -62.500002 -1.7145)
			(size 0.7112 4.191)
			(drill
				(offset 0 -0.381)
			)
			(layers "F.Cu" "F.Mask" "F.Paste")
			(net "GND")
		)
		(pad "B74" smd rect
			(at -63.5 -1.7145)
			(size 0.7112 4.191)
			(drill
				(offset 0 -0.381)
			)
			(layers "F.Cu" "F.Mask" "F.Paste")
			(net "GND")
		)
		(pad "B75" smd rect
			(at -64.499998 -1.7145)
			(size 0.7112 4.191)
			(drill
				(offset 0 -0.381)
			)
			(layers "F.Cu" "F.Mask" "F.Paste")
			(net "P2E_CPU_ETH10G_TX_DP10")
		)
		(pad "B76" smd rect
			(at -65.499996 -1.7145)
			(size 0.7112 4.191)
			(drill
				(offset 0 -0.381)
			)
			(layers "F.Cu" "F.Mask" "F.Paste")
			(net "P2E_CPU_ETH10G_TX_DN10")
		)
		(pad "B77" smd rect
			(at -66.499994 -1.7145)
			(size 0.7112 4.191)
			(drill
				(offset 0 -0.381)
			)
			(layers "F.Cu" "F.Mask" "F.Paste")
			(net "GND")
		)
		(pad "B78" smd rect
			(at -67.499992 -1.7145)
			(size 0.7112 4.191)
			(drill
				(offset 0 -0.381)
			)
			(layers "F.Cu" "F.Mask" "F.Paste")
			(net "GND")
		)
		(pad "B79" smd rect
			(at -68.49999 -1.7145)
			(size 0.7112 4.191)
			(drill
				(offset 0 -0.381)
			)
			(layers "F.Cu" "F.Mask" "F.Paste")
			(net "P2E_CPU_ETH10G_TX_DP11")
		)
		(pad "B80" smd rect
			(at -69.499988 -1.7145)
			(size 0.7112 4.191)
			(drill
				(offset 0 -0.381)
			)
			(layers "F.Cu" "F.Mask" "F.Paste")
			(net "P2E_CPU_ETH10G_TX_DN11")
		)
		(pad "B81" smd rect
			(at -70.499986 -2.5908)
			(size 0.7112 3.2004)
			(layers "F.Cu" "F.Mask" "F.Paste")
			(net "GND")
		)
		(pad "B82" smd rect
			(at -71.499984 -1.7145)
			(size 0.7112 4.191)
			(drill
				(offset 0 -0.381)
			)
			(layers "F.Cu" "F.Mask" "F.Paste")
			(net "GND")
		)
		(zone
			(layer "F.Cu")
			(hatch none 0.5)
			(connect_pads
				(clearance 0)
			)
			(min_thickness 0.25)
			(keepout
				(tracks allowed)
				(vias not_allowed)
				(pads allowed)
				(copperpour not_allowed)
				(footprints allowed)
			)
			(placement
				(enabled no)
				(sheetname "")
			)
			(fill
				(thermal_gap 0.5)
				(thermal_bridge_width 0.5)
				(island_removal_mode 0)
			)
			(polygon
				(pts
					(xy 13.977366 -3.084068) (xy 99.727766 -3.084068) (xy 99.727766 -9.307068) (xy 13.977366 -9.307068)
				)
			)
		)
		(zone
			(layer "F.Cu")
			(hatch none 0.5)
			(connect_pads
				(clearance 0)
			)
			(min_thickness 0.25)
			(keepout
				(tracks not_allowed)
				(vias allowed)
				(pads allowed)
				(copperpour not_allowed)
				(footprints allowed)
			)
			(placement
				(enabled no)
				(sheetname "")
			)
			(fill
				(thermal_gap 0.5)
				(thermal_bridge_width 0.5)
				(island_removal_mode 0)
			)
			(polygon
				(pts
					(xy 13.977366 -3.084068) (xy 99.727766 -3.084068) (xy 99.727766 -4.100068) (xy 13.977366 -4.100068)
				)
			)
		)
		(zone
			(layer "B.Cu")
			(hatch none 0.5)
			(connect_pads
				(clearance 0)
			)
			(min_thickness 0.25)
			(keepout
				(tracks allowed)
				(vias not_allowed)
				(pads allowed)
				(copperpour not_allowed)
				(footprints allowed)
			)
			(placement
				(enabled no)
				(sheetname "")
			)
			(fill
				(thermal_gap 0.5)
				(thermal_bridge_width 0.5)
				(island_removal_mode 0)
			)
			(polygon
				(pts
					(xy 13.977366 -3.084068) (xy 99.727766 -3.084068) (xy 99.727766 -9.307068) (xy 13.977366 -9.307068)
				)
			)
		)
		(zone
			(layer "B.Cu")
			(hatch none 0.5)
			(connect_pads
				(clearance 0)
			)
			(min_thickness 0.25)
			(keepout
				(tracks not_allowed)
				(vias allowed)
				(pads allowed)
				(copperpour not_allowed)
				(footprints allowed)
			)
			(placement
				(enabled no)
				(sheetname "")
			)
			(fill
				(thermal_gap 0.5)
				(thermal_bridge_width 0.5)
				(island_removal_mode 0)
			)
			(polygon
				(pts
					(xy 13.977366 -3.084068) (xy 99.727766 -3.084068) (xy 99.727766 -4.100068) (xy 13.977366 -4.100068)
				)
			)
		)
	)
	(footprint ""
		(layer "F.Cu")
		(at 19.304 -33.147 180)
		(property "Reference" "PC172"
			(at 0 0 180)
			(layer "F.SilkS")
			(hide yes)
			(effects
				(font
					(size 1.27 1.27)
				)
			)
		)
		(property "Value" "SC1U10V2KX-1GP"
			(at 1.8923 -1.2065 180)
			(unlocked yes)
			(layer "F.Fab")
			(hide yes)
			(effects
				(font
					(size 1.016 1.016)
					(thickness 0.1524)
				)
			)
		)
		(property "Device Type" "C402H22"
			(at 1.8923 -2.7305 180)
			(unlocked yes)
			(layer "F.Fab")
			(hide yes)
			(effects
				(font
					(size 1.016 1.016)
					(thickness 0.1524)
				)
			)
		)
		(duplicate_pad_numbers_are_jumpers no)
		(fp_rect
			(start -0.381 0.7366)
			(end 0.381 -0.7366)
			(stroke
				(width 0)
				(type default)
			)
			(fill no)
			(layer "F.CrtYd")
		)
		(fp_rect
			(start -0.381 0.7366)
			(end 0.381 -0.7366)
			(stroke
				(width 0)
				(type default)
			)
			(fill no)
			(layer "F.Fab")
		)
		(pad "1" smd custom
			(at 0 -0.4572 180)
			(size 0.1143 0.1143)
			(layers "F.Cu" "F.Mask" "F.Paste")
			(net "P3V3_STBY_VFB")
			(options
				(clearance outline)
				(anchor circle)
			)
			(primitives
				(gr_poly
					(pts
						(arc
							(start -0.254 -0.1778)
							(mid -0.239121 -0.213721)
							(end -0.2032 -0.2286)
						)
						(arc
							(start 0.2032 -0.2286)
							(mid 0.239121 -0.213721)
							(end 0.254 -0.1778)
						)
						(arc
							(start 0.254 0.1778)
							(mid 0.239121 0.213721)
							(end 0.2032 0.2286)
						)
						(arc
							(start -0.2032 0.2286)
							(mid -0.239121 0.213721)
							(end -0.254 0.1778)
						)
					)
					(width 0)
					(fill yes)
				)
			)
		)
		(pad "2" smd custom
			(at 0 0.4572 180)
			(size 0.1143 0.1143)
			(layers "F.Cu" "F.Mask" "F.Paste")
			(net "P3V3_STBY_VFB_R")
			(options
				(clearance outline)
				(anchor circle)
			)
			(primitives
				(gr_poly
					(pts
						(arc
							(start -0.254 -0.1778)
							(mid -0.239121 -0.213721)
							(end -0.2032 -0.2286)
						)
						(arc
							(start 0.2032 -0.2286)
							(mid 0.239121 -0.213721)
							(end 0.254 -0.1778)
						)
						(arc
							(start 0.254 0.1778)
							(mid 0.239121 0.213721)
							(end 0.2032 0.2286)
						)
						(arc
							(start -0.2032 0.2286)
							(mid -0.239121 0.213721)
							(end -0.254 0.1778)
						)
					)
					(width 0)
					(fill yes)
				)
			)
		)
	)
	(footprint ""
		(layer "F.Cu")
		(at 54.4322 -15.3416 180)
		(property "Reference" "Q18"
			(at 0 0 180)
			(layer "F.SilkS")
			(hide yes)
			(effects
				(font
					(size 1.27 1.27)
				)
			)
		)
		(property "Value" "2N7002A-7-GP"
			(at -4.3561 -5.7912 180)
			(unlocked yes)
			(layer "F.Fab")
			(hide yes)
			(effects
				(font
					(size 1.016 1.016)
					(thickness 0.1524)
				)
			)
		)
		(property "Device Type" "SOT23DGS2D4H48"
			(at -4.3561 -7.3152 180)
			(unlocked yes)
			(layer "F.Fab")
			(hide yes)
			(effects
				(font
					(size 1.016 1.016)
					(thickness 0.1524)
				)
			)
		)
		(duplicate_pad_numbers_are_jumpers no)
		(fp_line
			(start 1.7145 0.4445)
			(end 1.7145 -0.4445)
			(stroke
				(width 0.1524)
				(type default)
			)
			(layer "F.SilkS")
		)
		(fp_line
			(start 1.7145 -0.4445)
			(end -1.7145 -0.4445)
			(stroke
				(width 0.1524)
				(type default)
			)
			(layer "F.SilkS")
		)
		(fp_line
			(start -1.7145 0.4445)
			(end 1.7145 0.4445)
			(stroke
				(width 0.1524)
				(type default)
			)
			(layer "F.SilkS")
		)
		(fp_line
			(start -1.7145 -0.4445)
			(end -1.7145 0.4445)
			(stroke
				(width 0.1524)
				(type default)
			)
			(layer "F.SilkS")
		)
		(fp_poly
			(pts
				(xy -1.4224 1.5621) (xy -1.4224 0.9017) (xy -1.7145 0.9017) (xy -1.7145 -0.9017) (xy -0.4699 -0.9017)
				(xy -0.4699 -1.5621) (xy 0.4699 -1.5621) (xy 0.4699 -0.9017) (xy 1.7145 -0.9017) (xy 1.7145 0.9017)
				(xy 1.4224 0.9017) (xy 1.4224 1.5621) (xy 0.4826 1.5621) (xy 0.4826 0.9017) (xy -0.4826 0.9017)
				(xy -0.4826 1.5621)
			)
			(stroke
				(width 0)
				(type default)
			)
			(fill no)
			(layer "F.CrtYd")
		)
		(fp_poly
			(pts
				(xy -1.4224 1.5621) (xy -1.4224 0.9017) (xy -1.7145 0.9017) (xy -1.7145 -0.9017) (xy -0.4699 -0.9017)
				(xy -0.4699 -1.5621) (xy 0.4699 -1.5621) (xy 0.4699 -0.9017) (xy 1.7145 -0.9017) (xy 1.7145 0.9017)
				(xy 1.4224 0.9017) (xy 1.4224 1.5621) (xy 0.4826 1.5621) (xy 0.4826 0.9017) (xy -0.4826 0.9017)
				(xy -0.4826 1.5621)
			)
			(stroke
				(width 0)
				(type default)
			)
			(fill no)
			(layer "F.Fab")
		)
		(pad "D" smd custom
			(at 0 -1.069086 180)
			(size 0.17145 0.17145)
			(layers "F.Cu" "F.Mask" "F.Paste")
			(net "GF_GBE_SMBALRT#")
			(options
				(clearance outline)
				(anchor circle)
			)
			(primitives
				(gr_poly
					(pts
						(arc
							(start -0.1397 0.3683)
							(mid -0.283384 0.308784)
							(end -0.3429 0.1651)
						)
						(arc
							(start -0.3429 -0.1651)
							(mid -0.283384 -0.308784)
							(end -0.1397 -0.3683)
						)
						(arc
							(start 0.1397 -0.3683)
							(mid 0.283384 -0.308784)
							(end 0.3429 -0.1651)
						)
						(arc
							(start 0.3429 0.1651)
							(mid 0.283384 0.308784)
							(end 0.1397 0.3683)
						)
					)
					(width 0)
					(fill yes)
				)
			)
		)
		(pad "G" smd custom
			(at -0.94996 1.069086 180)
			(size 0.17145 0.17145)
			(layers "F.Cu" "F.Mask" "F.Paste")
			(net "GF_GBE_SMB_SW_EN")
			(options
				(clearance outline)
				(anchor circle)
			)
			(primitives
				(gr_poly
					(pts
						(arc
							(start -0.1397 0.3683)
							(mid -0.283384 0.308784)
							(end -0.3429 0.1651)
						)
						(arc
							(start -0.3429 -0.1651)
							(mid -0.283384 -0.308784)
							(end -0.1397 -0.3683)
						)
						(arc
							(start 0.1397 -0.3683)
							(mid 0.283384 -0.308784)
							(end 0.3429 -0.1651)
						)
						(arc
							(start 0.3429 0.1651)
							(mid 0.283384 0.308784)
							(end 0.1397 0.3683)
						)
					)
					(width 0)
					(fill yes)
				)
			)
		)
		(pad "S" smd custom
			(at 0.94996 1.069086 180)
			(size 0.17145 0.17145)
			(layers "F.Cu" "F.Mask" "F.Paste")
			(net "GBE_SMBALRT#")
			(options
				(clearance outline)
				(anchor circle)
			)
			(primitives
				(gr_poly
					(pts
						(arc
							(start -0.1397 0.3683)
							(mid -0.283384 0.308784)
							(end -0.3429 0.1651)
						)
						(arc
							(start -0.3429 -0.1651)
							(mid -0.283384 -0.308784)
							(end -0.1397 -0.3683)
						)
						(arc
							(start 0.1397 -0.3683)
							(mid 0.283384 -0.308784)
							(end 0.3429 -0.1651)
						)
						(arc
							(start 0.3429 0.1651)
							(mid 0.283384 0.308784)
							(end 0.1397 0.3683)
						)
					)
					(width 0)
					(fill yes)
				)
			)
		)
	)
	(footprint ""
		(layer "F.Cu")
		(at 167.894 -35.433 90)
		(property "Reference" "PR107"
			(at 0 0 90)
			(layer "F.SilkS")
			(hide yes)
			(effects
				(font
					(size 1.27 1.27)
				)
			)
		)
		(property "Value" "0R3J-6-GP"
			(at -0.0254 -2.5146 90)
			(unlocked yes)
			(layer "F.Fab")
			(hide yes)
			(effects
				(font
					(size 1.016 1.016)
					(thickness 0.1524)
				)
			)
		)
		(property "Device Type" "R603H22"
			(at -0.0254 -4.0386 90)
			(unlocked yes)
			(layer "F.Fab")
			(hide yes)
			(effects
				(font
					(size 1.016 1.016)
					(thickness 0.1524)
				)
			)
		)
		(duplicate_pad_numbers_are_jumpers no)
		(fp_line
			(start 0.4318 0)
			(end 0.2032 0)
			(stroke
				(width 0.2032)
				(type default)
			)
			(layer "F.SilkS")
		)
		(fp_line
			(start -0.2032 0)
			(end -0.4191 0)
			(stroke
				(width 0.2032)
				(type default)
			)
			(layer "F.SilkS")
		)
		(fp_rect
			(start -0.635 1.1811)
			(end 0.635 -1.1811)
			(stroke
				(width 0)
				(type default)
			)
			(fill no)
			(layer "F.CrtYd")
		)
		(fp_rect
			(start -0.635 1.1811)
			(end 0.635 -1.1811)
			(stroke
				(width 0)
				(type default)
			)
			(fill no)
			(layer "F.Fab")
		)
		(pad "1" smd custom
			(at 0 -0.6604 90)
			(size 0.19685 0.19685)
			(layers "F.Cu" "F.Mask" "F.Paste")
			(net "P1V2_FPGA_A")
			(options
				(clearance outline)
				(anchor circle)
			)
			(primitives
				(gr_poly
					(pts
						(arc
							(start 0.508 -0.2921)
							(mid 0.478242 -0.363942)
							(end 0.4064 -0.3937)
						)
						(arc
							(start -0.4064 -0.3937)
							(mid -0.478242 -0.363942)
							(end -0.508 -0.2921)
						)
						(arc
							(start -0.508 0.2921)
							(mid -0.478242 0.363942)
							(end -0.4064 0.3937)
						)
						(arc
							(start 0.4064 0.3937)
							(mid 0.478242 0.363942)
							(end 0.508 0.2921)
						)
					)
					(width 0)
					(fill yes)
				)
			)
		)
		(pad "2" smd custom
			(at 0 0.6604 90)
			(size 0.19685 0.19685)
			(layers "F.Cu" "F.Mask" "F.Paste")
			(net "P1V2_STBY_LDO_OUT1")
			(options
				(clearance outline)
				(anchor circle)
			)
			(primitives
				(gr_poly
					(pts
						(arc
							(start 0.508 -0.2921)
							(mid 0.478242 -0.363942)
							(end 0.4064 -0.3937)
						)
						(arc
							(start -0.4064 -0.3937)
							(mid -0.478242 -0.363942)
							(end -0.508 -0.2921)
						)
						(arc
							(start -0.508 0.2921)
							(mid -0.478242 0.363942)
							(end -0.4064 0.3937)
						)
						(arc
							(start 0.4064 0.3937)
							(mid 0.478242 0.363942)
							(end 0.508 0.2921)
						)
					)
					(width 0)
					(fill yes)
				)
			)
		)
	)
	(footprint ""
		(layer "F.Cu")
		(at 188.595 -16.129 180)
		(property "Reference" "PR170"
			(at 0 0 180)
			(layer "F.SilkS")
			(hide yes)
			(effects
				(font
					(size 1.27 1.27)
				)
			)
		)
		(property "Value" "0R3J-0-U-GP"
			(at -0.0254 -2.5146 180)
			(unlocked yes)
			(layer "F.Fab")
			(hide yes)
			(effects
				(font
					(size 1.016 1.016)
					(thickness 0.1524)
				)
			)
		)
		(property "Device Type" "R603H22"
			(at -0.0254 -4.0386 180)
			(unlocked yes)
			(layer "F.Fab")
			(hide yes)
			(effects
				(font
					(size 1.016 1.016)
					(thickness 0.1524)
				)
			)
		)
		(duplicate_pad_numbers_are_jumpers no)
		(fp_line
			(start 0.4318 0)
			(end 0.2032 0)
			(stroke
				(width 0.2032)
				(type default)
			)
			(layer "F.SilkS")
		)
		(fp_line
			(start -0.2032 0)
			(end -0.4191 0)
			(stroke
				(width 0.2032)
				(type default)
			)
			(layer "F.SilkS")
		)
		(fp_rect
			(start -0.635 1.1811)
			(end 0.635 -1.1811)
			(stroke
				(width 0)
				(type default)
			)
			(fill no)
			(layer "F.CrtYd")
		)
		(fp_rect
			(start -0.635 1.1811)
			(end 0.635 -1.1811)
			(stroke
				(width 0)
				(type default)
			)
			(fill no)
			(layer "F.Fab")
		)
		(pad "1" smd custom
			(at 0 -0.6604 180)
			(size 0.19685 0.19685)
			(layers "F.Cu" "F.Mask" "F.Paste")
			(net "PV_VTT_DDR_B")
			(options
				(clearance outline)
				(anchor circle)
			)
			(primitives
				(gr_poly
					(pts
						(arc
							(start 0.508 -0.2921)
							(mid 0.478242 -0.363942)
							(end 0.4064 -0.3937)
						)
						(arc
							(start -0.4064 -0.3937)
							(mid -0.478242 -0.363942)
							(end -0.508 -0.2921)
						)
						(arc
							(start -0.508 0.2921)
							(mid -0.478242 0.363942)
							(end -0.4064 0.3937)
						)
						(arc
							(start 0.4064 0.3937)
							(mid 0.478242 0.363942)
							(end 0.508 0.2921)
						)
					)
					(width 0)
					(fill yes)
				)
			)
		)
		(pad "2" smd custom
			(at 0 0.6604 180)
			(size 0.19685 0.19685)
			(layers "F.Cu" "F.Mask" "F.Paste")
			(net "PV_VTT_DDR_B_SNS")
			(options
				(clearance outline)
				(anchor circle)
			)
			(primitives
				(gr_poly
					(pts
						(arc
							(start 0.508 -0.2921)
							(mid 0.478242 -0.363942)
							(end 0.4064 -0.3937)
						)
						(arc
							(start -0.4064 -0.3937)
							(mid -0.478242 -0.363942)
							(end -0.508 -0.2921)
						)
						(arc
							(start -0.508 0.2921)
							(mid -0.478242 0.363942)
							(end -0.4064 0.3937)
						)
						(arc
							(start 0.4064 0.3937)
							(mid 0.478242 0.363942)
							(end 0.508 0.2921)
						)
					)
					(width 0)
					(fill yes)
				)
			)
		)
	)
	(footprint ""
		(layer "F.Cu")
		(at 61.214 -56.769)
		(property "Reference" "PC60"
			(at 0 0 0)
			(layer "F.SilkS")
			(hide yes)
			(effects
				(font
					(size 1.27 1.27)
				)
			)
		)
		(property "Value" "SC47U6D3V5MX-1-GP"
			(at -0.0762 -6.1214 0)
			(unlocked yes)
			(layer "F.Fab")
			(hide yes)
			(effects
				(font
					(size 1.016 1.016)
					(thickness 0.1524)
				)
			)
		)
		(property "Device Type" "C805H54"
			(at -0.0762 -8.1534 0)
			(unlocked yes)
			(layer "F.Fab")
			(hide yes)
			(effects
				(font
					(size 1.016 1.016)
					(thickness 0.1524)
				)
			)
		)
		(duplicate_pad_numbers_are_jumpers no)
		(fp_line
			(start 0.6096 0)
			(end -0.6096 0)
			(stroke
				(width 0.3048)
				(type default)
			)
			(layer "F.SilkS")
		)
		(fp_poly
			(pts
				(xy -0.9017 1.4351) (xy 0.9017 1.4351) (xy 0.9017 -1.4351) (xy -0.9017 -1.4351)
			)
			(stroke
				(width 0)
				(type default)
			)
			(fill no)
			(layer "F.CrtYd")
		)
		(fp_poly
			(pts
				(xy 0.9017 1.4351) (xy 0.9017 -1.4351) (xy -0.9017 -1.4351) (xy -0.9017 1.4351)
			)
			(stroke
				(width 0)
				(type default)
			)
			(fill no)
			(layer "F.Fab")
		)
		(pad "1" smd rect
			(at 0 -0.8382)
			(size 1.5494 0.9398)
			(layers "F.Cu" "F.Mask" "F.Paste")
			(net "PVCCP")
		)
		(pad "2" smd rect
			(at 0 0.8382)
			(size 1.5494 0.9398)
			(layers "F.Cu" "F.Mask" "F.Paste")
			(net "GND")
		)
	)
	(footprint ""
		(layer "F.Cu")
		(at 44.45 -42.545 90)
		(property "Reference" "U10"
			(at 0 0 90)
			(layer "F.SilkS")
			(hide yes)
			(effects
				(font
					(size 1.27 1.27)
				)
			)
		)
		(property "Value" "SN74LVC1G14DCKR-GP"
			(at 0 -8.0772 90)
			(unlocked yes)
			(layer "F.Fab")
			(hide yes)
			(effects
				(font
					(size 1.016 1.016)
					(thickness 0.1524)
				)
			)
		)
		(property "Device Type" "SC70-5H44"
			(at 0 -9.6012 90)
			(unlocked yes)
			(layer "F.Fab")
			(hide yes)
			(effects
				(font
					(size 1.016 1.016)
					(thickness 0.1524)
				)
			)
		)
		(duplicate_pad_numbers_are_jumpers no)
		(fp_line
			(start 1.0033 -0.3302)
			(end 1.0033 0.3302)
			(stroke
				(width 0.1524)
				(type default)
			)
			(layer "F.SilkS")
		)
		(fp_line
			(start -1.0033 -0.3302)
			(end 1.0033 -0.3302)
			(stroke
				(width 0.1524)
				(type default)
			)
			(layer "F.SilkS")
		)
		(fp_line
			(start 1.0033 0.3302)
			(end -1.0033 0.3302)
			(stroke
				(width 0.1524)
				(type default)
			)
			(layer "F.SilkS")
		)
		(fp_line
			(start -1.0033 0.3302)
			(end -1.0033 -0.3302)
			(stroke
				(width 0.1524)
				(type default)
			)
			(layer "F.SilkS")
		)
		(fp_poly
			(pts
				(xy -1.0033 1.4859) (xy -1.0033 0.8001) (xy -1.1811 0.8001) (xy -1.1811 -0.8001) (xy -1.0033 -0.8001)
				(xy -1.0033 -1.4859) (xy 1.0033 -1.4859) (xy 1.0033 -0.8001) (xy 1.1811 -0.8001) (xy 1.1811 0.8001)
				(xy 1.0033 0.8001) (xy 1.0033 1.4859) (xy 0.2921 1.4859) (xy 0.2921 0.8001) (xy -0.2921 0.8001)
				(xy -0.2921 1.4859)
			)
			(stroke
				(width 0)
				(type default)
			)
			(fill no)
			(layer "F.CrtYd")
		)
		(fp_poly
			(pts
				(xy -1.0033 1.4859) (xy -1.0033 0.8001) (xy -1.1811 0.8001) (xy -1.1811 -0.8001) (xy -1.0033 -0.8001)
				(xy -1.0033 -1.4859) (xy 1.0033 -1.4859) (xy 1.0033 -0.8001) (xy 1.1811 -0.8001) (xy 1.1811 0.8001)
				(xy 1.0033 0.8001) (xy 1.0033 1.4859) (xy 0.2921 1.4859) (xy 0.2921 0.8001) (xy -0.2921 0.8001)
				(xy -0.2921 1.4859)
			)
			(stroke
				(width 0)
				(type default)
			)
			(fill no)
			(layer "F.Fab")
		)
		(pad "1" smd rect
			(at 0.65024 -0.93472 90)
			(size 0.3556 0.762)
			(layers "F.Cu" "F.Mask" "F.Paste")
			(net "Net_405")
		)
		(pad "2" smd rect
			(at 0 -0.93472 90)
			(size 0.3556 0.762)
			(layers "F.Cu" "F.Mask" "F.Paste")
			(net "CLK_GEN_DELAY1_PG")
		)
		(pad "3" smd rect
			(at -0.65024 -0.93472 90)
			(size 0.3556 0.762)
			(layers "F.Cu" "F.Mask" "F.Paste")
			(net "GND")
		)
		(pad "4" smd rect
			(at -0.65024 0.93472 90)
			(size 0.3556 0.762)
			(layers "F.Cu" "F.Mask" "F.Paste")
			(net "CLK_GEN_DELAY2_PG")
		)
		(pad "5" smd rect
			(at 0.65024 0.93472 90)
			(size 0.3556 0.762)
			(layers "F.Cu" "F.Mask" "F.Paste")
			(net "P3V3")
		)
	)
	(footprint ""
		(layer "F.Cu")
		(at 47.879 -68.072 180)
		(property "Reference" "PC30"
			(at 0 0 180)
			(layer "F.SilkS")
			(hide yes)
			(effects
				(font
					(size 1.27 1.27)
				)
			)
		)
		(property "Value" "SC47U6D3V5MX-1-GP"
			(at 0 -4.9022 180)
			(unlocked yes)
			(layer "F.Fab")
			(hide yes)
			(effects
				(font
					(size 1.016 1.016)
					(thickness 0.1524)
				)
			)
		)
		(property "Device Type" "C805H54"
			(at 0 -6.8072 180)
			(unlocked yes)
			(layer "F.Fab")
			(hide yes)
			(effects
				(font
					(size 1.016 1.016)
					(thickness 0.1524)
				)
			)
		)
		(duplicate_pad_numbers_are_jumpers no)
		(fp_line
			(start 0.6096 0)
			(end -0.6096 0)
			(stroke
				(width 0.3048)
				(type default)
			)
			(layer "F.SilkS")
		)
		(fp_poly
			(pts
				(xy -0.9017 1.4351) (xy 0.9017 1.4351) (xy 0.9017 -1.4351) (xy -0.9017 -1.4351)
			)
			(stroke
				(width 0)
				(type default)
			)
			(fill no)
			(layer "F.CrtYd")
		)
		(fp_poly
			(pts
				(xy 0.9017 1.4351) (xy 0.9017 -1.4351) (xy -0.9017 -1.4351) (xy -0.9017 1.4351)
			)
			(stroke
				(width 0)
				(type default)
			)
			(fill no)
			(layer "F.Fab")
		)
		(pad "1" smd rect
			(at 0 -0.8382 180)
			(size 1.5494 0.9398)
			(layers "F.Cu" "F.Mask" "F.Paste")
			(net "PVNN")
		)
		(pad "2" smd rect
			(at 0 0.8382 180)
			(size 1.5494 0.9398)
			(layers "F.Cu" "F.Mask" "F.Paste")
			(net "GND")
		)
	)
	(footprint ""
		(layer "F.Cu")
		(at 51.435 -23.495 90)
		(property "Reference" "R448"
			(at 0 0 90)
			(layer "F.SilkS")
			(hide yes)
			(effects
				(font
					(size 1.27 1.27)
				)
			)
		)
		(property "Value" "4K7R2F-GP"
			(at 1.7907 -1.1176 90)
			(unlocked yes)
			(layer "F.Fab")
			(hide yes)
			(effects
				(font
					(size 1.016 1.016)
					(thickness 0.1524)
				)
			)
		)
		(property "Device Type" "R402H16"
			(at 1.7907 -2.6416 90)
			(unlocked yes)
			(layer "F.Fab")
			(hide yes)
			(effects
				(font
					(size 1.016 1.016)
					(thickness 0.1524)
				)
			)
		)
		(duplicate_pad_numbers_are_jumpers no)
		(fp_rect
			(start -0.381 0.8382)
			(end 0.381 -0.8382)
			(stroke
				(width 0)
				(type default)
			)
			(fill no)
			(layer "F.CrtYd")
		)
		(fp_rect
			(start -0.381 0.8382)
			(end 0.381 -0.8382)
			(stroke
				(width 0)
				(type default)
			)
			(fill no)
			(layer "F.Fab")
		)
		(pad "1" smd custom
			(at 0 -0.4318 90)
			(size 0.127 0.127)
			(layers "F.Cu" "F.Mask" "F.Paste")
			(net "CLKBUFF_OE7#")
			(options
				(clearance outline)
				(anchor circle)
			)
			(primitives
				(gr_poly
					(pts
						(arc
							(start -0.2032 -0.2794)
							(mid -0.239121 -0.264521)
							(end -0.254 -0.2286)
						)
						(arc
							(start -0.254 0.2286)
							(mid -0.239121 0.264521)
							(end -0.2032 0.2794)
						)
						(arc
							(start 0.2032 0.2794)
							(mid 0.239121 0.264521)
							(end 0.254 0.2286)
						)
						(arc
							(start 0.254 -0.2286)
							(mid 0.239121 -0.264521)
							(end 0.2032 -0.2794)
						)
					)
					(width 0)
					(fill yes)
				)
			)
		)
		(pad "2" smd custom
			(at 0 0.4318 90)
			(size 0.127 0.127)
			(layers "F.Cu" "F.Mask" "F.Paste")
			(net "GND")
			(options
				(clearance outline)
				(anchor circle)
			)
			(primitives
				(gr_poly
					(pts
						(arc
							(start -0.2032 -0.2794)
							(mid -0.239121 -0.264521)
							(end -0.254 -0.2286)
						)
						(arc
							(start -0.254 0.2286)
							(mid -0.239121 0.264521)
							(end -0.2032 0.2794)
						)
						(arc
							(start 0.2032 0.2794)
							(mid 0.239121 0.264521)
							(end 0.254 0.2286)
						)
						(arc
							(start 0.254 -0.2286)
							(mid 0.239121 -0.264521)
							(end 0.2032 -0.2794)
						)
					)
					(width 0)
					(fill yes)
				)
			)
		)
	)
	(footprint ""
		(layer "F.Cu")
		(at 138.4046 -51.9684 90)
		(property "Reference" "R118"
			(at 0 0 90)
			(layer "F.SilkS")
			(hide yes)
			(effects
				(font
					(size 1.27 1.27)
				)
			)
		)
		(property "Value" "0R2J-2-GP"
			(at 1.7907 -1.1176 90)
			(unlocked yes)
			(layer "F.Fab")
			(hide yes)
			(effects
				(font
					(size 1.016 1.016)
					(thickness 0.1524)
				)
			)
		)
		(property "Device Type" "R402H16"
			(at 1.7907 -2.6416 90)
			(unlocked yes)
			(layer "F.Fab")
			(hide yes)
			(effects
				(font
					(size 1.016 1.016)
					(thickness 0.1524)
				)
			)
		)
		(duplicate_pad_numbers_are_jumpers no)
		(fp_rect
			(start -0.381 0.8382)
			(end 0.381 -0.8382)
			(stroke
				(width 0)
				(type default)
			)
			(fill no)
			(layer "F.CrtYd")
		)
		(fp_rect
			(start -0.381 0.8382)
			(end 0.381 -0.8382)
			(stroke
				(width 0)
				(type default)
			)
			(fill no)
			(layer "F.Fab")
		)
		(pad "1" smd custom
			(at 0 -0.4318 90)
			(size 0.127 0.127)
			(layers "F.Cu" "F.Mask" "F.Paste")
			(net "C_NCONFIG#")
			(options
				(clearance outline)
				(anchor circle)
			)
			(primitives
				(gr_poly
					(pts
						(arc
							(start -0.2032 -0.2794)
							(mid -0.239121 -0.264521)
							(end -0.254 -0.2286)
						)
						(arc
							(start -0.254 0.2286)
							(mid -0.239121 0.264521)
							(end -0.2032 0.2794)
						)
						(arc
							(start 0.2032 0.2794)
							(mid 0.239121 0.264521)
							(end 0.254 0.2286)
						)
						(arc
							(start 0.254 -0.2286)
							(mid 0.239121 -0.264521)
							(end 0.2032 -0.2794)
						)
					)
					(width 0)
					(fill yes)
				)
			)
		)
		(pad "2" smd custom
			(at 0 0.4318 90)
			(size 0.127 0.127)
			(layers "F.Cu" "F.Mask" "F.Paste")
			(net "SPI_SW_NCONFIG#")
			(options
				(clearance outline)
				(anchor circle)
			)
			(primitives
				(gr_poly
					(pts
						(arc
							(start -0.2032 -0.2794)
							(mid -0.239121 -0.264521)
							(end -0.254 -0.2286)
						)
						(arc
							(start -0.254 0.2286)
							(mid -0.239121 0.264521)
							(end -0.2032 0.2794)
						)
						(arc
							(start 0.2032 0.2794)
							(mid 0.239121 0.264521)
							(end 0.254 0.2286)
						)
						(arc
							(start 0.254 -0.2286)
							(mid 0.239121 -0.264521)
							(end 0.2032 -0.2794)
						)
					)
					(width 0)
					(fill yes)
				)
			)
		)
	)
	(footprint ""
		(layer "F.Cu")
		(at 170.688 -26.543 -90)
		(property "Reference" "PU9"
			(at 0 0 270)
			(layer "F.SilkS")
			(hide yes)
			(effects
				(font
					(size 1.27 1.27)
				)
			)
		)
		(property "Value" "LD1117AG-12-AA3-A-R-GP"
			(at -0.0508 -10.3632 270)
			(unlocked yes)
			(layer "F.Fab")
			(hide yes)
			(effects
				(font
					(size 1.016 1.016)
					(thickness 0.1524)
				)
			)
		)
		(property "Device Type" "SOT-223H71"
			(at -0.1524 -12.3952 270)
			(unlocked yes)
			(layer "F.Fab")
			(hide yes)
			(effects
				(font
					(size 1.016 1.016)
					(thickness 0.1524)
				)
			)
		)
		(duplicate_pad_numbers_are_jumpers no)
		(fp_poly
			(pts
				(xy -2.3749 1.0922) (xy -1.9431 1.524) (xy -2.8067 1.524)
			)
			(stroke
				(width 0)
				(type default)
			)
			(fill yes)
			(layer "F.SilkS")
		)
		(fp_poly
			(pts
				(xy 3.048 1.0795) (xy 3.048 -0.8001) (xy 3.5052 -0.8001) (xy 3.5052 -4.8133) (xy 1.8796 -4.8133)
				(xy 1.8796 -6.6675) (xy -1.8796 -6.6675) (xy -1.8796 -4.8133) (xy -3.5052 -4.8133) (xy -3.5052 -0.8001)
				(xy -3.048 -0.8001) (xy -3.048 1.0795)
			)
			(stroke
				(width 0)
				(type default)
			)
			(fill no)
			(layer "F.CrtYd")
		)
		(fp_poly
			(pts
				(xy 3.048 1.0795) (xy 3.048 -0.5207) (xy 3.048 -0.6731) (xy 3.048 -0.8001) (xy 3.5052 -0.8001) (xy 3.5052 -4.6863)
				(xy 3.5052 -4.8133) (xy 1.905 -4.8133) (xy 1.8796 -4.8133) (xy 1.8796 -6.6675) (xy -1.8796 -6.6675)
				(xy -1.8796 -4.8133) (xy -1.905 -4.8133) (xy -3.5052 -4.8133) (xy -3.5052 -4.6863) (xy -3.5052 -0.8001)
				(xy -3.048 -0.8001) (xy -3.048 -0.6731) (xy -3.048 1.0795)
			)
			(stroke
				(width 0)
				(type default)
			)
			(fill no)
			(layer "F.Fab")
		)
		(pad "1" smd rect
			(at -2.286 0 270)
			(size 1.27 1.905)
			(layers "F.Cu" "F.Mask" "F.Paste")
			(net "GND")
		)
		(pad "2" smd custom
			(at 0 0 270)
			(size 0.8763 0.8763)
			(layers "F.Cu" "F.Mask" "F.Paste")
			(net "P1V2_STBY_LDO_OUT2")
			(options
				(clearance outline)
				(anchor circle)
			)
			(primitives
				(gr_poly
					(pts
						(xy 1.7526 -1.8415) (xy 0.381 -1.8415) (xy 0.381 1.8415) (xy 0.635 1.8415) (xy 0.635 3.7465) (xy -0.635 3.7465)
						(xy -0.635 1.8415) (xy -0.381 1.8415) (xy -0.381 -1.8415) (xy -1.7526 -1.8415) (xy -1.7526 -3.7465)
						(xy 1.7526 -3.7465)
					)
					(width 0)
					(fill yes)
				)
			)
		)
		(pad "3" smd rect
			(at 2.286 0 270)
			(size 1.27 1.905)
			(layers "F.Cu" "F.Mask" "F.Paste")
			(net "P1V8_STBY_LDO_IN2")
		)
	)
	(footprint ""
		(layer "F.Cu")
		(at 181.737 -14.859 180)
		(property "Reference" "PC117"
			(at 0 0 180)
			(layer "F.SilkS")
			(hide yes)
			(effects
				(font
					(size 1.27 1.27)
				)
			)
		)
		(property "Value" "SC10U6D3V3MX-GP"
			(at 0 -2.8194 180)
			(unlocked yes)
			(layer "F.Fab")
			(hide yes)
			(effects
				(font
					(size 1.016 1.016)
					(thickness 0.1524)
				)
			)
		)
		(property "Device Type" "C603H38"
			(at 0 -4.3434 180)
			(unlocked yes)
			(layer "F.Fab")
			(hide yes)
			(effects
				(font
					(size 1.016 1.016)
					(thickness 0.1524)
				)
			)
		)
		(duplicate_pad_numbers_are_jumpers no)
		(fp_line
			(start -0.4064 0)
			(end 0.4064 0)
			(stroke
				(width 0.2286)
				(type default)
			)
			(layer "F.SilkS")
		)
		(fp_rect
			(start -0.635 1.1811)
			(end 0.635 -1.1811)
			(stroke
				(width 0)
				(type default)
			)
			(fill no)
			(layer "F.CrtYd")
		)
		(fp_rect
			(start -0.635 1.1811)
			(end 0.635 -1.1811)
			(stroke
				(width 0)
				(type default)
			)
			(fill no)
			(layer "F.Fab")
		)
		(pad "1" smd custom
			(at 0 -0.6604 180)
			(size 0.19685 0.19685)
			(layers "F.Cu" "F.Mask" "F.Paste")
			(net "GND")
			(options
				(clearance outline)
				(anchor circle)
			)
			(primitives
				(gr_poly
					(pts
						(arc
							(start 0.508 -0.2921)
							(mid 0.478242 -0.363942)
							(end 0.4064 -0.3937)
						)
						(arc
							(start -0.4064 -0.3937)
							(mid -0.478242 -0.363942)
							(end -0.508 -0.2921)
						)
						(arc
							(start -0.508 0.2921)
							(mid -0.478242 0.363942)
							(end -0.4064 0.3937)
						)
						(arc
							(start 0.4064 0.3937)
							(mid 0.478242 0.363942)
							(end 0.508 0.2921)
						)
					)
					(width 0)
					(fill yes)
				)
			)
		)
		(pad "2" smd custom
			(at 0 0.6604 180)
			(size 0.19685 0.19685)
			(layers "F.Cu" "F.Mask" "F.Paste")
			(net "PV_VDDR")
			(options
				(clearance outline)
				(anchor circle)
			)
			(primitives
				(gr_poly
					(pts
						(arc
							(start 0.508 -0.2921)
							(mid 0.478242 -0.363942)
							(end 0.4064 -0.3937)
						)
						(arc
							(start -0.4064 -0.3937)
							(mid -0.478242 -0.363942)
							(end -0.508 -0.2921)
						)
						(arc
							(start -0.508 0.2921)
							(mid -0.478242 0.363942)
							(end -0.4064 0.3937)
						)
						(arc
							(start 0.4064 0.3937)
							(mid 0.478242 0.363942)
							(end 0.508 0.2921)
						)
					)
					(width 0)
					(fill yes)
				)
			)
		)
	)
	(footprint ""
		(layer "F.Cu")
		(at 193.04 -30.988 90)
		(property "Reference" "PR143"
			(at 0 0 90)
			(layer "F.SilkS")
			(hide yes)
			(effects
				(font
					(size 1.27 1.27)
				)
			)
		)
		(property "Value" "0R2J-2-GP"
			(at 1.7907 -1.1176 90)
			(unlocked yes)
			(layer "F.Fab")
			(hide yes)
			(effects
				(font
					(size 1.016 1.016)
					(thickness 0.1524)
				)
			)
		)
		(property "Device Type" "R402H16"
			(at 1.7907 -2.6416 90)
			(unlocked yes)
			(layer "F.Fab")
			(hide yes)
			(effects
				(font
					(size 1.016 1.016)
					(thickness 0.1524)
				)
			)
		)
		(duplicate_pad_numbers_are_jumpers no)
		(fp_rect
			(start -0.381 0.8382)
			(end 0.381 -0.8382)
			(stroke
				(width 0)
				(type default)
			)
			(fill no)
			(layer "F.CrtYd")
		)
		(fp_rect
			(start -0.381 0.8382)
			(end 0.381 -0.8382)
			(stroke
				(width 0)
				(type default)
			)
			(fill no)
			(layer "F.Fab")
		)
		(pad "1" smd custom
			(at 0 -0.4318 90)
			(size 0.127 0.127)
			(layers "F.Cu" "F.Mask" "F.Paste")
			(net "VR_PVDDR_A_VIN")
			(options
				(clearance outline)
				(anchor circle)
			)
			(primitives
				(gr_poly
					(pts
						(arc
							(start -0.2032 -0.2794)
							(mid -0.239121 -0.264521)
							(end -0.254 -0.2286)
						)
						(arc
							(start -0.254 0.2286)
							(mid -0.239121 0.264521)
							(end -0.2032 0.2794)
						)
						(arc
							(start 0.2032 0.2794)
							(mid 0.239121 0.264521)
							(end 0.254 0.2286)
						)
						(arc
							(start 0.254 -0.2286)
							(mid 0.239121 -0.264521)
							(end 0.2032 -0.2794)
						)
					)
					(width 0)
					(fill yes)
				)
			)
		)
		(pad "2" smd custom
			(at 0 0.4318 90)
			(size 0.127 0.127)
			(layers "F.Cu" "F.Mask" "F.Paste")
			(net "P12V")
			(options
				(clearance outline)
				(anchor circle)
			)
			(primitives
				(gr_poly
					(pts
						(arc
							(start -0.2032 -0.2794)
							(mid -0.239121 -0.264521)
							(end -0.254 -0.2286)
						)
						(arc
							(start -0.254 0.2286)
							(mid -0.239121 0.264521)
							(end -0.2032 0.2794)
						)
						(arc
							(start 0.2032 0.2794)
							(mid 0.239121 0.264521)
							(end 0.254 0.2286)
						)
						(arc
							(start 0.254 -0.2286)
							(mid 0.239121 -0.264521)
							(end 0.2032 -0.2794)
						)
					)
					(width 0)
					(fill yes)
				)
			)
		)
	)
	(footprint ""
		(layer "F.Cu")
		(at 39.64178 -40.31488 90)
		(property "Reference" "TP20"
			(at 0 0 90)
			(layer "F.SilkS")
			(hide yes)
			(effects
				(font
					(size 1.27 1.27)
				)
			)
		)
		(property "Value" "TPAD28-1-GP-U"
			(at 0.0508 -1.9304 90)
			(unlocked yes)
			(layer "F.Fab")
			(hide yes)
			(effects
				(font
					(size 1.016 1.016)
					(thickness 0.1524)
				)
			)
		)
		(property "Device Type" "TPAD28-1-U"
			(at 0.0508 -3.4544 90)
			(unlocked yes)
			(layer "F.Fab")
			(hide yes)
			(effects
				(font
					(size 1.016 1.016)
					(thickness 0.1524)
				)
			)
		)
		(duplicate_pad_numbers_are_jumpers no)
		(fp_poly
			(pts
				(arc
					(start 0 0.3556)
					(mid 0 -0.3556)
					(end 0 0.3556)
				)
			)
			(stroke
				(width 0)
				(type default)
			)
			(fill no)
			(layer "F.CrtYd")
		)
		(fp_poly
			(pts
				(arc
					(start 0 0.9525)
					(mid 0 -0.9525)
					(end 0 0.9525)
				)
			)
			(stroke
				(width 0)
				(type default)
			)
			(fill no)
			(layer "F.Fab")
		)
		(pad "1" smd circle
			(at 0 0 90)
			(size 0.7112 0.7112)
			(layers "F.Cu" "F.Mask" "F.Paste")
			(net "TP_XDP0_TCK1")
		)
	)
	(footprint ""
		(layer "F.Cu")
		(at 160.02 -59.309)
		(property "Reference" "C374"
			(at 0 0 0)
			(layer "F.SilkS")
			(hide yes)
			(effects
				(font
					(size 1.27 1.27)
				)
			)
		)
		(property "Value" "SC47U6D3V5MX-1-GP"
			(at 0 -4.9022 0)
			(unlocked yes)
			(layer "F.Fab")
			(hide yes)
			(effects
				(font
					(size 1.016 1.016)
					(thickness 0.1524)
				)
			)
		)
		(property "Device Type" "C805H54"
			(at 0 -6.8072 0)
			(unlocked yes)
			(layer "F.Fab")
			(hide yes)
			(effects
				(font
					(size 1.016 1.016)
					(thickness 0.1524)
				)
			)
		)
		(duplicate_pad_numbers_are_jumpers no)
		(fp_line
			(start 0.6096 0)
			(end -0.6096 0)
			(stroke
				(width 0.3048)
				(type default)
			)
			(layer "F.SilkS")
		)
		(fp_poly
			(pts
				(xy -0.9017 1.4351) (xy 0.9017 1.4351) (xy 0.9017 -1.4351) (xy -0.9017 -1.4351)
			)
			(stroke
				(width 0)
				(type default)
			)
			(fill no)
			(layer "F.CrtYd")
		)
		(fp_poly
			(pts
				(xy 0.9017 1.4351) (xy 0.9017 -1.4351) (xy -0.9017 -1.4351) (xy -0.9017 1.4351)
			)
			(stroke
				(width 0)
				(type default)
			)
			(fill no)
			(layer "F.Fab")
		)
		(pad "1" smd rect
			(at 0 -0.8382)
			(size 1.5494 0.9398)
			(layers "F.Cu" "F.Mask" "F.Paste")
			(net "PV_VDDR")
		)
		(pad "2" smd rect
			(at 0 0.8382)
			(size 1.5494 0.9398)
			(layers "F.Cu" "F.Mask" "F.Paste")
			(net "GND")
		)
	)
	(footprint ""
		(layer "F.Cu")
		(at 46.228 -33.274 -90)
		(property "Reference" "R241"
			(at 0 0 270)
			(layer "F.SilkS")
			(hide yes)
			(effects
				(font
					(size 1.27 1.27)
				)
			)
		)
		(property "Value" "1KR2F-3-GP"
			(at 0.064008 -3.993896 270)
			(unlocked yes)
			(layer "F.Fab")
			(hide yes)
			(effects
				(font
					(size 1.016 1.016)
					(thickness 0.1524)
				)
			)
		)
		(property "Device Type" "R402H16"
			(at 0.064008 -5.517896 270)
			(unlocked yes)
			(layer "F.Fab")
			(hide yes)
			(effects
				(font
					(size 1.016 1.016)
					(thickness 0.1524)
				)
			)
		)
		(duplicate_pad_numbers_are_jumpers no)
		(fp_rect
			(start -0.381 0.8382)
			(end 0.381 -0.8382)
			(stroke
				(width 0)
				(type default)
			)
			(fill no)
			(layer "F.CrtYd")
		)
		(fp_rect
			(start -0.381 0.8382)
			(end 0.381 -0.8382)
			(stroke
				(width 0)
				(type default)
			)
			(fill no)
			(layer "F.Fab")
		)
		(pad "1" smd custom
			(at 0 -0.4318 270)
			(size 0.127 0.127)
			(layers "F.Cu" "F.Mask" "F.Paste")
			(net "P3V3_CPU")
			(options
				(clearance outline)
				(anchor circle)
			)
			(primitives
				(gr_poly
					(pts
						(arc
							(start -0.2032 -0.2794)
							(mid -0.239121 -0.264521)
							(end -0.254 -0.2286)
						)
						(arc
							(start -0.254 0.2286)
							(mid -0.239121 0.264521)
							(end -0.2032 0.2794)
						)
						(arc
							(start 0.2032 0.2794)
							(mid 0.239121 0.264521)
							(end 0.254 0.2286)
						)
						(arc
							(start 0.254 -0.2286)
							(mid 0.239121 -0.264521)
							(end 0.2032 -0.2794)
						)
					)
					(width 0)
					(fill yes)
				)
			)
		)
		(pad "2" smd custom
			(at 0 0.4318 270)
			(size 0.127 0.127)
			(layers "F.Cu" "F.Mask" "F.Paste")
			(net "XDP_PWRBTN#")
			(options
				(clearance outline)
				(anchor circle)
			)
			(primitives
				(gr_poly
					(pts
						(arc
							(start -0.2032 -0.2794)
							(mid -0.239121 -0.264521)
							(end -0.254 -0.2286)
						)
						(arc
							(start -0.254 0.2286)
							(mid -0.239121 0.264521)
							(end -0.2032 0.2794)
						)
						(arc
							(start 0.2032 0.2794)
							(mid 0.239121 0.264521)
							(end 0.254 0.2286)
						)
						(arc
							(start 0.254 -0.2286)
							(mid 0.239121 -0.264521)
							(end 0.2032 -0.2794)
						)
					)
					(width 0)
					(fill yes)
				)
			)
		)
	)
	(footprint ""
		(layer "F.Cu")
		(at 155.702 -27.305)
		(property "Reference" "C235"
			(at 0 0 0)
			(layer "F.SilkS")
			(hide yes)
			(effects
				(font
					(size 1.27 1.27)
				)
			)
		)
		(property "Value" "SCD1U10V2KX-5GP"
			(at 1.1811 -2.7051 0)
			(unlocked yes)
			(layer "F.Fab")
			(hide yes)
			(effects
				(font
					(size 1.016 1.016)
					(thickness 0.1524)
				)
			)
		)
		(property "Device Type" "C402H22"
			(at 1.1811 -4.2291 0)
			(unlocked yes)
			(layer "F.Fab")
			(hide yes)
			(effects
				(font
					(size 1.016 1.016)
					(thickness 0.1524)
				)
			)
		)
		(duplicate_pad_numbers_are_jumpers no)
		(fp_rect
			(start -0.381 0.7366)
			(end 0.381 -0.7366)
			(stroke
				(width 0)
				(type default)
			)
			(fill no)
			(layer "F.CrtYd")
		)
		(fp_rect
			(start -0.381 0.7366)
			(end 0.381 -0.7366)
			(stroke
				(width 0)
				(type default)
			)
			(fill no)
			(layer "F.Fab")
		)
		(pad "1" smd custom
			(at 0 -0.4572)
			(size 0.1143 0.1143)
			(layers "F.Cu" "F.Mask" "F.Paste")
			(net "P3V3_STBY")
			(options
				(clearance outline)
				(anchor circle)
			)
			(primitives
				(gr_poly
					(pts
						(arc
							(start -0.254 -0.1778)
							(mid -0.239121 -0.213721)
							(end -0.2032 -0.2286)
						)
						(arc
							(start 0.2032 -0.2286)
							(mid 0.239121 -0.213721)
							(end 0.254 -0.1778)
						)
						(arc
							(start 0.254 0.1778)
							(mid 0.239121 0.213721)
							(end 0.2032 0.2286)
						)
						(arc
							(start -0.2032 0.2286)
							(mid -0.239121 0.213721)
							(end -0.254 0.1778)
						)
					)
					(width 0)
					(fill yes)
				)
			)
		)
		(pad "2" smd custom
			(at 0 0.4572)
			(size 0.1143 0.1143)
			(layers "F.Cu" "F.Mask" "F.Paste")
			(net "GND")
			(options
				(clearance outline)
				(anchor circle)
			)
			(primitives
				(gr_poly
					(pts
						(arc
							(start -0.254 -0.1778)
							(mid -0.239121 -0.213721)
							(end -0.2032 -0.2286)
						)
						(arc
							(start 0.2032 -0.2286)
							(mid 0.239121 -0.213721)
							(end 0.254 -0.1778)
						)
						(arc
							(start 0.254 0.1778)
							(mid 0.239121 0.213721)
							(end 0.2032 0.2286)
						)
						(arc
							(start -0.2032 0.2286)
							(mid -0.239121 0.213721)
							(end -0.254 0.1778)
						)
					)
					(width 0)
					(fill yes)
				)
			)
		)
	)
	(footprint ""
		(layer "F.Cu")
		(at 200.914 -31.242 -90)
		(property "Reference" "PC165"
			(at 0 0 270)
			(layer "F.SilkS")
			(hide yes)
			(effects
				(font
					(size 1.27 1.27)
				)
			)
		)
		(property "Value" "SC10U25V5KX-GP"
			(at 0 -4.9022 270)
			(unlocked yes)
			(layer "F.Fab")
			(hide yes)
			(effects
				(font
					(size 1.016 1.016)
					(thickness 0.1524)
				)
			)
		)
		(property "Device Type" "C805H56"
			(at 0 -6.8072 270)
			(unlocked yes)
			(layer "F.Fab")
			(hide yes)
			(effects
				(font
					(size 1.016 1.016)
					(thickness 0.1524)
				)
			)
		)
		(duplicate_pad_numbers_are_jumpers no)
		(fp_line
			(start 0.6096 0)
			(end -0.6096 0)
			(stroke
				(width 0.3048)
				(type default)
			)
			(layer "F.SilkS")
		)
		(fp_poly
			(pts
				(xy -0.9017 1.4351) (xy 0.9017 1.4351) (xy 0.9017 -1.4351) (xy -0.9017 -1.4351)
			)
			(stroke
				(width 0)
				(type default)
			)
			(fill no)
			(layer "F.CrtYd")
		)
		(fp_poly
			(pts
				(xy 0.9017 1.4351) (xy 0.9017 -1.4351) (xy -0.9017 -1.4351) (xy -0.9017 1.4351)
			)
			(stroke
				(width 0)
				(type default)
			)
			(fill no)
			(layer "F.Fab")
		)
		(pad "1" smd rect
			(at 0 -0.8382 270)
			(size 1.5494 0.9398)
			(layers "F.Cu" "F.Mask" "F.Paste")
			(net "PVDDR_VIN")
		)
		(pad "2" smd rect
			(at 0 0.8382 270)
			(size 1.5494 0.9398)
			(layers "F.Cu" "F.Mask" "F.Paste")
			(net "GND")
		)
	)
	(footprint ""
		(layer "F.Cu")
		(at 12.573 -60.071 180)
		(property "Reference" "PR52"
			(at 0 0 180)
			(layer "F.SilkS")
			(hide yes)
			(effects
				(font
					(size 1.27 1.27)
				)
			)
		)
		(property "Value" "56D2R2F-GP"
			(at 1.7907 -1.1176 180)
			(unlocked yes)
			(layer "F.Fab")
			(hide yes)
			(effects
				(font
					(size 1.016 1.016)
					(thickness 0.1524)
				)
			)
		)
		(property "Device Type" "R402H16"
			(at 1.7907 -2.6416 180)
			(unlocked yes)
			(layer "F.Fab")
			(hide yes)
			(effects
				(font
					(size 1.016 1.016)
					(thickness 0.1524)
				)
			)
		)
		(duplicate_pad_numbers_are_jumpers no)
		(fp_rect
			(start -0.381 0.8382)
			(end 0.381 -0.8382)
			(stroke
				(width 0)
				(type default)
			)
			(fill no)
			(layer "F.CrtYd")
		)
		(fp_rect
			(start -0.381 0.8382)
			(end 0.381 -0.8382)
			(stroke
				(width 0)
				(type default)
			)
			(fill no)
			(layer "F.Fab")
		)
		(pad "1" smd custom
			(at 0 -0.4318 180)
			(size 0.127 0.127)
			(layers "F.Cu" "F.Mask" "F.Paste")
			(net "P1V0")
			(options
				(clearance outline)
				(anchor circle)
			)
			(primitives
				(gr_poly
					(pts
						(arc
							(start -0.2032 -0.2794)
							(mid -0.239121 -0.264521)
							(end -0.254 -0.2286)
						)
						(arc
							(start -0.254 0.2286)
							(mid -0.239121 0.264521)
							(end -0.2032 0.2794)
						)
						(arc
							(start 0.2032 0.2794)
							(mid 0.239121 0.264521)
							(end 0.254 0.2286)
						)
						(arc
							(start 0.254 -0.2286)
							(mid 0.239121 -0.264521)
							(end 0.2032 -0.2794)
						)
					)
					(width 0)
					(fill yes)
				)
			)
		)
		(pad "2" smd custom
			(at 0 0.4318 180)
			(size 0.127 0.127)
			(layers "F.Cu" "F.Mask" "F.Paste")
			(net "SVID_CPU_CLK")
			(options
				(clearance outline)
				(anchor circle)
			)
			(primitives
				(gr_poly
					(pts
						(arc
							(start -0.2032 -0.2794)
							(mid -0.239121 -0.264521)
							(end -0.254 -0.2286)
						)
						(arc
							(start -0.254 0.2286)
							(mid -0.239121 0.264521)
							(end -0.2032 0.2794)
						)
						(arc
							(start 0.2032 0.2794)
							(mid 0.239121 0.264521)
							(end 0.254 0.2286)
						)
						(arc
							(start 0.254 -0.2286)
							(mid 0.239121 -0.264521)
							(end 0.2032 -0.2794)
						)
					)
					(width 0)
					(fill yes)
				)
			)
		)
	)
	(footprint ""
		(layer "F.Cu")
		(at 189.103 -48.514)
		(property "Reference" "C94"
			(at 0 0 0)
			(layer "F.SilkS")
			(hide yes)
			(effects
				(font
					(size 1.27 1.27)
				)
			)
		)
		(property "Value" "SCD1U16V2KX-3GP"
			(at 1.1811 -2.7051 0)
			(unlocked yes)
			(layer "F.Fab")
			(hide yes)
			(effects
				(font
					(size 1.016 1.016)
					(thickness 0.1524)
				)
			)
		)
		(property "Device Type" "C402H22"
			(at 1.1811 -4.2291 0)
			(unlocked yes)
			(layer "F.Fab")
			(hide yes)
			(effects
				(font
					(size 1.016 1.016)
					(thickness 0.1524)
				)
			)
		)
		(duplicate_pad_numbers_are_jumpers no)
		(fp_rect
			(start -0.381 0.7366)
			(end 0.381 -0.7366)
			(stroke
				(width 0)
				(type default)
			)
			(fill no)
			(layer "F.CrtYd")
		)
		(fp_rect
			(start -0.381 0.7366)
			(end 0.381 -0.7366)
			(stroke
				(width 0)
				(type default)
			)
			(fill no)
			(layer "F.Fab")
		)
		(pad "1" smd custom
			(at 0 -0.4572)
			(size 0.1143 0.1143)
			(layers "F.Cu" "F.Mask" "F.Paste")
			(net "P3V3_STBY")
			(options
				(clearance outline)
				(anchor circle)
			)
			(primitives
				(gr_poly
					(pts
						(arc
							(start -0.254 -0.1778)
							(mid -0.239121 -0.213721)
							(end -0.2032 -0.2286)
						)
						(arc
							(start 0.2032 -0.2286)
							(mid 0.239121 -0.213721)
							(end 0.254 -0.1778)
						)
						(arc
							(start 0.254 0.1778)
							(mid 0.239121 0.213721)
							(end 0.2032 0.2286)
						)
						(arc
							(start -0.2032 0.2286)
							(mid -0.239121 0.213721)
							(end -0.254 0.1778)
						)
					)
					(width 0)
					(fill yes)
				)
			)
		)
		(pad "2" smd custom
			(at 0 0.4572)
			(size 0.1143 0.1143)
			(layers "F.Cu" "F.Mask" "F.Paste")
			(net "GND")
			(options
				(clearance outline)
				(anchor circle)
			)
			(primitives
				(gr_poly
					(pts
						(arc
							(start -0.254 -0.1778)
							(mid -0.239121 -0.213721)
							(end -0.2032 -0.2286)
						)
						(arc
							(start 0.2032 -0.2286)
							(mid 0.239121 -0.213721)
							(end 0.254 -0.1778)
						)
						(arc
							(start 0.254 0.1778)
							(mid 0.239121 0.213721)
							(end 0.2032 0.2286)
						)
						(arc
							(start -0.2032 0.2286)
							(mid -0.239121 0.213721)
							(end -0.254 0.1778)
						)
					)
					(width 0)
					(fill yes)
				)
			)
		)
	)
	(footprint ""
		(layer "F.Cu")
		(at 69.596 -57.6072)
		(property "Reference" "C77"
			(at 0 0 0)
			(layer "F.SilkS")
			(hide yes)
			(effects
				(font
					(size 1.27 1.27)
				)
			)
		)
		(property "Value" "SCD1U16V2KX-3GP"
			(at 1.8923 -1.2065 0)
			(unlocked yes)
			(layer "F.Fab")
			(hide yes)
			(effects
				(font
					(size 1.016 1.016)
					(thickness 0.1524)
				)
			)
		)
		(property "Device Type" "C402H22"
			(at 1.8923 -2.7305 0)
			(unlocked yes)
			(layer "F.Fab")
			(hide yes)
			(effects
				(font
					(size 1.016 1.016)
					(thickness 0.1524)
				)
			)
		)
		(duplicate_pad_numbers_are_jumpers no)
		(fp_rect
			(start -0.381 0.7366)
			(end 0.381 -0.7366)
			(stroke
				(width 0)
				(type default)
			)
			(fill no)
			(layer "F.CrtYd")
		)
		(fp_rect
			(start -0.381 0.7366)
			(end 0.381 -0.7366)
			(stroke
				(width 0)
				(type default)
			)
			(fill no)
			(layer "F.Fab")
		)
		(pad "1" smd custom
			(at 0 -0.4572)
			(size 0.1143 0.1143)
			(layers "F.Cu" "F.Mask" "F.Paste")
			(net "P3V3_SENSE")
			(options
				(clearance outline)
				(anchor circle)
			)
			(primitives
				(gr_poly
					(pts
						(arc
							(start -0.254 -0.1778)
							(mid -0.239121 -0.213721)
							(end -0.2032 -0.2286)
						)
						(arc
							(start 0.2032 -0.2286)
							(mid 0.239121 -0.213721)
							(end 0.254 -0.1778)
						)
						(arc
							(start 0.254 0.1778)
							(mid 0.239121 0.213721)
							(end 0.2032 0.2286)
						)
						(arc
							(start -0.2032 0.2286)
							(mid -0.239121 0.213721)
							(end -0.254 0.1778)
						)
					)
					(width 0)
					(fill yes)
				)
			)
		)
		(pad "2" smd custom
			(at 0 0.4572)
			(size 0.1143 0.1143)
			(layers "F.Cu" "F.Mask" "F.Paste")
			(net "GND")
			(options
				(clearance outline)
				(anchor circle)
			)
			(primitives
				(gr_poly
					(pts
						(arc
							(start -0.254 -0.1778)
							(mid -0.239121 -0.213721)
							(end -0.2032 -0.2286)
						)
						(arc
							(start 0.2032 -0.2286)
							(mid 0.239121 -0.213721)
							(end 0.254 -0.1778)
						)
						(arc
							(start 0.254 0.1778)
							(mid 0.239121 0.213721)
							(end 0.2032 0.2286)
						)
						(arc
							(start -0.2032 0.2286)
							(mid -0.239121 0.213721)
							(end -0.254 0.1778)
						)
					)
					(width 0)
					(fill yes)
				)
			)
		)
	)
	(footprint ""
		(layer "F.Cu")
		(at 11.049 -61.468 -90)
		(property "Reference" "TP4"
			(at 0 0 270)
			(layer "F.SilkS")
			(hide yes)
			(effects
				(font
					(size 1.27 1.27)
				)
			)
		)
		(property "Value" "TPAD28-1-GP-U"
			(at 0.0508 -1.9304 270)
			(unlocked yes)
			(layer "F.Fab")
			(hide yes)
			(effects
				(font
					(size 1.016 1.016)
					(thickness 0.1524)
				)
			)
		)
		(property "Device Type" "TPAD28-1-U"
			(at 0.0508 -3.4544 270)
			(unlocked yes)
			(layer "F.Fab")
			(hide yes)
			(effects
				(font
					(size 1.016 1.016)
					(thickness 0.1524)
				)
			)
		)
		(duplicate_pad_numbers_are_jumpers no)
		(fp_poly
			(pts
				(arc
					(start 0 -0.3556)
					(mid 0 0.3556)
					(end 0 -0.3556)
				)
			)
			(stroke
				(width 0)
				(type default)
			)
			(fill no)
			(layer "F.CrtYd")
		)
		(fp_poly
			(pts
				(arc
					(start 0 -0.9525)
					(mid 0 0.9525)
					(end 0 -0.9525)
				)
			)
			(stroke
				(width 0)
				(type default)
			)
			(fill no)
			(layer "F.Fab")
		)
		(pad "1" smd circle
			(at 0 0 270)
			(size 0.7112 0.7112)
			(layers "F.Cu" "F.Mask" "F.Paste")
			(net "TP_PVCCP_VDIO")
		)
	)
	(footprint ""
		(layer "F.Cu")
		(at 74.4982 -39.624)
		(property "Reference" "C33"
			(at 0 0 0)
			(layer "F.SilkS")
			(hide yes)
			(effects
				(font
					(size 1.27 1.27)
				)
			)
		)
		(property "Value" "SC6P50V2CN-1GP"
			(at 1.1811 -2.7051 0)
			(unlocked yes)
			(layer "F.Fab")
			(hide yes)
			(effects
				(font
					(size 1.016 1.016)
					(thickness 0.1524)
				)
			)
		)
		(property "Device Type" "C402H22"
			(at 1.1811 -4.2291 0)
			(unlocked yes)
			(layer "F.Fab")
			(hide yes)
			(effects
				(font
					(size 1.016 1.016)
					(thickness 0.1524)
				)
			)
		)
		(duplicate_pad_numbers_are_jumpers no)
		(fp_rect
			(start -0.381 0.7366)
			(end 0.381 -0.7366)
			(stroke
				(width 0)
				(type default)
			)
			(fill no)
			(layer "F.CrtYd")
		)
		(fp_rect
			(start -0.381 0.7366)
			(end 0.381 -0.7366)
			(stroke
				(width 0)
				(type default)
			)
			(fill no)
			(layer "F.Fab")
		)
		(pad "1" smd custom
			(at 0 -0.4572)
			(size 0.1143 0.1143)
			(layers "F.Cu" "F.Mask" "F.Paste")
			(net "RTC_X2PAD")
			(options
				(clearance outline)
				(anchor circle)
			)
			(primitives
				(gr_poly
					(pts
						(arc
							(start -0.254 -0.1778)
							(mid -0.239121 -0.213721)
							(end -0.2032 -0.2286)
						)
						(arc
							(start 0.2032 -0.2286)
							(mid 0.239121 -0.213721)
							(end 0.254 -0.1778)
						)
						(arc
							(start 0.254 0.1778)
							(mid 0.239121 0.213721)
							(end 0.2032 0.2286)
						)
						(arc
							(start -0.2032 0.2286)
							(mid -0.239121 0.213721)
							(end -0.254 0.1778)
						)
					)
					(width 0)
					(fill yes)
				)
			)
		)
		(pad "2" smd custom
			(at 0 0.4572)
			(size 0.1143 0.1143)
			(layers "F.Cu" "F.Mask" "F.Paste")
			(net "GND")
			(options
				(clearance outline)
				(anchor circle)
			)
			(primitives
				(gr_poly
					(pts
						(arc
							(start -0.254 -0.1778)
							(mid -0.239121 -0.213721)
							(end -0.2032 -0.2286)
						)
						(arc
							(start 0.2032 -0.2286)
							(mid 0.239121 -0.213721)
							(end 0.254 -0.1778)
						)
						(arc
							(start 0.254 0.1778)
							(mid 0.239121 0.213721)
							(end 0.2032 0.2286)
						)
						(arc
							(start -0.2032 0.2286)
							(mid -0.239121 0.213721)
							(end -0.254 0.1778)
						)
					)
					(width 0)
					(fill yes)
				)
			)
		)
	)
	(footprint ""
		(layer "F.Cu")
		(at 6.3246 -50.546 180)
		(property "Reference" "R6"
			(at 0 0 180)
			(layer "F.SilkS")
			(hide yes)
			(effects
				(font
					(size 1.27 1.27)
				)
			)
		)
		(property "Value" "4K7R2F-GP"
			(at 0.064008 -3.993896 180)
			(unlocked yes)
			(layer "F.Fab")
			(hide yes)
			(effects
				(font
					(size 1.016 1.016)
					(thickness 0.1524)
				)
			)
		)
		(property "Device Type" "R402H16"
			(at 0.064008 -5.517896 180)
			(unlocked yes)
			(layer "F.Fab")
			(hide yes)
			(effects
				(font
					(size 1.016 1.016)
					(thickness 0.1524)
				)
			)
		)
		(duplicate_pad_numbers_are_jumpers no)
		(fp_rect
			(start -0.381 0.8382)
			(end 0.381 -0.8382)
			(stroke
				(width 0)
				(type default)
			)
			(fill no)
			(layer "F.CrtYd")
		)
		(fp_rect
			(start -0.381 0.8382)
			(end 0.381 -0.8382)
			(stroke
				(width 0)
				(type default)
			)
			(fill no)
			(layer "F.Fab")
		)
		(pad "1" smd custom
			(at 0 -0.4318 180)
			(size 0.127 0.127)
			(layers "F.Cu" "F.Mask" "F.Paste")
			(net "TEMP_1_A0")
			(options
				(clearance outline)
				(anchor circle)
			)
			(primitives
				(gr_poly
					(pts
						(arc
							(start -0.2032 -0.2794)
							(mid -0.239121 -0.264521)
							(end -0.254 -0.2286)
						)
						(arc
							(start -0.254 0.2286)
							(mid -0.239121 0.264521)
							(end -0.2032 0.2794)
						)
						(arc
							(start 0.2032 0.2794)
							(mid 0.239121 0.264521)
							(end 0.254 0.2286)
						)
						(arc
							(start 0.254 -0.2286)
							(mid 0.239121 -0.264521)
							(end 0.2032 -0.2794)
						)
					)
					(width 0)
					(fill yes)
				)
			)
		)
		(pad "2" smd custom
			(at 0 0.4318 180)
			(size 0.127 0.127)
			(layers "F.Cu" "F.Mask" "F.Paste")
			(net "GND")
			(options
				(clearance outline)
				(anchor circle)
			)
			(primitives
				(gr_poly
					(pts
						(arc
							(start -0.2032 -0.2794)
							(mid -0.239121 -0.264521)
							(end -0.254 -0.2286)
						)
						(arc
							(start -0.254 0.2286)
							(mid -0.239121 0.264521)
							(end -0.2032 0.2794)
						)
						(arc
							(start 0.2032 0.2794)
							(mid 0.239121 0.264521)
							(end 0.254 0.2286)
						)
						(arc
							(start 0.254 -0.2286)
							(mid 0.239121 -0.264521)
							(end 0.2032 -0.2794)
						)
					)
					(width 0)
					(fill yes)
				)
			)
		)
	)
	(footprint ""
		(layer "F.Cu")
		(at 156.718 -12.955778 180)
		(property "Reference" "C371"
			(at 0 0 180)
			(layer "F.SilkS")
			(hide yes)
			(effects
				(font
					(size 1.27 1.27)
				)
			)
		)
		(property "Value" "SC47U6D3V5MX-1-GP"
			(at 0 -4.9022 180)
			(unlocked yes)
			(layer "F.Fab")
			(hide yes)
			(effects
				(font
					(size 1.016 1.016)
					(thickness 0.1524)
				)
			)
		)
		(property "Device Type" "C805H54"
			(at 0 -6.8072 180)
			(unlocked yes)
			(layer "F.Fab")
			(hide yes)
			(effects
				(font
					(size 1.016 1.016)
					(thickness 0.1524)
				)
			)
		)
		(duplicate_pad_numbers_are_jumpers no)
		(fp_line
			(start 0.6096 0)
			(end -0.6096 0)
			(stroke
				(width 0.3048)
				(type default)
			)
			(layer "F.SilkS")
		)
		(fp_poly
			(pts
				(xy -0.9017 1.4351) (xy 0.9017 1.4351) (xy 0.9017 -1.4351) (xy -0.9017 -1.4351)
			)
			(stroke
				(width 0)
				(type default)
			)
			(fill no)
			(layer "F.CrtYd")
		)
		(fp_poly
			(pts
				(xy 0.9017 1.4351) (xy 0.9017 -1.4351) (xy -0.9017 -1.4351) (xy -0.9017 1.4351)
			)
			(stroke
				(width 0)
				(type default)
			)
			(fill no)
			(layer "F.Fab")
		)
		(pad "1" smd rect
			(at 0 -0.8382 180)
			(size 1.5494 0.9398)
			(layers "F.Cu" "F.Mask" "F.Paste")
			(net "PV_VDDR")
		)
		(pad "2" smd rect
			(at 0 0.8382 180)
			(size 1.5494 0.9398)
			(layers "F.Cu" "F.Mask" "F.Paste")
			(net "GND")
		)
	)
	(footprint ""
		(layer "F.Cu")
		(at 107.569 -20.701 90)
		(property "Reference" "R170"
			(at 0 0 90)
			(layer "F.SilkS")
			(hide yes)
			(effects
				(font
					(size 1.27 1.27)
				)
			)
		)
		(property "Value" "1KR2F-3-GP"
			(at 0.064008 -3.993896 90)
			(unlocked yes)
			(layer "F.Fab")
			(hide yes)
			(effects
				(font
					(size 1.016 1.016)
					(thickness 0.1524)
				)
			)
		)
		(property "Device Type" "R402H16"
			(at 0.064008 -5.517896 90)
			(unlocked yes)
			(layer "F.Fab")
			(hide yes)
			(effects
				(font
					(size 1.016 1.016)
					(thickness 0.1524)
				)
			)
		)
		(duplicate_pad_numbers_are_jumpers no)
		(fp_rect
			(start -0.381 0.8382)
			(end 0.381 -0.8382)
			(stroke
				(width 0)
				(type default)
			)
			(fill no)
			(layer "F.CrtYd")
		)
		(fp_rect
			(start -0.381 0.8382)
			(end 0.381 -0.8382)
			(stroke
				(width 0)
				(type default)
			)
			(fill no)
			(layer "F.Fab")
		)
		(pad "1" smd custom
			(at 0 -0.4318 90)
			(size 0.127 0.127)
			(layers "F.Cu" "F.Mask" "F.Paste")
			(net "PV_VDDR")
			(options
				(clearance outline)
				(anchor circle)
			)
			(primitives
				(gr_poly
					(pts
						(arc
							(start -0.2032 -0.2794)
							(mid -0.239121 -0.264521)
							(end -0.254 -0.2286)
						)
						(arc
							(start -0.254 0.2286)
							(mid -0.239121 0.264521)
							(end -0.2032 0.2794)
						)
						(arc
							(start 0.2032 0.2794)
							(mid 0.239121 0.264521)
							(end 0.254 0.2286)
						)
						(arc
							(start 0.254 -0.2286)
							(mid 0.239121 -0.264521)
							(end 0.2032 -0.2794)
						)
					)
					(width 0)
					(fill yes)
				)
			)
		)
		(pad "2" smd custom
			(at 0 0.4318 90)
			(size 0.127 0.127)
			(layers "F.Cu" "F.Mask" "F.Paste")
			(net "M_B_RESET#")
			(options
				(clearance outline)
				(anchor circle)
			)
			(primitives
				(gr_poly
					(pts
						(arc
							(start -0.2032 -0.2794)
							(mid -0.239121 -0.264521)
							(end -0.254 -0.2286)
						)
						(arc
							(start -0.254 0.2286)
							(mid -0.239121 0.264521)
							(end -0.2032 0.2794)
						)
						(arc
							(start 0.2032 0.2794)
							(mid 0.239121 0.264521)
							(end 0.254 0.2286)
						)
						(arc
							(start 0.254 -0.2286)
							(mid 0.239121 -0.264521)
							(end 0.2032 -0.2794)
						)
					)
					(width 0)
					(fill yes)
				)
			)
		)
	)
	(footprint ""
		(layer "F.Cu")
		(at 91.186 -13.208)
		(property "Reference" "R459"
			(at 0 0 0)
			(layer "F.SilkS")
			(hide yes)
			(effects
				(font
					(size 1.27 1.27)
				)
			)
		)
		(property "Value" "4K7R2F-GP"
			(at 1.7907 -1.1176 0)
			(unlocked yes)
			(layer "F.Fab")
			(hide yes)
			(effects
				(font
					(size 1.016 1.016)
					(thickness 0.1524)
				)
			)
		)
		(property "Device Type" "R402H16"
			(at 1.7907 -2.6416 0)
			(unlocked yes)
			(layer "F.Fab")
			(hide yes)
			(effects
				(font
					(size 1.016 1.016)
					(thickness 0.1524)
				)
			)
		)
		(duplicate_pad_numbers_are_jumpers no)
		(fp_rect
			(start -0.381 0.8382)
			(end 0.381 -0.8382)
			(stroke
				(width 0)
				(type default)
			)
			(fill no)
			(layer "F.CrtYd")
		)
		(fp_rect
			(start -0.381 0.8382)
			(end 0.381 -0.8382)
			(stroke
				(width 0)
				(type default)
			)
			(fill no)
			(layer "F.Fab")
		)
		(pad "1" smd custom
			(at 0 -0.4318)
			(size 0.127 0.127)
			(layers "F.Cu" "F.Mask" "F.Paste")
			(net "P3V3_STBY")
			(options
				(clearance outline)
				(anchor circle)
			)
			(primitives
				(gr_poly
					(pts
						(arc
							(start -0.2032 -0.2794)
							(mid -0.239121 -0.264521)
							(end -0.254 -0.2286)
						)
						(arc
							(start -0.254 0.2286)
							(mid -0.239121 0.264521)
							(end -0.2032 0.2794)
						)
						(arc
							(start 0.2032 0.2794)
							(mid 0.239121 0.264521)
							(end 0.254 0.2286)
						)
						(arc
							(start 0.254 -0.2286)
							(mid 0.239121 -0.264521)
							(end 0.2032 -0.2794)
						)
					)
					(width 0)
					(fill yes)
				)
			)
		)
		(pad "2" smd custom
			(at 0 0.4318)
			(size 0.127 0.127)
			(layers "F.Cu" "F.Mask" "F.Paste")
			(net "SLOT_ID3")
			(options
				(clearance outline)
				(anchor circle)
			)
			(primitives
				(gr_poly
					(pts
						(arc
							(start -0.2032 -0.2794)
							(mid -0.239121 -0.264521)
							(end -0.254 -0.2286)
						)
						(arc
							(start -0.254 0.2286)
							(mid -0.239121 0.264521)
							(end -0.2032 0.2794)
						)
						(arc
							(start 0.2032 0.2794)
							(mid 0.239121 0.264521)
							(end 0.254 0.2286)
						)
						(arc
							(start 0.254 -0.2286)
							(mid 0.239121 -0.264521)
							(end 0.2032 -0.2794)
						)
					)
					(width 0)
					(fill yes)
				)
			)
		)
	)
	(footprint ""
		(layer "F.Cu")
		(at 68.072 -51.054 -90)
		(property "Reference" "R465"
			(at 0 0 270)
			(layer "F.SilkS")
			(hide yes)
			(effects
				(font
					(size 1.27 1.27)
				)
			)
		)
		(property "Value" "4K7R2F-GP"
			(at 1.7907 -1.1176 270)
			(unlocked yes)
			(layer "F.Fab")
			(hide yes)
			(effects
				(font
					(size 1.016 1.016)
					(thickness 0.1524)
				)
			)
		)
		(property "Device Type" "R402H16"
			(at 1.7907 -2.6416 270)
			(unlocked yes)
			(layer "F.Fab")
			(hide yes)
			(effects
				(font
					(size 1.016 1.016)
					(thickness 0.1524)
				)
			)
		)
		(duplicate_pad_numbers_are_jumpers no)
		(fp_rect
			(start -0.381 0.8382)
			(end 0.381 -0.8382)
			(stroke
				(width 0)
				(type default)
			)
			(fill no)
			(layer "F.CrtYd")
		)
		(fp_rect
			(start -0.381 0.8382)
			(end 0.381 -0.8382)
			(stroke
				(width 0)
				(type default)
			)
			(fill no)
			(layer "F.Fab")
		)
		(pad "1" smd custom
			(at 0 -0.4318 270)
			(size 0.127 0.127)
			(layers "F.Cu" "F.Mask" "F.Paste")
			(net "P3V3")
			(options
				(clearance outline)
				(anchor circle)
			)
			(primitives
				(gr_poly
					(pts
						(arc
							(start -0.2032 -0.2794)
							(mid -0.239121 -0.264521)
							(end -0.254 -0.2286)
						)
						(arc
							(start -0.254 0.2286)
							(mid -0.239121 0.264521)
							(end -0.2032 0.2794)
						)
						(arc
							(start 0.2032 0.2794)
							(mid 0.239121 0.264521)
							(end 0.254 0.2286)
						)
						(arc
							(start 0.254 -0.2286)
							(mid 0.239121 -0.264521)
							(end 0.2032 -0.2794)
						)
					)
					(width 0)
					(fill yes)
				)
			)
		)
		(pad "2" smd custom
			(at 0 0.4318 270)
			(size 0.127 0.127)
			(layers "F.Cu" "F.Mask" "F.Paste")
			(net "SMBUS_SW_INV_D")
			(options
				(clearance outline)
				(anchor circle)
			)
			(primitives
				(gr_poly
					(pts
						(arc
							(start -0.2032 -0.2794)
							(mid -0.239121 -0.264521)
							(end -0.254 -0.2286)
						)
						(arc
							(start -0.254 0.2286)
							(mid -0.239121 0.264521)
							(end -0.2032 0.2794)
						)
						(arc
							(start 0.2032 0.2794)
							(mid 0.239121 0.264521)
							(end 0.254 0.2286)
						)
						(arc
							(start 0.254 -0.2286)
							(mid 0.239121 -0.264521)
							(end 0.2032 -0.2794)
						)
					)
					(width 0)
					(fill yes)
				)
			)
		)
	)
	(footprint ""
		(layer "F.Cu")
		(at 186.436 -39.878)
		(property "Reference" "PR123"
			(at 0 0 0)
			(layer "F.SilkS")
			(hide yes)
			(effects
				(font
					(size 1.27 1.27)
				)
			)
		)
		(property "Value" "0R2J-2-GP"
			(at 1.7907 -1.1176 0)
			(unlocked yes)
			(layer "F.Fab")
			(hide yes)
			(effects
				(font
					(size 1.016 1.016)
					(thickness 0.1524)
				)
			)
		)
		(property "Device Type" "R402H16"
			(at 1.7907 -2.6416 0)
			(unlocked yes)
			(layer "F.Fab")
			(hide yes)
			(effects
				(font
					(size 1.016 1.016)
					(thickness 0.1524)
				)
			)
		)
		(duplicate_pad_numbers_are_jumpers no)
		(fp_rect
			(start -0.381 0.8382)
			(end 0.381 -0.8382)
			(stroke
				(width 0)
				(type default)
			)
			(fill no)
			(layer "F.CrtYd")
		)
		(fp_rect
			(start -0.381 0.8382)
			(end 0.381 -0.8382)
			(stroke
				(width 0)
				(type default)
			)
			(fill no)
			(layer "F.Fab")
		)
		(pad "1" smd custom
			(at 0 -0.4318)
			(size 0.127 0.127)
			(layers "F.Cu" "F.Mask" "F.Paste")
			(net "GND")
			(options
				(clearance outline)
				(anchor circle)
			)
			(primitives
				(gr_poly
					(pts
						(arc
							(start -0.2032 -0.2794)
							(mid -0.239121 -0.264521)
							(end -0.254 -0.2286)
						)
						(arc
							(start -0.254 0.2286)
							(mid -0.239121 0.264521)
							(end -0.2032 0.2794)
						)
						(arc
							(start 0.2032 0.2794)
							(mid 0.239121 0.264521)
							(end 0.254 0.2286)
						)
						(arc
							(start 0.254 -0.2286)
							(mid 0.239121 -0.264521)
							(end 0.2032 -0.2794)
						)
					)
					(width 0)
					(fill yes)
				)
			)
		)
		(pad "2" smd custom
			(at 0 0.4318)
			(size 0.127 0.127)
			(layers "F.Cu" "F.Mask" "F.Paste")
			(net "VR_PVDDR_A_IAUTO")
			(options
				(clearance outline)
				(anchor circle)
			)
			(primitives
				(gr_poly
					(pts
						(arc
							(start -0.2032 -0.2794)
							(mid -0.239121 -0.264521)
							(end -0.254 -0.2286)
						)
						(arc
							(start -0.254 0.2286)
							(mid -0.239121 0.264521)
							(end -0.2032 0.2794)
						)
						(arc
							(start 0.2032 0.2794)
							(mid 0.239121 0.264521)
							(end 0.254 0.2286)
						)
						(arc
							(start 0.254 -0.2286)
							(mid 0.239121 -0.264521)
							(end 0.2032 -0.2794)
						)
					)
					(width 0)
					(fill yes)
				)
			)
		)
	)
	(footprint ""
		(layer "F.Cu")
		(at 73.66 -49.276)
		(property "Reference" "R44"
			(at 0 0 0)
			(layer "F.SilkS")
			(hide yes)
			(effects
				(font
					(size 1.27 1.27)
				)
			)
		)
		(property "Value" "4K7R2F-GP"
			(at 0.064008 -3.993896 0)
			(unlocked yes)
			(layer "F.Fab")
			(hide yes)
			(effects
				(font
					(size 1.016 1.016)
					(thickness 0.1524)
				)
			)
		)
		(property "Device Type" "R402H16"
			(at 0.064008 -5.517896 0)
			(unlocked yes)
			(layer "F.Fab")
			(hide yes)
			(effects
				(font
					(size 1.016 1.016)
					(thickness 0.1524)
				)
			)
		)
		(duplicate_pad_numbers_are_jumpers no)
		(fp_rect
			(start -0.381 0.8382)
			(end 0.381 -0.8382)
			(stroke
				(width 0)
				(type default)
			)
			(fill no)
			(layer "F.CrtYd")
		)
		(fp_rect
			(start -0.381 0.8382)
			(end 0.381 -0.8382)
			(stroke
				(width 0)
				(type default)
			)
			(fill no)
			(layer "F.Fab")
		)
		(pad "1" smd custom
			(at 0 -0.4318)
			(size 0.127 0.127)
			(layers "F.Cu" "F.Mask" "F.Paste")
			(net "P3V3")
			(options
				(clearance outline)
				(anchor circle)
			)
			(primitives
				(gr_poly
					(pts
						(arc
							(start -0.2032 -0.2794)
							(mid -0.239121 -0.264521)
							(end -0.254 -0.2286)
						)
						(arc
							(start -0.254 0.2286)
							(mid -0.239121 0.264521)
							(end -0.2032 0.2794)
						)
						(arc
							(start 0.2032 0.2794)
							(mid 0.239121 0.264521)
							(end 0.254 0.2286)
						)
						(arc
							(start 0.254 -0.2286)
							(mid 0.239121 -0.264521)
							(end 0.2032 -0.2794)
						)
					)
					(width 0)
					(fill yes)
				)
			)
		)
		(pad "2" smd custom
			(at 0 0.4318)
			(size 0.127 0.127)
			(layers "F.Cu" "F.Mask" "F.Paste")
			(net "BD_ID_0")
			(options
				(clearance outline)
				(anchor circle)
			)
			(primitives
				(gr_poly
					(pts
						(arc
							(start -0.2032 -0.2794)
							(mid -0.239121 -0.264521)
							(end -0.254 -0.2286)
						)
						(arc
							(start -0.254 0.2286)
							(mid -0.239121 0.264521)
							(end -0.2032 0.2794)
						)
						(arc
							(start 0.2032 0.2794)
							(mid 0.239121 0.264521)
							(end 0.254 0.2286)
						)
						(arc
							(start 0.254 -0.2286)
							(mid 0.239121 -0.264521)
							(end 0.2032 -0.2794)
						)
					)
					(width 0)
					(fill yes)
				)
			)
		)
	)
	(footprint ""
		(layer "F.Cu")
		(at 50.1142 -34.925 180)
		(property "Reference" "R105"
			(at 0 0 180)
			(layer "F.SilkS")
			(hide yes)
			(effects
				(font
					(size 1.27 1.27)
				)
			)
		)
		(property "Value" "4K7R2F-GP"
			(at 0.064008 -3.993896 180)
			(unlocked yes)
			(layer "F.Fab")
			(hide yes)
			(effects
				(font
					(size 1.016 1.016)
					(thickness 0.1524)
				)
			)
		)
		(property "Device Type" "R402H16"
			(at 0.064008 -5.517896 180)
			(unlocked yes)
			(layer "F.Fab")
			(hide yes)
			(effects
				(font
					(size 1.016 1.016)
					(thickness 0.1524)
				)
			)
		)
		(duplicate_pad_numbers_are_jumpers no)
		(fp_rect
			(start -0.381 0.8382)
			(end 0.381 -0.8382)
			(stroke
				(width 0)
				(type default)
			)
			(fill no)
			(layer "F.CrtYd")
		)
		(fp_rect
			(start -0.381 0.8382)
			(end 0.381 -0.8382)
			(stroke
				(width 0)
				(type default)
			)
			(fill no)
			(layer "F.Fab")
		)
		(pad "1" smd custom
			(at 0 -0.4318 180)
			(size 0.127 0.127)
			(layers "F.Cu" "F.Mask" "F.Paste")
			(net "SPI_HOLD#")
			(options
				(clearance outline)
				(anchor circle)
			)
			(primitives
				(gr_poly
					(pts
						(arc
							(start -0.2032 -0.2794)
							(mid -0.239121 -0.264521)
							(end -0.254 -0.2286)
						)
						(arc
							(start -0.254 0.2286)
							(mid -0.239121 0.264521)
							(end -0.2032 0.2794)
						)
						(arc
							(start 0.2032 0.2794)
							(mid 0.239121 0.264521)
							(end 0.254 0.2286)
						)
						(arc
							(start 0.254 -0.2286)
							(mid 0.239121 -0.264521)
							(end 0.2032 -0.2794)
						)
					)
					(width 0)
					(fill yes)
				)
			)
		)
		(pad "2" smd custom
			(at 0 0.4318 180)
			(size 0.127 0.127)
			(layers "F.Cu" "F.Mask" "F.Paste")
			(net "P3V3_CPU")
			(options
				(clearance outline)
				(anchor circle)
			)
			(primitives
				(gr_poly
					(pts
						(arc
							(start -0.2032 -0.2794)
							(mid -0.239121 -0.264521)
							(end -0.254 -0.2286)
						)
						(arc
							(start -0.254 0.2286)
							(mid -0.239121 0.264521)
							(end -0.2032 0.2794)
						)
						(arc
							(start 0.2032 0.2794)
							(mid 0.239121 0.264521)
							(end 0.254 0.2286)
						)
						(arc
							(start 0.254 -0.2286)
							(mid 0.239121 -0.264521)
							(end 0.2032 -0.2794)
						)
					)
					(width 0)
					(fill yes)
				)
			)
		)
	)
	(footprint ""
		(layer "F.Cu")
		(at 41.148 -58.039 90)
		(property "Reference" "PU2"
			(at 0 0 90)
			(layer "F.SilkS")
			(hide yes)
			(effects
				(font
					(size 1.27 1.27)
				)
			)
		)
		(property "Value" "IRFH4253DTRPBF-GP-U"
			(at -3.9116 -4.5085 90)
			(unlocked yes)
			(layer "F.Fab")
			(hide yes)
			(effects
				(font
					(size 1.016 1.016)
					(thickness 0.1524)
				)
			)
		)
		(property "Device Type" "DFN8A5060-G2PH40"
			(at -3.9116 -6.0325 90)
			(unlocked yes)
			(layer "F.Fab")
			(hide yes)
			(effects
				(font
					(size 1.016 1.016)
					(thickness 0.1524)
				)
			)
		)
		(duplicate_pad_numbers_are_jumpers no)
		(fp_rect
			(start -2.7559 3.3782)
			(end 2.7559 -3.3782)
			(stroke
				(width 0)
				(type default)
			)
			(fill no)
			(layer "F.CrtYd")
		)
		(fp_rect
			(start -2.7559 3.3782)
			(end 2.7559 -3.3782)
			(stroke
				(width 0)
				(type default)
			)
			(fill no)
			(layer "F.Fab")
		)
		(pad "1" smd rect
			(at 1.905 -2.796794 90)
			(size 0.6604 0.9144)
			(layers "F.Cu" "F.Mask" "F.Paste")
			(net "VR_PVCCP_GH_R")
		)
		(pad "2" smd rect
			(at 0.635 -2.796794 90)
			(size 0.6604 0.9144)
			(layers "F.Cu" "F.Mask" "F.Paste")
			(net "VR_PVCCP_PHASE")
		)
		(pad "3" smd rect
			(at -0.635 -2.796794 90)
			(size 0.6604 0.9144)
			(layers "F.Cu" "F.Mask" "F.Paste")
			(net "VR_FET_SW_P12V_PVCCP_PVNN")
		)
		(pad "4" smd rect
			(at -1.905 -2.796794 90)
			(size 0.6604 0.9144)
			(layers "F.Cu" "F.Mask" "F.Paste")
			(net "VR_FET_SW_P12V_PVCCP_PVNN")
		)
		(pad "5" smd rect
			(at -1.905 2.745994 90)
			(size 0.6604 1.016)
			(layers "F.Cu" "F.Mask" "F.Paste")
			(net "VR_PVCCP_PWM_OUT")
		)
		(pad "6" smd rect
			(at -0.635 2.745994 90)
			(size 0.6604 1.016)
			(layers "F.Cu" "F.Mask" "F.Paste")
			(net "VR_PVCCP_PWM_OUT")
		)
		(pad "7" smd rect
			(at 0.635 2.745994 90)
			(size 0.6604 1.016)
			(layers "F.Cu" "F.Mask" "F.Paste")
			(net "VR_PVCCP_PWM_OUT")
		)
		(pad "8" smd rect
			(at 1.905 2.174494 90)
			(size 0.6604 2.159)
			(layers "F.Cu" "F.Mask" "F.Paste")
			(net "VR_PVCCP_LH_R")
		)
		(pad "9" smd custom
			(at 0 0.635 90)
			(size 0.66675 0.66675)
			(layers "F.Cu" "F.Mask" "F.Paste")
			(net "GND")
			(options
				(clearance outline)
				(anchor circle)
			)
			(primitives
				(gr_poly
					(pts
						(xy -2.3241 1.3335) (xy -2.3241 -1.3335) (xy 2.3241 -1.3335) (xy 2.3241 0.1905) (xy 1.1049 0.1905)
						(xy 1.1049 1.3335)
					)
					(width 0)
					(fill yes)
				)
			)
		)
		(pad "10" smd rect
			(at 0 -1.59512 90)
			(size 4.2672 1.0414)
			(layers "F.Cu" "F.Mask" "F.Paste")
			(net "VR_FET_SW_P12V_PVCCP_PVNN")
		)
	)
	(footprint ""
		(layer "F.Cu")
		(at 47.6504 -37.5158)
		(property "Reference" "C28"
			(at 0 0 0)
			(layer "F.SilkS")
			(hide yes)
			(effects
				(font
					(size 1.27 1.27)
				)
			)
		)
		(property "Value" "SCD1U10V2KX-5GP"
			(at 1.8923 -1.2065 0)
			(unlocked yes)
			(layer "F.Fab")
			(hide yes)
			(effects
				(font
					(size 1.016 1.016)
					(thickness 0.1524)
				)
			)
		)
		(property "Device Type" "C402H22"
			(at 1.8923 -2.7305 0)
			(unlocked yes)
			(layer "F.Fab")
			(hide yes)
			(effects
				(font
					(size 1.016 1.016)
					(thickness 0.1524)
				)
			)
		)
		(duplicate_pad_numbers_are_jumpers no)
		(fp_rect
			(start -0.381 0.7366)
			(end 0.381 -0.7366)
			(stroke
				(width 0)
				(type default)
			)
			(fill no)
			(layer "F.CrtYd")
		)
		(fp_rect
			(start -0.381 0.7366)
			(end 0.381 -0.7366)
			(stroke
				(width 0)
				(type default)
			)
			(fill no)
			(layer "F.Fab")
		)
		(pad "1" smd custom
			(at 0 -0.4572)
			(size 0.1143 0.1143)
			(layers "F.Cu" "F.Mask" "F.Paste")
			(net "P3V3_STBY")
			(options
				(clearance outline)
				(anchor circle)
			)
			(primitives
				(gr_poly
					(pts
						(arc
							(start -0.254 -0.1778)
							(mid -0.239121 -0.213721)
							(end -0.2032 -0.2286)
						)
						(arc
							(start 0.2032 -0.2286)
							(mid 0.239121 -0.213721)
							(end 0.254 -0.1778)
						)
						(arc
							(start 0.254 0.1778)
							(mid 0.239121 0.213721)
							(end 0.2032 0.2286)
						)
						(arc
							(start -0.2032 0.2286)
							(mid -0.239121 0.213721)
							(end -0.254 0.1778)
						)
					)
					(width 0)
					(fill yes)
				)
			)
		)
		(pad "2" smd custom
			(at 0 0.4572)
			(size 0.1143 0.1143)
			(layers "F.Cu" "F.Mask" "F.Paste")
			(net "GND")
			(options
				(clearance outline)
				(anchor circle)
			)
			(primitives
				(gr_poly
					(pts
						(arc
							(start -0.254 -0.1778)
							(mid -0.239121 -0.213721)
							(end -0.2032 -0.2286)
						)
						(arc
							(start 0.2032 -0.2286)
							(mid 0.239121 -0.213721)
							(end 0.254 -0.1778)
						)
						(arc
							(start 0.254 0.1778)
							(mid 0.239121 0.213721)
							(end 0.2032 0.2286)
						)
						(arc
							(start -0.2032 0.2286)
							(mid -0.239121 0.213721)
							(end -0.254 0.1778)
						)
					)
					(width 0)
					(fill yes)
				)
			)
		)
	)
	(footprint ""
		(layer "F.Cu")
		(at 26.289 -32.385 180)
		(property "Reference" "PC51"
			(at 0 0 180)
			(layer "F.SilkS")
			(hide yes)
			(effects
				(font
					(size 1.27 1.27)
				)
			)
		)
		(property "Value" "SC22U6D3V3MX-1-GP"
			(at -0.0254 -2.0193 180)
			(unlocked yes)
			(layer "F.Fab")
			(hide yes)
			(effects
				(font
					(size 1.016 1.016)
					(thickness 0.1524)
				)
			)
		)
		(property "Device Type" "C603H40"
			(at -0.0254 -3.5433 180)
			(unlocked yes)
			(layer "F.Fab")
			(hide yes)
			(effects
				(font
					(size 1.016 1.016)
					(thickness 0.1524)
				)
			)
		)
		(duplicate_pad_numbers_are_jumpers no)
		(fp_line
			(start -0.4064 0)
			(end 0.4064 0)
			(stroke
				(width 0.2286)
				(type default)
			)
			(layer "F.SilkS")
		)
		(fp_rect
			(start -0.635 1.1811)
			(end 0.635 -1.1811)
			(stroke
				(width 0)
				(type default)
			)
			(fill no)
			(layer "F.CrtYd")
		)
		(fp_rect
			(start -0.635 1.1811)
			(end 0.635 -1.1811)
			(stroke
				(width 0)
				(type default)
			)
			(fill no)
			(layer "F.Fab")
		)
		(pad "1" smd custom
			(at 0 -0.6604 180)
			(size 0.19685 0.19685)
			(layers "F.Cu" "F.Mask" "F.Paste")
			(net "P1V0")
			(options
				(clearance outline)
				(anchor circle)
			)
			(primitives
				(gr_poly
					(pts
						(arc
							(start 0.508 -0.2921)
							(mid 0.478242 -0.363942)
							(end 0.4064 -0.3937)
						)
						(arc
							(start -0.4064 -0.3937)
							(mid -0.478242 -0.363942)
							(end -0.508 -0.2921)
						)
						(arc
							(start -0.508 0.2921)
							(mid -0.478242 0.363942)
							(end -0.4064 0.3937)
						)
						(arc
							(start 0.4064 0.3937)
							(mid 0.478242 0.363942)
							(end 0.508 0.2921)
						)
					)
					(width 0)
					(fill yes)
				)
			)
		)
		(pad "2" smd custom
			(at 0 0.6604 180)
			(size 0.19685 0.19685)
			(layers "F.Cu" "F.Mask" "F.Paste")
			(net "GND")
			(options
				(clearance outline)
				(anchor circle)
			)
			(primitives
				(gr_poly
					(pts
						(arc
							(start 0.508 -0.2921)
							(mid 0.478242 -0.363942)
							(end 0.4064 -0.3937)
						)
						(arc
							(start -0.4064 -0.3937)
							(mid -0.478242 -0.363942)
							(end -0.508 -0.2921)
						)
						(arc
							(start -0.508 0.2921)
							(mid -0.478242 0.363942)
							(end -0.4064 0.3937)
						)
						(arc
							(start 0.4064 0.3937)
							(mid 0.478242 0.363942)
							(end 0.508 0.2921)
						)
					)
					(width 0)
					(fill yes)
				)
			)
		)
	)
	(footprint ""
		(layer "F.Cu")
		(at 173.355 -57.15 180)
		(property "Reference" "R185"
			(at 0 0 180)
			(layer "F.SilkS")
			(hide yes)
			(effects
				(font
					(size 1.27 1.27)
				)
			)
		)
		(property "Value" "4K7R2F-GP"
			(at 0.064008 -3.993896 180)
			(unlocked yes)
			(layer "F.Fab")
			(hide yes)
			(effects
				(font
					(size 1.016 1.016)
					(thickness 0.1524)
				)
			)
		)
		(property "Device Type" "R402H16"
			(at 0.064008 -5.517896 180)
			(unlocked yes)
			(layer "F.Fab")
			(hide yes)
			(effects
				(font
					(size 1.016 1.016)
					(thickness 0.1524)
				)
			)
		)
		(duplicate_pad_numbers_are_jumpers no)
		(fp_rect
			(start -0.381 0.8382)
			(end 0.381 -0.8382)
			(stroke
				(width 0)
				(type default)
			)
			(fill no)
			(layer "F.CrtYd")
		)
		(fp_rect
			(start -0.381 0.8382)
			(end 0.381 -0.8382)
			(stroke
				(width 0)
				(type default)
			)
			(fill no)
			(layer "F.Fab")
		)
		(pad "1" smd custom
			(at 0 -0.4318 180)
			(size 0.127 0.127)
			(layers "F.Cu" "F.Mask" "F.Paste")
			(net "EEPROM_A2")
			(options
				(clearance outline)
				(anchor circle)
			)
			(primitives
				(gr_poly
					(pts
						(arc
							(start -0.2032 -0.2794)
							(mid -0.239121 -0.264521)
							(end -0.254 -0.2286)
						)
						(arc
							(start -0.254 0.2286)
							(mid -0.239121 0.264521)
							(end -0.2032 0.2794)
						)
						(arc
							(start 0.2032 0.2794)
							(mid 0.239121 0.264521)
							(end 0.254 0.2286)
						)
						(arc
							(start 0.254 -0.2286)
							(mid 0.239121 -0.264521)
							(end 0.2032 -0.2794)
						)
					)
					(width 0)
					(fill yes)
				)
			)
		)
		(pad "2" smd custom
			(at 0 0.4318 180)
			(size 0.127 0.127)
			(layers "F.Cu" "F.Mask" "F.Paste")
			(net "GND")
			(options
				(clearance outline)
				(anchor circle)
			)
			(primitives
				(gr_poly
					(pts
						(arc
							(start -0.2032 -0.2794)
							(mid -0.239121 -0.264521)
							(end -0.254 -0.2286)
						)
						(arc
							(start -0.254 0.2286)
							(mid -0.239121 0.264521)
							(end -0.2032 0.2794)
						)
						(arc
							(start 0.2032 0.2794)
							(mid 0.239121 0.264521)
							(end 0.254 0.2286)
						)
						(arc
							(start 0.254 -0.2286)
							(mid 0.239121 -0.264521)
							(end 0.2032 -0.2794)
						)
					)
					(width 0)
					(fill yes)
				)
			)
		)
	)
	(footprint ""
		(layer "F.Cu")
		(at 198.12 -4.826 90)
		(property "Reference" "R389"
			(at 0 0 90)
			(layer "F.SilkS")
			(hide yes)
			(effects
				(font
					(size 1.27 1.27)
				)
			)
		)
		(property "Value" "4K7R2F-GP"
			(at 0.064008 -3.993896 90)
			(unlocked yes)
			(layer "F.Fab")
			(hide yes)
			(effects
				(font
					(size 1.016 1.016)
					(thickness 0.1524)
				)
			)
		)
		(property "Device Type" "R402H16"
			(at 0.064008 -5.517896 90)
			(unlocked yes)
			(layer "F.Fab")
			(hide yes)
			(effects
				(font
					(size 1.016 1.016)
					(thickness 0.1524)
				)
			)
		)
		(duplicate_pad_numbers_are_jumpers no)
		(fp_rect
			(start -0.381 0.8382)
			(end 0.381 -0.8382)
			(stroke
				(width 0)
				(type default)
			)
			(fill no)
			(layer "F.CrtYd")
		)
		(fp_rect
			(start -0.381 0.8382)
			(end 0.381 -0.8382)
			(stroke
				(width 0)
				(type default)
			)
			(fill no)
			(layer "F.Fab")
		)
		(pad "1" smd custom
			(at 0 -0.4318 90)
			(size 0.127 0.127)
			(layers "F.Cu" "F.Mask" "F.Paste")
			(net "CHB_1_SA1")
			(options
				(clearance outline)
				(anchor circle)
			)
			(primitives
				(gr_poly
					(pts
						(arc
							(start -0.2032 -0.2794)
							(mid -0.239121 -0.264521)
							(end -0.254 -0.2286)
						)
						(arc
							(start -0.254 0.2286)
							(mid -0.239121 0.264521)
							(end -0.2032 0.2794)
						)
						(arc
							(start 0.2032 0.2794)
							(mid 0.239121 0.264521)
							(end 0.254 0.2286)
						)
						(arc
							(start 0.254 -0.2286)
							(mid 0.239121 -0.264521)
							(end 0.2032 -0.2794)
						)
					)
					(width 0)
					(fill yes)
				)
			)
		)
		(pad "2" smd custom
			(at 0 0.4318 90)
			(size 0.127 0.127)
			(layers "F.Cu" "F.Mask" "F.Paste")
			(net "GND")
			(options
				(clearance outline)
				(anchor circle)
			)
			(primitives
				(gr_poly
					(pts
						(arc
							(start -0.2032 -0.2794)
							(mid -0.239121 -0.264521)
							(end -0.254 -0.2286)
						)
						(arc
							(start -0.254 0.2286)
							(mid -0.239121 0.264521)
							(end -0.2032 0.2794)
						)
						(arc
							(start 0.2032 0.2794)
							(mid 0.239121 0.264521)
							(end 0.254 0.2286)
						)
						(arc
							(start 0.254 -0.2286)
							(mid 0.239121 -0.264521)
							(end 0.2032 -0.2794)
						)
					)
					(width 0)
					(fill yes)
				)
			)
		)
	)
	(footprint ""
		(layer "F.Cu")
		(at 128.143 -33.528 90)
		(property "Reference" "R26"
			(at 0 0 90)
			(layer "F.SilkS")
			(hide yes)
			(effects
				(font
					(size 1.27 1.27)
				)
			)
		)
		(property "Value" "4K7R2F-GP"
			(at 0.064008 -3.993896 90)
			(unlocked yes)
			(layer "F.Fab")
			(hide yes)
			(effects
				(font
					(size 1.016 1.016)
					(thickness 0.1524)
				)
			)
		)
		(property "Device Type" "R402H16"
			(at 0.064008 -5.517896 90)
			(unlocked yes)
			(layer "F.Fab")
			(hide yes)
			(effects
				(font
					(size 1.016 1.016)
					(thickness 0.1524)
				)
			)
		)
		(duplicate_pad_numbers_are_jumpers no)
		(fp_rect
			(start -0.381 0.8382)
			(end 0.381 -0.8382)
			(stroke
				(width 0)
				(type default)
			)
			(fill no)
			(layer "F.CrtYd")
		)
		(fp_rect
			(start -0.381 0.8382)
			(end 0.381 -0.8382)
			(stroke
				(width 0)
				(type default)
			)
			(fill no)
			(layer "F.Fab")
		)
		(pad "1" smd custom
			(at 0 -0.4318 90)
			(size 0.127 0.127)
			(layers "F.Cu" "F.Mask" "F.Paste")
			(net "P3V3_STBY")
			(options
				(clearance outline)
				(anchor circle)
			)
			(primitives
				(gr_poly
					(pts
						(arc
							(start -0.2032 -0.2794)
							(mid -0.239121 -0.264521)
							(end -0.254 -0.2286)
						)
						(arc
							(start -0.254 0.2286)
							(mid -0.239121 0.264521)
							(end -0.2032 0.2794)
						)
						(arc
							(start 0.2032 0.2794)
							(mid 0.239121 0.264521)
							(end 0.254 0.2286)
						)
						(arc
							(start 0.254 -0.2286)
							(mid 0.239121 -0.264521)
							(end 0.2032 -0.2794)
						)
					)
					(width 0)
					(fill yes)
				)
			)
		)
		(pad "2" smd custom
			(at 0 0.4318 90)
			(size 0.127 0.127)
			(layers "F.Cu" "F.Mask" "F.Paste")
			(net "SMB_PECI_LV_CLK")
			(options
				(clearance outline)
				(anchor circle)
			)
			(primitives
				(gr_poly
					(pts
						(arc
							(start -0.2032 -0.2794)
							(mid -0.239121 -0.264521)
							(end -0.254 -0.2286)
						)
						(arc
							(start -0.254 0.2286)
							(mid -0.239121 0.264521)
							(end -0.2032 0.2794)
						)
						(arc
							(start 0.2032 0.2794)
							(mid 0.239121 0.264521)
							(end 0.254 0.2286)
						)
						(arc
							(start 0.254 -0.2286)
							(mid 0.239121 -0.264521)
							(end 0.2032 -0.2794)
						)
					)
					(width 0)
					(fill yes)
				)
			)
		)
	)
	(footprint ""
		(layer "F.Cu")
		(at 44.6024 -24.003 90)
		(property "Reference" "TP19"
			(at 0 0 90)
			(layer "F.SilkS")
			(hide yes)
			(effects
				(font
					(size 1.27 1.27)
				)
			)
		)
		(property "Value" "TPAD28-1-GP-U"
			(at 0.0508 -1.9304 90)
			(unlocked yes)
			(layer "F.Fab")
			(hide yes)
			(effects
				(font
					(size 1.016 1.016)
					(thickness 0.1524)
				)
			)
		)
		(property "Device Type" "TPAD28-1-U"
			(at 0.0508 -3.4544 90)
			(unlocked yes)
			(layer "F.Fab")
			(hide yes)
			(effects
				(font
					(size 1.016 1.016)
					(thickness 0.1524)
				)
			)
		)
		(duplicate_pad_numbers_are_jumpers no)
		(fp_poly
			(pts
				(arc
					(start 0 0.3556)
					(mid 0 -0.3556)
					(end 0 0.3556)
				)
			)
			(stroke
				(width 0)
				(type default)
			)
			(fill no)
			(layer "F.CrtYd")
		)
		(fp_poly
			(pts
				(arc
					(start 0 0.9525)
					(mid 0 -0.9525)
					(end 0 0.9525)
				)
			)
			(stroke
				(width 0)
				(type default)
			)
			(fill no)
			(layer "F.Fab")
		)
		(pad "1" smd circle
			(at 0 0 90)
			(size 0.7112 0.7112)
			(layers "F.Cu" "F.Mask" "F.Paste")
			(net "TP_XDP_DFX_PORT_CLK1")
		)
	)
	(footprint ""
		(layer "F.Cu")
		(at 203.962 -68.7324 90)
		(property "Reference" "PC178"
			(at 0 0 90)
			(layer "F.SilkS")
			(hide yes)
			(effects
				(font
					(size 1.27 1.27)
				)
			)
		)
		(property "Value" "SC10U6D3V3MX-GP"
			(at -0.0254 -2.0193 90)
			(unlocked yes)
			(layer "F.Fab")
			(hide yes)
			(effects
				(font
					(size 1.016 1.016)
					(thickness 0.1524)
				)
			)
		)
		(property "Device Type" "C603H38"
			(at -0.0254 -3.5433 90)
			(unlocked yes)
			(layer "F.Fab")
			(hide yes)
			(effects
				(font
					(size 1.016 1.016)
					(thickness 0.1524)
				)
			)
		)
		(duplicate_pad_numbers_are_jumpers no)
		(fp_line
			(start -0.4064 0)
			(end 0.4064 0)
			(stroke
				(width 0.2286)
				(type default)
			)
			(layer "F.SilkS")
		)
		(fp_rect
			(start -0.635 1.1811)
			(end 0.635 -1.1811)
			(stroke
				(width 0)
				(type default)
			)
			(fill no)
			(layer "F.CrtYd")
		)
		(fp_rect
			(start -0.635 1.1811)
			(end 0.635 -1.1811)
			(stroke
				(width 0)
				(type default)
			)
			(fill no)
			(layer "F.Fab")
		)
		(pad "1" smd custom
			(at 0 -0.6604 90)
			(size 0.19685 0.19685)
			(layers "F.Cu" "F.Mask" "F.Paste")
			(net "PV_VDDR")
			(options
				(clearance outline)
				(anchor circle)
			)
			(primitives
				(gr_poly
					(pts
						(arc
							(start 0.508 -0.2921)
							(mid 0.478242 -0.363942)
							(end 0.4064 -0.3937)
						)
						(arc
							(start -0.4064 -0.3937)
							(mid -0.478242 -0.363942)
							(end -0.508 -0.2921)
						)
						(arc
							(start -0.508 0.2921)
							(mid -0.478242 0.363942)
							(end -0.4064 0.3937)
						)
						(arc
							(start 0.4064 0.3937)
							(mid 0.478242 0.363942)
							(end 0.508 0.2921)
						)
					)
					(width 0)
					(fill yes)
				)
			)
		)
		(pad "2" smd custom
			(at 0 0.6604 90)
			(size 0.19685 0.19685)
			(layers "F.Cu" "F.Mask" "F.Paste")
			(net "GND")
			(options
				(clearance outline)
				(anchor circle)
			)
			(primitives
				(gr_poly
					(pts
						(arc
							(start 0.508 -0.2921)
							(mid 0.478242 -0.363942)
							(end 0.4064 -0.3937)
						)
						(arc
							(start -0.4064 -0.3937)
							(mid -0.478242 -0.363942)
							(end -0.508 -0.2921)
						)
						(arc
							(start -0.508 0.2921)
							(mid -0.478242 0.363942)
							(end -0.4064 0.3937)
						)
						(arc
							(start 0.4064 0.3937)
							(mid 0.478242 0.363942)
							(end 0.508 0.2921)
						)
					)
					(width 0)
					(fill yes)
				)
			)
		)
	)
	(footprint ""
		(layer "F.Cu")
		(at 20.066 -33.2486 180)
		(property "Reference" "PR198"
			(at 0 0 180)
			(layer "F.SilkS")
			(hide yes)
			(effects
				(font
					(size 1.27 1.27)
				)
			)
		)
		(property "Value" "44K2R2F-1-GP"
			(at 1.7907 -1.1176 180)
			(unlocked yes)
			(layer "F.Fab")
			(hide yes)
			(effects
				(font
					(size 1.016 1.016)
					(thickness 0.1524)
				)
			)
		)
		(property "Device Type" "R402H16"
			(at 1.7907 -2.6416 180)
			(unlocked yes)
			(layer "F.Fab")
			(hide yes)
			(effects
				(font
					(size 1.016 1.016)
					(thickness 0.1524)
				)
			)
		)
		(duplicate_pad_numbers_are_jumpers no)
		(fp_rect
			(start -0.381 0.8382)
			(end 0.381 -0.8382)
			(stroke
				(width 0)
				(type default)
			)
			(fill no)
			(layer "F.CrtYd")
		)
		(fp_rect
			(start -0.381 0.8382)
			(end 0.381 -0.8382)
			(stroke
				(width 0)
				(type default)
			)
			(fill no)
			(layer "F.Fab")
		)
		(pad "1" smd custom
			(at 0 -0.4318 180)
			(size 0.127 0.127)
			(layers "F.Cu" "F.Mask" "F.Paste")
			(net "P3V3_STBY_VFB")
			(options
				(clearance outline)
				(anchor circle)
			)
			(primitives
				(gr_poly
					(pts
						(arc
							(start -0.2032 -0.2794)
							(mid -0.239121 -0.264521)
							(end -0.254 -0.2286)
						)
						(arc
							(start -0.254 0.2286)
							(mid -0.239121 0.264521)
							(end -0.2032 0.2794)
						)
						(arc
							(start 0.2032 0.2794)
							(mid 0.239121 0.264521)
							(end 0.254 0.2286)
						)
						(arc
							(start 0.254 -0.2286)
							(mid 0.239121 -0.264521)
							(end 0.2032 -0.2794)
						)
					)
					(width 0)
					(fill yes)
				)
			)
		)
		(pad "2" smd custom
			(at 0 0.4318 180)
			(size 0.127 0.127)
			(layers "F.Cu" "F.Mask" "F.Paste")
			(net "P3V3_STBY_VFB_R")
			(options
				(clearance outline)
				(anchor circle)
			)
			(primitives
				(gr_poly
					(pts
						(arc
							(start -0.2032 -0.2794)
							(mid -0.239121 -0.264521)
							(end -0.254 -0.2286)
						)
						(arc
							(start -0.254 0.2286)
							(mid -0.239121 0.264521)
							(end -0.2032 0.2794)
						)
						(arc
							(start 0.2032 0.2794)
							(mid 0.239121 0.264521)
							(end 0.254 0.2286)
						)
						(arc
							(start 0.254 -0.2286)
							(mid 0.239121 -0.264521)
							(end 0.2032 -0.2794)
						)
					)
					(width 0)
					(fill yes)
				)
			)
		)
	)
	(footprint ""
		(layer "F.Cu")
		(at 183.388 -53.848 180)
		(property "Reference" "R202"
			(at 0 0 180)
			(layer "F.SilkS")
			(hide yes)
			(effects
				(font
					(size 1.27 1.27)
				)
			)
		)
		(property "Value" "2D2R2J-GP"
			(at 0.064008 -3.993896 180)
			(unlocked yes)
			(layer "F.Fab")
			(hide yes)
			(effects
				(font
					(size 1.016 1.016)
					(thickness 0.1524)
				)
			)
		)
		(property "Device Type" "R402H16"
			(at 0.064008 -5.517896 180)
			(unlocked yes)
			(layer "F.Fab")
			(hide yes)
			(effects
				(font
					(size 1.016 1.016)
					(thickness 0.1524)
				)
			)
		)
		(duplicate_pad_numbers_are_jumpers no)
		(fp_rect
			(start -0.381 0.8382)
			(end 0.381 -0.8382)
			(stroke
				(width 0)
				(type default)
			)
			(fill no)
			(layer "F.CrtYd")
		)
		(fp_rect
			(start -0.381 0.8382)
			(end 0.381 -0.8382)
			(stroke
				(width 0)
				(type default)
			)
			(fill no)
			(layer "F.Fab")
		)
		(pad "1" smd custom
			(at 0 -0.4318 180)
			(size 0.127 0.127)
			(layers "F.Cu" "F.Mask" "F.Paste")
			(net "PV_VDDR_VREF_A_FB")
			(options
				(clearance outline)
				(anchor circle)
			)
			(primitives
				(gr_poly
					(pts
						(arc
							(start -0.2032 -0.2794)
							(mid -0.239121 -0.264521)
							(end -0.254 -0.2286)
						)
						(arc
							(start -0.254 0.2286)
							(mid -0.239121 0.264521)
							(end -0.2032 0.2794)
						)
						(arc
							(start 0.2032 0.2794)
							(mid 0.239121 0.264521)
							(end 0.254 0.2286)
						)
						(arc
							(start 0.254 -0.2286)
							(mid 0.239121 -0.264521)
							(end 0.2032 -0.2794)
						)
					)
					(width 0)
					(fill yes)
				)
			)
		)
		(pad "2" smd custom
			(at 0 0.4318 180)
			(size 0.127 0.127)
			(layers "F.Cu" "F.Mask" "F.Paste")
			(net "PV_VDDR_VREF_A")
			(options
				(clearance outline)
				(anchor circle)
			)
			(primitives
				(gr_poly
					(pts
						(arc
							(start -0.2032 -0.2794)
							(mid -0.239121 -0.264521)
							(end -0.254 -0.2286)
						)
						(arc
							(start -0.254 0.2286)
							(mid -0.239121 0.264521)
							(end -0.2032 0.2794)
						)
						(arc
							(start 0.2032 0.2794)
							(mid 0.239121 0.264521)
							(end 0.254 0.2286)
						)
						(arc
							(start 0.254 -0.2286)
							(mid 0.239121 -0.264521)
							(end 0.2032 -0.2794)
						)
					)
					(width 0)
					(fill yes)
				)
			)
		)
	)
	(footprint ""
		(layer "F.Cu")
		(at 183.261 -22.86 90)
		(property "Reference" "PR60"
			(at 0 0 90)
			(layer "F.SilkS")
			(hide yes)
			(effects
				(font
					(size 1.27 1.27)
				)
			)
		)
		(property "Value" "10R3F-GP"
			(at -0.0254 -2.5146 90)
			(unlocked yes)
			(layer "F.Fab")
			(hide yes)
			(effects
				(font
					(size 1.016 1.016)
					(thickness 0.1524)
				)
			)
		)
		(property "Device Type" "R603H22"
			(at -0.0254 -4.0386 90)
			(unlocked yes)
			(layer "F.Fab")
			(hide yes)
			(effects
				(font
					(size 1.016 1.016)
					(thickness 0.1524)
				)
			)
		)
		(duplicate_pad_numbers_are_jumpers no)
		(fp_line
			(start 0.4318 0)
			(end 0.2032 0)
			(stroke
				(width 0.2032)
				(type default)
			)
			(layer "F.SilkS")
		)
		(fp_line
			(start -0.2032 0)
			(end -0.4191 0)
			(stroke
				(width 0.2032)
				(type default)
			)
			(layer "F.SilkS")
		)
		(fp_rect
			(start -0.635 1.1811)
			(end 0.635 -1.1811)
			(stroke
				(width 0)
				(type default)
			)
			(fill no)
			(layer "F.CrtYd")
		)
		(fp_rect
			(start -0.635 1.1811)
			(end 0.635 -1.1811)
			(stroke
				(width 0)
				(type default)
			)
			(fill no)
			(layer "F.Fab")
		)
		(pad "1" smd custom
			(at 0 -0.6604 90)
			(size 0.19685 0.19685)
			(layers "F.Cu" "F.Mask" "F.Paste")
			(net "P3V3_STBY")
			(options
				(clearance outline)
				(anchor circle)
			)
			(primitives
				(gr_poly
					(pts
						(arc
							(start 0.508 -0.2921)
							(mid 0.478242 -0.363942)
							(end 0.4064 -0.3937)
						)
						(arc
							(start -0.4064 -0.3937)
							(mid -0.478242 -0.363942)
							(end -0.508 -0.2921)
						)
						(arc
							(start -0.508 0.2921)
							(mid -0.478242 0.363942)
							(end -0.4064 0.3937)
						)
						(arc
							(start 0.4064 0.3937)
							(mid 0.478242 0.363942)
							(end 0.508 0.2921)
						)
					)
					(width 0)
					(fill yes)
				)
			)
		)
		(pad "2" smd custom
			(at 0 0.6604 90)
			(size 0.19685 0.19685)
			(layers "F.Cu" "F.Mask" "F.Paste")
			(net "PV_VTT_DDR_B_VIN")
			(options
				(clearance outline)
				(anchor circle)
			)
			(primitives
				(gr_poly
					(pts
						(arc
							(start 0.508 -0.2921)
							(mid 0.478242 -0.363942)
							(end 0.4064 -0.3937)
						)
						(arc
							(start -0.4064 -0.3937)
							(mid -0.478242 -0.363942)
							(end -0.508 -0.2921)
						)
						(arc
							(start -0.508 0.2921)
							(mid -0.478242 0.363942)
							(end -0.4064 0.3937)
						)
						(arc
							(start 0.4064 0.3937)
							(mid 0.478242 0.363942)
							(end 0.508 0.2921)
						)
					)
					(width 0)
					(fill yes)
				)
			)
		)
	)
	(footprint ""
		(layer "F.Cu")
		(at 22.352 -66.421 90)
		(property "Reference" "PC10"
			(at 0 0 90)
			(layer "F.SilkS")
			(hide yes)
			(effects
				(font
					(size 1.27 1.27)
				)
			)
		)
		(property "Value" "SC220P50V2KX-3GP"
			(at 1.8923 -1.2065 90)
			(unlocked yes)
			(layer "F.Fab")
			(hide yes)
			(effects
				(font
					(size 1.016 1.016)
					(thickness 0.1524)
				)
			)
		)
		(property "Device Type" "C402H22"
			(at 1.8923 -2.7305 90)
			(unlocked yes)
			(layer "F.Fab")
			(hide yes)
			(effects
				(font
					(size 1.016 1.016)
					(thickness 0.1524)
				)
			)
		)
		(duplicate_pad_numbers_are_jumpers no)
		(fp_rect
			(start -0.381 0.7366)
			(end 0.381 -0.7366)
			(stroke
				(width 0)
				(type default)
			)
			(fill no)
			(layer "F.CrtYd")
		)
		(fp_rect
			(start -0.381 0.7366)
			(end 0.381 -0.7366)
			(stroke
				(width 0)
				(type default)
			)
			(fill no)
			(layer "F.Fab")
		)
		(pad "1" smd custom
			(at 0 -0.4572 90)
			(size 0.1143 0.1143)
			(layers "F.Cu" "F.Mask" "F.Paste")
			(net "VR_PVNN_ISUMN")
			(options
				(clearance outline)
				(anchor circle)
			)
			(primitives
				(gr_poly
					(pts
						(arc
							(start -0.254 -0.1778)
							(mid -0.239121 -0.213721)
							(end -0.2032 -0.2286)
						)
						(arc
							(start 0.2032 -0.2286)
							(mid 0.239121 -0.213721)
							(end 0.254 -0.1778)
						)
						(arc
							(start 0.254 0.1778)
							(mid 0.239121 0.213721)
							(end 0.2032 0.2286)
						)
						(arc
							(start -0.2032 0.2286)
							(mid -0.239121 0.213721)
							(end -0.254 0.1778)
						)
					)
					(width 0)
					(fill yes)
				)
			)
		)
		(pad "2" smd custom
			(at 0 0.4572 90)
			(size 0.1143 0.1143)
			(layers "F.Cu" "F.Mask" "F.Paste")
			(net "VR_PVNN_ISUMN_RC")
			(options
				(clearance outline)
				(anchor circle)
			)
			(primitives
				(gr_poly
					(pts
						(arc
							(start -0.254 -0.1778)
							(mid -0.239121 -0.213721)
							(end -0.2032 -0.2286)
						)
						(arc
							(start 0.2032 -0.2286)
							(mid 0.239121 -0.213721)
							(end 0.254 -0.1778)
						)
						(arc
							(start 0.254 0.1778)
							(mid 0.239121 0.213721)
							(end 0.2032 0.2286)
						)
						(arc
							(start -0.2032 0.2286)
							(mid -0.239121 0.213721)
							(end -0.254 0.1778)
						)
					)
					(width 0)
					(fill yes)
				)
			)
		)
	)
	(footprint ""
		(layer "F.Cu")
		(at 73.66 -36.576 90)
		(property "Reference" "R103"
			(at 0 0 90)
			(layer "F.SilkS")
			(hide yes)
			(effects
				(font
					(size 1.27 1.27)
				)
			)
		)
		(property "Value" "1KR2F-3-GP"
			(at 0.064008 -3.993896 90)
			(unlocked yes)
			(layer "F.Fab")
			(hide yes)
			(effects
				(font
					(size 1.016 1.016)
					(thickness 0.1524)
				)
			)
		)
		(property "Device Type" "R402H16"
			(at 0.064008 -5.517896 90)
			(unlocked yes)
			(layer "F.Fab")
			(hide yes)
			(effects
				(font
					(size 1.016 1.016)
					(thickness 0.1524)
				)
			)
		)
		(duplicate_pad_numbers_are_jumpers no)
		(fp_rect
			(start -0.381 0.8382)
			(end 0.381 -0.8382)
			(stroke
				(width 0)
				(type default)
			)
			(fill no)
			(layer "F.CrtYd")
		)
		(fp_rect
			(start -0.381 0.8382)
			(end 0.381 -0.8382)
			(stroke
				(width 0)
				(type default)
			)
			(fill no)
			(layer "F.Fab")
		)
		(pad "1" smd custom
			(at 0 -0.4318 90)
			(size 0.127 0.127)
			(layers "F.Cu" "F.Mask" "F.Paste")
			(net "P3V3_CPU")
			(options
				(clearance outline)
				(anchor circle)
			)
			(primitives
				(gr_poly
					(pts
						(arc
							(start -0.2032 -0.2794)
							(mid -0.239121 -0.264521)
							(end -0.254 -0.2286)
						)
						(arc
							(start -0.254 0.2286)
							(mid -0.239121 0.264521)
							(end -0.2032 0.2794)
						)
						(arc
							(start 0.2032 0.2794)
							(mid 0.239121 0.264521)
							(end 0.254 0.2286)
						)
						(arc
							(start 0.254 -0.2286)
							(mid 0.239121 -0.264521)
							(end 0.2032 -0.2794)
						)
					)
					(width 0)
					(fill yes)
				)
			)
		)
		(pad "2" smd custom
			(at 0 0.4318 90)
			(size 0.127 0.127)
			(layers "F.Cu" "F.Mask" "F.Paste")
			(net "PMU_WAKE#")
			(options
				(clearance outline)
				(anchor circle)
			)
			(primitives
				(gr_poly
					(pts
						(arc
							(start -0.2032 -0.2794)
							(mid -0.239121 -0.264521)
							(end -0.254 -0.2286)
						)
						(arc
							(start -0.254 0.2286)
							(mid -0.239121 0.264521)
							(end -0.2032 0.2794)
						)
						(arc
							(start 0.2032 0.2794)
							(mid 0.239121 0.264521)
							(end 0.254 0.2286)
						)
						(arc
							(start 0.254 -0.2286)
							(mid 0.239121 -0.264521)
							(end 0.2032 -0.2794)
						)
					)
					(width 0)
					(fill yes)
				)
			)
		)
	)
	(footprint ""
		(layer "F.Cu")
		(at 88.011 -15.113)
		(property "Reference" "PC196"
			(at 0 0 0)
			(layer "F.SilkS")
			(hide yes)
			(effects
				(font
					(size 1.27 1.27)
				)
			)
		)
		(property "Value" "SC10U6D3V5KX-4GP"
			(at -0.0762 -6.1214 0)
			(unlocked yes)
			(layer "F.Fab")
			(hide yes)
			(effects
				(font
					(size 1.016 1.016)
					(thickness 0.1524)
				)
			)
		)
		(property "Device Type" "C805H58"
			(at -0.0762 -8.1534 0)
			(unlocked yes)
			(layer "F.Fab")
			(hide yes)
			(effects
				(font
					(size 1.016 1.016)
					(thickness 0.1524)
				)
			)
		)
		(duplicate_pad_numbers_are_jumpers no)
		(fp_line
			(start 0.6096 0)
			(end -0.6096 0)
			(stroke
				(width 0.3048)
				(type default)
			)
			(layer "F.SilkS")
		)
		(fp_poly
			(pts
				(xy -0.9017 1.4351) (xy 0.9017 1.4351) (xy 0.9017 -1.4351) (xy -0.9017 -1.4351)
			)
			(stroke
				(width 0)
				(type default)
			)
			(fill no)
			(layer "F.CrtYd")
		)
		(fp_poly
			(pts
				(xy 0.9017 1.4351) (xy 0.9017 -1.4351) (xy -0.9017 -1.4351) (xy -0.9017 1.4351)
			)
			(stroke
				(width 0)
				(type default)
			)
			(fill no)
			(layer "F.Fab")
		)
		(pad "1" smd rect
			(at 0 -0.8382)
			(size 1.5494 0.9398)
			(layers "F.Cu" "F.Mask" "F.Paste")
			(net "TPS74801_1V35_OUT")
		)
		(pad "2" smd rect
			(at 0 0.8382)
			(size 1.5494 0.9398)
			(layers "F.Cu" "F.Mask" "F.Paste")
			(net "GND")
		)
	)
	(footprint ""
		(layer "F.Cu")
		(at 167.894 -26.67 -90)
		(property "Reference" "PC96"
			(at 0 0 270)
			(layer "F.SilkS")
			(hide yes)
			(effects
				(font
					(size 1.27 1.27)
				)
			)
		)
		(property "Value" "SC22U6D3V5MX-2GP"
			(at -0.0762 -6.1214 270)
			(unlocked yes)
			(layer "F.Fab")
			(hide yes)
			(effects
				(font
					(size 1.016 1.016)
					(thickness 0.1524)
				)
			)
		)
		(property "Device Type" "C805H58"
			(at -0.0762 -8.1534 270)
			(unlocked yes)
			(layer "F.Fab")
			(hide yes)
			(effects
				(font
					(size 1.016 1.016)
					(thickness 0.1524)
				)
			)
		)
		(duplicate_pad_numbers_are_jumpers no)
		(fp_line
			(start 0.6096 0)
			(end -0.6096 0)
			(stroke
				(width 0.3048)
				(type default)
			)
			(layer "F.SilkS")
		)
		(fp_poly
			(pts
				(xy -0.9017 1.4351) (xy 0.9017 1.4351) (xy 0.9017 -1.4351) (xy -0.9017 -1.4351)
			)
			(stroke
				(width 0)
				(type default)
			)
			(fill no)
			(layer "F.CrtYd")
		)
		(fp_poly
			(pts
				(xy 0.9017 1.4351) (xy 0.9017 -1.4351) (xy -0.9017 -1.4351) (xy -0.9017 1.4351)
			)
			(stroke
				(width 0)
				(type default)
			)
			(fill no)
			(layer "F.Fab")
		)
		(pad "1" smd rect
			(at 0 -0.8382 270)
			(size 1.5494 0.9398)
			(layers "F.Cu" "F.Mask" "F.Paste")
			(net "P1V2_STBY_LDO_OUT2")
		)
		(pad "2" smd rect
			(at 0 0.8382 270)
			(size 1.5494 0.9398)
			(layers "F.Cu" "F.Mask" "F.Paste")
			(net "GND")
		)
	)
	(footprint ""
		(layer "F.Cu")
		(at 109.601 -57.912 90)
		(property "Reference" "R23"
			(at 0 0 90)
			(layer "F.SilkS")
			(hide yes)
			(effects
				(font
					(size 1.27 1.27)
				)
			)
		)
		(property "Value" "100R2F-L1-GP-U"
			(at 0.064008 -3.993896 90)
			(unlocked yes)
			(layer "F.Fab")
			(hide yes)
			(effects
				(font
					(size 1.016 1.016)
					(thickness 0.1524)
				)
			)
		)
		(property "Device Type" "R402H14"
			(at 0.064008 -5.517896 90)
			(unlocked yes)
			(layer "F.Fab")
			(hide yes)
			(effects
				(font
					(size 1.016 1.016)
					(thickness 0.1524)
				)
			)
		)
		(duplicate_pad_numbers_are_jumpers no)
		(fp_rect
			(start -0.381 0.8382)
			(end 0.381 -0.8382)
			(stroke
				(width 0)
				(type default)
			)
			(fill no)
			(layer "F.CrtYd")
		)
		(fp_rect
			(start -0.381 0.8382)
			(end 0.381 -0.8382)
			(stroke
				(width 0)
				(type default)
			)
			(fill no)
			(layer "F.Fab")
		)
		(pad "1" smd custom
			(at 0 -0.4318 90)
			(size 0.127 0.127)
			(layers "F.Cu" "F.Mask" "F.Paste")
			(net "M_A_MON1_P")
			(options
				(clearance outline)
				(anchor circle)
			)
			(primitives
				(gr_poly
					(pts
						(arc
							(start -0.2032 -0.2794)
							(mid -0.239121 -0.264521)
							(end -0.254 -0.2286)
						)
						(arc
							(start -0.254 0.2286)
							(mid -0.239121 0.264521)
							(end -0.2032 0.2794)
						)
						(arc
							(start 0.2032 0.2794)
							(mid 0.239121 0.264521)
							(end 0.254 0.2286)
						)
						(arc
							(start 0.254 -0.2286)
							(mid 0.239121 -0.264521)
							(end 0.2032 -0.2794)
						)
					)
					(width 0)
					(fill yes)
				)
			)
		)
		(pad "2" smd custom
			(at 0 0.4318 90)
			(size 0.127 0.127)
			(layers "F.Cu" "F.Mask" "F.Paste")
			(net "M_A_MON1_N")
			(options
				(clearance outline)
				(anchor circle)
			)
			(primitives
				(gr_poly
					(pts
						(arc
							(start -0.2032 -0.2794)
							(mid -0.239121 -0.264521)
							(end -0.254 -0.2286)
						)
						(arc
							(start -0.254 0.2286)
							(mid -0.239121 0.264521)
							(end -0.2032 0.2794)
						)
						(arc
							(start 0.2032 0.2794)
							(mid 0.239121 0.264521)
							(end 0.254 0.2286)
						)
						(arc
							(start 0.254 -0.2286)
							(mid 0.239121 -0.264521)
							(end 0.2032 -0.2794)
						)
					)
					(width 0)
					(fill yes)
				)
			)
		)
	)
	(footprint ""
		(layer "F.Cu")
		(at 112.1664 -64.2874 180)
		(property "Reference" "R17"
			(at 0 0 180)
			(layer "F.SilkS")
			(hide yes)
			(effects
				(font
					(size 1.27 1.27)
				)
			)
		)
		(property "Value" "20KR2F-L-GP"
			(at 0.064008 -3.993896 180)
			(unlocked yes)
			(layer "F.Fab")
			(hide yes)
			(effects
				(font
					(size 1.016 1.016)
					(thickness 0.1524)
				)
			)
		)
		(property "Device Type" "R402H16"
			(at 0.064008 -5.517896 180)
			(unlocked yes)
			(layer "F.Fab")
			(hide yes)
			(effects
				(font
					(size 1.016 1.016)
					(thickness 0.1524)
				)
			)
		)
		(duplicate_pad_numbers_are_jumpers no)
		(fp_rect
			(start -0.381 0.8382)
			(end 0.381 -0.8382)
			(stroke
				(width 0)
				(type default)
			)
			(fill no)
			(layer "F.CrtYd")
		)
		(fp_rect
			(start -0.381 0.8382)
			(end 0.381 -0.8382)
			(stroke
				(width 0)
				(type default)
			)
			(fill no)
			(layer "F.Fab")
		)
		(pad "1" smd custom
			(at 0 -0.4318 180)
			(size 0.127 0.127)
			(layers "F.Cu" "F.Mask" "F.Paste")
			(net "CLK_GEN_PG")
			(options
				(clearance outline)
				(anchor circle)
			)
			(primitives
				(gr_poly
					(pts
						(arc
							(start -0.2032 -0.2794)
							(mid -0.239121 -0.264521)
							(end -0.254 -0.2286)
						)
						(arc
							(start -0.254 0.2286)
							(mid -0.239121 0.264521)
							(end -0.2032 0.2794)
						)
						(arc
							(start 0.2032 0.2794)
							(mid 0.239121 0.264521)
							(end 0.254 0.2286)
						)
						(arc
							(start 0.254 -0.2286)
							(mid 0.239121 -0.264521)
							(end 0.2032 -0.2794)
						)
					)
					(width 0)
					(fill yes)
				)
			)
		)
		(pad "2" smd custom
			(at 0 0.4318 180)
			(size 0.127 0.127)
			(layers "F.Cu" "F.Mask" "F.Paste")
			(net "CLK_GEN_INA_PG")
			(options
				(clearance outline)
				(anchor circle)
			)
			(primitives
				(gr_poly
					(pts
						(arc
							(start -0.2032 -0.2794)
							(mid -0.239121 -0.264521)
							(end -0.254 -0.2286)
						)
						(arc
							(start -0.254 0.2286)
							(mid -0.239121 0.264521)
							(end -0.2032 0.2794)
						)
						(arc
							(start 0.2032 0.2794)
							(mid 0.239121 0.264521)
							(end 0.254 0.2286)
						)
						(arc
							(start 0.254 -0.2286)
							(mid 0.239121 -0.264521)
							(end 0.2032 -0.2794)
						)
					)
					(width 0)
					(fill yes)
				)
			)
		)
	)
	(footprint ""
		(layer "F.Cu")
		(at 113.792 -64.262)
		(property "Reference" "C5"
			(at 0 0 0)
			(layer "F.SilkS")
			(hide yes)
			(effects
				(font
					(size 1.27 1.27)
				)
			)
		)
		(property "Value" "SC2D2U10V2KX-GP"
			(at 1.8923 -1.2065 0)
			(unlocked yes)
			(layer "F.Fab")
			(hide yes)
			(effects
				(font
					(size 1.016 1.016)
					(thickness 0.1524)
				)
			)
		)
		(property "Device Type" "C402H22"
			(at 1.8923 -2.7305 0)
			(unlocked yes)
			(layer "F.Fab")
			(hide yes)
			(effects
				(font
					(size 1.016 1.016)
					(thickness 0.1524)
				)
			)
		)
		(duplicate_pad_numbers_are_jumpers no)
		(fp_rect
			(start -0.381 0.7366)
			(end 0.381 -0.7366)
			(stroke
				(width 0)
				(type default)
			)
			(fill no)
			(layer "F.CrtYd")
		)
		(fp_rect
			(start -0.381 0.7366)
			(end 0.381 -0.7366)
			(stroke
				(width 0)
				(type default)
			)
			(fill no)
			(layer "F.Fab")
		)
		(pad "1" smd custom
			(at 0 -0.4572)
			(size 0.1143 0.1143)
			(layers "F.Cu" "F.Mask" "F.Paste")
			(net "CLK_GEN_INA_PG")
			(options
				(clearance outline)
				(anchor circle)
			)
			(primitives
				(gr_poly
					(pts
						(arc
							(start -0.254 -0.1778)
							(mid -0.239121 -0.213721)
							(end -0.2032 -0.2286)
						)
						(arc
							(start 0.2032 -0.2286)
							(mid 0.239121 -0.213721)
							(end 0.254 -0.1778)
						)
						(arc
							(start 0.254 0.1778)
							(mid 0.239121 0.213721)
							(end 0.2032 0.2286)
						)
						(arc
							(start -0.2032 0.2286)
							(mid -0.239121 0.213721)
							(end -0.254 0.1778)
						)
					)
					(width 0)
					(fill yes)
				)
			)
		)
		(pad "2" smd custom
			(at 0 0.4572)
			(size 0.1143 0.1143)
			(layers "F.Cu" "F.Mask" "F.Paste")
			(net "GND")
			(options
				(clearance outline)
				(anchor circle)
			)
			(primitives
				(gr_poly
					(pts
						(arc
							(start -0.254 -0.1778)
							(mid -0.239121 -0.213721)
							(end -0.2032 -0.2286)
						)
						(arc
							(start 0.2032 -0.2286)
							(mid 0.239121 -0.213721)
							(end 0.254 -0.1778)
						)
						(arc
							(start 0.254 0.1778)
							(mid 0.239121 0.213721)
							(end 0.2032 0.2286)
						)
						(arc
							(start -0.2032 0.2286)
							(mid -0.239121 0.213721)
							(end -0.254 0.1778)
						)
					)
					(width 0)
					(fill yes)
				)
			)
		)
	)
	(footprint ""
		(layer "F.Cu")
		(at 194.183 -38.735 180)
		(property "Reference" "PC93"
			(at 0 0 180)
			(layer "F.SilkS")
			(hide yes)
			(effects
				(font
					(size 1.27 1.27)
				)
			)
		)
		(property "Value" "SC1U16V3KX-5GP"
			(at -0.0254 -2.0193 180)
			(unlocked yes)
			(layer "F.Fab")
			(hide yes)
			(effects
				(font
					(size 1.016 1.016)
					(thickness 0.1524)
				)
			)
		)
		(property "Device Type" "C603H36"
			(at -0.0254 -3.5433 180)
			(unlocked yes)
			(layer "F.Fab")
			(hide yes)
			(effects
				(font
					(size 1.016 1.016)
					(thickness 0.1524)
				)
			)
		)
		(duplicate_pad_numbers_are_jumpers no)
		(fp_line
			(start -0.4064 0)
			(end 0.4064 0)
			(stroke
				(width 0.2286)
				(type default)
			)
			(layer "F.SilkS")
		)
		(fp_rect
			(start -0.635 1.1811)
			(end 0.635 -1.1811)
			(stroke
				(width 0)
				(type default)
			)
			(fill no)
			(layer "F.CrtYd")
		)
		(fp_rect
			(start -0.635 1.1811)
			(end 0.635 -1.1811)
			(stroke
				(width 0)
				(type default)
			)
			(fill no)
			(layer "F.Fab")
		)
		(pad "1" smd custom
			(at 0 -0.6604 180)
			(size 0.19685 0.19685)
			(layers "F.Cu" "F.Mask" "F.Paste")
			(net "VR_PVDDR_A_VDDP")
			(options
				(clearance outline)
				(anchor circle)
			)
			(primitives
				(gr_poly
					(pts
						(arc
							(start 0.508 -0.2921)
							(mid 0.478242 -0.363942)
							(end 0.4064 -0.3937)
						)
						(arc
							(start -0.4064 -0.3937)
							(mid -0.478242 -0.363942)
							(end -0.508 -0.2921)
						)
						(arc
							(start -0.508 0.2921)
							(mid -0.478242 0.363942)
							(end -0.4064 0.3937)
						)
						(arc
							(start 0.4064 0.3937)
							(mid 0.478242 0.363942)
							(end 0.508 0.2921)
						)
					)
					(width 0)
					(fill yes)
				)
			)
		)
		(pad "2" smd custom
			(at 0 0.6604 180)
			(size 0.19685 0.19685)
			(layers "F.Cu" "F.Mask" "F.Paste")
			(net "GND")
			(options
				(clearance outline)
				(anchor circle)
			)
			(primitives
				(gr_poly
					(pts
						(arc
							(start 0.508 -0.2921)
							(mid 0.478242 -0.363942)
							(end 0.4064 -0.3937)
						)
						(arc
							(start -0.4064 -0.3937)
							(mid -0.478242 -0.363942)
							(end -0.508 -0.2921)
						)
						(arc
							(start -0.508 0.2921)
							(mid -0.478242 0.363942)
							(end -0.4064 0.3937)
						)
						(arc
							(start 0.4064 0.3937)
							(mid 0.478242 0.363942)
							(end 0.508 0.2921)
						)
					)
					(width 0)
					(fill yes)
				)
			)
		)
	)
	(footprint ""
		(layer "F.Cu")
		(at 183.261 -21.59 -90)
		(property "Reference" "PC41"
			(at 0 0 270)
			(layer "F.SilkS")
			(hide yes)
			(effects
				(font
					(size 1.27 1.27)
				)
			)
		)
		(property "Value" "SC4D7U10V3KX-GP"
			(at 0 -2.8194 270)
			(unlocked yes)
			(layer "F.Fab")
			(hide yes)
			(effects
				(font
					(size 1.016 1.016)
					(thickness 0.1524)
				)
			)
		)
		(property "Device Type" "C603H36"
			(at 0 -4.3434 270)
			(unlocked yes)
			(layer "F.Fab")
			(hide yes)
			(effects
				(font
					(size 1.016 1.016)
					(thickness 0.1524)
				)
			)
		)
		(duplicate_pad_numbers_are_jumpers no)
		(fp_line
			(start -0.4064 0)
			(end 0.4064 0)
			(stroke
				(width 0.2286)
				(type default)
			)
			(layer "F.SilkS")
		)
		(fp_rect
			(start -0.635 1.1811)
			(end 0.635 -1.1811)
			(stroke
				(width 0)
				(type default)
			)
			(fill no)
			(layer "F.CrtYd")
		)
		(fp_rect
			(start -0.635 1.1811)
			(end 0.635 -1.1811)
			(stroke
				(width 0)
				(type default)
			)
			(fill no)
			(layer "F.Fab")
		)
		(pad "1" smd custom
			(at 0 -0.6604 270)
			(size 0.19685 0.19685)
			(layers "F.Cu" "F.Mask" "F.Paste")
			(net "PV_VTT_DDR_B_VIN")
			(options
				(clearance outline)
				(anchor circle)
			)
			(primitives
				(gr_poly
					(pts
						(arc
							(start 0.508 -0.2921)
							(mid 0.478242 -0.363942)
							(end 0.4064 -0.3937)
						)
						(arc
							(start -0.4064 -0.3937)
							(mid -0.478242 -0.363942)
							(end -0.508 -0.2921)
						)
						(arc
							(start -0.508 0.2921)
							(mid -0.478242 0.363942)
							(end -0.4064 0.3937)
						)
						(arc
							(start 0.4064 0.3937)
							(mid 0.478242 0.363942)
							(end 0.508 0.2921)
						)
					)
					(width 0)
					(fill yes)
				)
			)
		)
		(pad "2" smd custom
			(at 0 0.6604 270)
			(size 0.19685 0.19685)
			(layers "F.Cu" "F.Mask" "F.Paste")
			(net "GND")
			(options
				(clearance outline)
				(anchor circle)
			)
			(primitives
				(gr_poly
					(pts
						(arc
							(start 0.508 -0.2921)
							(mid 0.478242 -0.363942)
							(end 0.4064 -0.3937)
						)
						(arc
							(start -0.4064 -0.3937)
							(mid -0.478242 -0.363942)
							(end -0.508 -0.2921)
						)
						(arc
							(start -0.508 0.2921)
							(mid -0.478242 0.363942)
							(end -0.4064 0.3937)
						)
						(arc
							(start 0.4064 0.3937)
							(mid 0.478242 0.363942)
							(end 0.508 0.2921)
						)
					)
					(width 0)
					(fill yes)
				)
			)
		)
	)
	(footprint ""
		(layer "F.Cu")
		(at 34.417 -38.7858 180)
		(property "Reference" "R271"
			(at 0 0 180)
			(layer "F.SilkS")
			(hide yes)
			(effects
				(font
					(size 1.27 1.27)
				)
			)
		)
		(property "Value" "0R3J-0-U-GP"
			(at -0.0254 -2.5146 180)
			(unlocked yes)
			(layer "F.Fab")
			(hide yes)
			(effects
				(font
					(size 1.016 1.016)
					(thickness 0.1524)
				)
			)
		)
		(property "Device Type" "R603H22"
			(at -0.0254 -4.0386 180)
			(unlocked yes)
			(layer "F.Fab")
			(hide yes)
			(effects
				(font
					(size 1.016 1.016)
					(thickness 0.1524)
				)
			)
		)
		(duplicate_pad_numbers_are_jumpers no)
		(fp_line
			(start 0.4318 0)
			(end 0.2032 0)
			(stroke
				(width 0.2032)
				(type default)
			)
			(layer "F.SilkS")
		)
		(fp_line
			(start -0.2032 0)
			(end -0.4191 0)
			(stroke
				(width 0.2032)
				(type default)
			)
			(layer "F.SilkS")
		)
		(fp_rect
			(start -0.635 1.1811)
			(end 0.635 -1.1811)
			(stroke
				(width 0)
				(type default)
			)
			(fill no)
			(layer "F.CrtYd")
		)
		(fp_rect
			(start -0.635 1.1811)
			(end 0.635 -1.1811)
			(stroke
				(width 0)
				(type default)
			)
			(fill no)
			(layer "F.Fab")
		)
		(pad "1" smd custom
			(at 0 -0.6604 180)
			(size 0.19685 0.19685)
			(layers "F.Cu" "F.Mask" "F.Paste")
			(net "XDP_P60")
			(options
				(clearance outline)
				(anchor circle)
			)
			(primitives
				(gr_poly
					(pts
						(arc
							(start 0.508 -0.2921)
							(mid 0.478242 -0.363942)
							(end 0.4064 -0.3937)
						)
						(arc
							(start -0.4064 -0.3937)
							(mid -0.478242 -0.363942)
							(end -0.508 -0.2921)
						)
						(arc
							(start -0.508 0.2921)
							(mid -0.478242 0.363942)
							(end -0.4064 0.3937)
						)
						(arc
							(start 0.4064 0.3937)
							(mid 0.478242 0.363942)
							(end 0.508 0.2921)
						)
					)
					(width 0)
					(fill yes)
				)
			)
		)
		(pad "2" smd custom
			(at 0 0.6604 180)
			(size 0.19685 0.19685)
			(layers "F.Cu" "F.Mask" "F.Paste")
			(net "GND")
			(options
				(clearance outline)
				(anchor circle)
			)
			(primitives
				(gr_poly
					(pts
						(arc
							(start 0.508 -0.2921)
							(mid 0.478242 -0.363942)
							(end 0.4064 -0.3937)
						)
						(arc
							(start -0.4064 -0.3937)
							(mid -0.478242 -0.363942)
							(end -0.508 -0.2921)
						)
						(arc
							(start -0.508 0.2921)
							(mid -0.478242 0.363942)
							(end -0.4064 0.3937)
						)
						(arc
							(start 0.4064 0.3937)
							(mid 0.478242 0.363942)
							(end 0.508 0.2921)
						)
					)
					(width 0)
					(fill yes)
				)
			)
		)
	)
	(footprint ""
		(layer "F.Cu")
		(at 23.98268 -64.8716 180)
		(property "Reference" "PC13"
			(at 0 0 180)
			(layer "F.SilkS")
			(hide yes)
			(effects
				(font
					(size 1.27 1.27)
				)
			)
		)
		(property "Value" "SCD22U16V3KX-2-GP"
			(at -0.0254 -2.0193 180)
			(unlocked yes)
			(layer "F.Fab")
			(hide yes)
			(effects
				(font
					(size 1.016 1.016)
					(thickness 0.1524)
				)
			)
		)
		(property "Device Type" "C603H36"
			(at -0.0254 -3.5433 180)
			(unlocked yes)
			(layer "F.Fab")
			(hide yes)
			(effects
				(font
					(size 1.016 1.016)
					(thickness 0.1524)
				)
			)
		)
		(duplicate_pad_numbers_are_jumpers no)
		(fp_line
			(start -0.4064 0)
			(end 0.4064 0)
			(stroke
				(width 0.2286)
				(type default)
			)
			(layer "F.SilkS")
		)
		(fp_rect
			(start -0.635 1.1811)
			(end 0.635 -1.1811)
			(stroke
				(width 0)
				(type default)
			)
			(fill no)
			(layer "F.CrtYd")
		)
		(fp_rect
			(start -0.635 1.1811)
			(end 0.635 -1.1811)
			(stroke
				(width 0)
				(type default)
			)
			(fill no)
			(layer "F.Fab")
		)
		(pad "1" smd custom
			(at 0 -0.6604 180)
			(size 0.19685 0.19685)
			(layers "F.Cu" "F.Mask" "F.Paste")
			(net "VR_PVNN_BOOT")
			(options
				(clearance outline)
				(anchor circle)
			)
			(primitives
				(gr_poly
					(pts
						(arc
							(start 0.508 -0.2921)
							(mid 0.478242 -0.363942)
							(end 0.4064 -0.3937)
						)
						(arc
							(start -0.4064 -0.3937)
							(mid -0.478242 -0.363942)
							(end -0.508 -0.2921)
						)
						(arc
							(start -0.508 0.2921)
							(mid -0.478242 0.363942)
							(end -0.4064 0.3937)
						)
						(arc
							(start 0.4064 0.3937)
							(mid 0.478242 0.363942)
							(end 0.508 0.2921)
						)
					)
					(width 0)
					(fill yes)
				)
			)
		)
		(pad "2" smd custom
			(at 0 0.6604 180)
			(size 0.19685 0.19685)
			(layers "F.Cu" "F.Mask" "F.Paste")
			(net "VR_PVNN_BOOT_R")
			(options
				(clearance outline)
				(anchor circle)
			)
			(primitives
				(gr_poly
					(pts
						(arc
							(start 0.508 -0.2921)
							(mid 0.478242 -0.363942)
							(end 0.4064 -0.3937)
						)
						(arc
							(start -0.4064 -0.3937)
							(mid -0.478242 -0.363942)
							(end -0.508 -0.2921)
						)
						(arc
							(start -0.508 0.2921)
							(mid -0.478242 0.363942)
							(end -0.4064 0.3937)
						)
						(arc
							(start 0.4064 0.3937)
							(mid 0.478242 0.363942)
							(end 0.508 0.2921)
						)
					)
					(width 0)
					(fill yes)
				)
			)
		)
	)
	(footprint ""
		(layer "F.Cu")
		(at 25.019 -49.276 180)
		(property "Reference" "PC54"
			(at 0 0 180)
			(layer "F.SilkS")
			(hide yes)
			(effects
				(font
					(size 1.27 1.27)
				)
			)
		)
		(property "Value" "SCD1U16V2KX-3GP"
			(at 1.8923 -1.2065 180)
			(unlocked yes)
			(layer "F.Fab")
			(hide yes)
			(effects
				(font
					(size 1.016 1.016)
					(thickness 0.1524)
				)
			)
		)
		(property "Device Type" "C402H22"
			(at 1.8923 -2.7305 180)
			(unlocked yes)
			(layer "F.Fab")
			(hide yes)
			(effects
				(font
					(size 1.016 1.016)
					(thickness 0.1524)
				)
			)
		)
		(duplicate_pad_numbers_are_jumpers no)
		(fp_rect
			(start -0.381 0.7366)
			(end 0.381 -0.7366)
			(stroke
				(width 0)
				(type default)
			)
			(fill no)
			(layer "F.CrtYd")
		)
		(fp_rect
			(start -0.381 0.7366)
			(end 0.381 -0.7366)
			(stroke
				(width 0)
				(type default)
			)
			(fill no)
			(layer "F.Fab")
		)
		(pad "1" smd custom
			(at 0 -0.4572 180)
			(size 0.1143 0.1143)
			(layers "F.Cu" "F.Mask" "F.Paste")
			(net "VR_PVCCP_ISUMN")
			(options
				(clearance outline)
				(anchor circle)
			)
			(primitives
				(gr_poly
					(pts
						(arc
							(start -0.254 -0.1778)
							(mid -0.239121 -0.213721)
							(end -0.2032 -0.2286)
						)
						(arc
							(start 0.2032 -0.2286)
							(mid 0.239121 -0.213721)
							(end 0.254 -0.1778)
						)
						(arc
							(start 0.254 0.1778)
							(mid 0.239121 0.213721)
							(end 0.2032 0.2286)
						)
						(arc
							(start -0.2032 0.2286)
							(mid -0.239121 0.213721)
							(end -0.254 0.1778)
						)
					)
					(width 0)
					(fill yes)
				)
			)
		)
		(pad "2" smd custom
			(at 0 0.4572 180)
			(size 0.1143 0.1143)
			(layers "F.Cu" "F.Mask" "F.Paste")
			(net "GND")
			(options
				(clearance outline)
				(anchor circle)
			)
			(primitives
				(gr_poly
					(pts
						(arc
							(start -0.254 -0.1778)
							(mid -0.239121 -0.213721)
							(end -0.2032 -0.2286)
						)
						(arc
							(start 0.2032 -0.2286)
							(mid 0.239121 -0.213721)
							(end 0.254 -0.1778)
						)
						(arc
							(start 0.254 0.1778)
							(mid 0.239121 0.213721)
							(end 0.2032 0.2286)
						)
						(arc
							(start -0.2032 0.2286)
							(mid -0.239121 0.213721)
							(end -0.254 0.1778)
						)
					)
					(width 0)
					(fill yes)
				)
			)
		)
	)
	(footprint ""
		(layer "F.Cu")
		(at 63.627 -13.589)
		(property "Reference" "C308"
			(at 0 0 0)
			(layer "F.SilkS")
			(hide yes)
			(effects
				(font
					(size 1.27 1.27)
				)
			)
		)
		(property "Value" "SCD01U16V2KX-3GP"
			(at 1.8923 -1.2065 0)
			(unlocked yes)
			(layer "F.Fab")
			(hide yes)
			(effects
				(font
					(size 1.016 1.016)
					(thickness 0.1524)
				)
			)
		)
		(property "Device Type" "C402H22"
			(at 1.8923 -2.7305 0)
			(unlocked yes)
			(layer "F.Fab")
			(hide yes)
			(effects
				(font
					(size 1.016 1.016)
					(thickness 0.1524)
				)
			)
		)
		(duplicate_pad_numbers_are_jumpers no)
		(fp_rect
			(start -0.381 0.7366)
			(end 0.381 -0.7366)
			(stroke
				(width 0)
				(type default)
			)
			(fill no)
			(layer "F.CrtYd")
		)
		(fp_rect
			(start -0.381 0.7366)
			(end 0.381 -0.7366)
			(stroke
				(width 0)
				(type default)
			)
			(fill no)
			(layer "F.Fab")
		)
		(pad "1" smd custom
			(at 0 -0.4572)
			(size 0.1143 0.1143)
			(layers "F.Cu" "F.Mask" "F.Paste")
			(net "SATA2_RX_DN0")
			(options
				(clearance outline)
				(anchor circle)
			)
			(primitives
				(gr_poly
					(pts
						(arc
							(start -0.254 -0.1778)
							(mid -0.239121 -0.213721)
							(end -0.2032 -0.2286)
						)
						(arc
							(start 0.2032 -0.2286)
							(mid 0.239121 -0.213721)
							(end 0.254 -0.1778)
						)
						(arc
							(start 0.254 0.1778)
							(mid 0.239121 0.213721)
							(end 0.2032 0.2286)
						)
						(arc
							(start -0.2032 0.2286)
							(mid -0.239121 0.213721)
							(end -0.254 0.1778)
						)
					)
					(width 0)
					(fill yes)
				)
			)
		)
		(pad "2" smd custom
			(at 0 0.4572)
			(size 0.1143 0.1143)
			(layers "F.Cu" "F.Mask" "F.Paste")
			(net "SATA2_RX_C_DN0")
			(options
				(clearance outline)
				(anchor circle)
			)
			(primitives
				(gr_poly
					(pts
						(arc
							(start -0.254 -0.1778)
							(mid -0.239121 -0.213721)
							(end -0.2032 -0.2286)
						)
						(arc
							(start 0.2032 -0.2286)
							(mid 0.239121 -0.213721)
							(end 0.254 -0.1778)
						)
						(arc
							(start 0.254 0.1778)
							(mid 0.239121 0.213721)
							(end 0.2032 0.2286)
						)
						(arc
							(start -0.2032 0.2286)
							(mid -0.239121 0.213721)
							(end -0.254 0.1778)
						)
					)
					(width 0)
					(fill yes)
				)
			)
		)
	)
	(footprint ""
		(layer "F.Cu")
		(at 109.2708 -20.193 90)
		(property "Reference" "R160"
			(at 0 0 90)
			(layer "F.SilkS")
			(hide yes)
			(effects
				(font
					(size 1.27 1.27)
				)
			)
		)
		(property "Value" "100R2F-L1-GP-U"
			(at 0.064008 -3.993896 90)
			(unlocked yes)
			(layer "F.Fab")
			(hide yes)
			(effects
				(font
					(size 1.016 1.016)
					(thickness 0.1524)
				)
			)
		)
		(property "Device Type" "R402H14"
			(at 0.064008 -5.517896 90)
			(unlocked yes)
			(layer "F.Fab")
			(hide yes)
			(effects
				(font
					(size 1.016 1.016)
					(thickness 0.1524)
				)
			)
		)
		(duplicate_pad_numbers_are_jumpers no)
		(fp_rect
			(start -0.381 0.8382)
			(end 0.381 -0.8382)
			(stroke
				(width 0)
				(type default)
			)
			(fill no)
			(layer "F.CrtYd")
		)
		(fp_rect
			(start -0.381 0.8382)
			(end 0.381 -0.8382)
			(stroke
				(width 0)
				(type default)
			)
			(fill no)
			(layer "F.Fab")
		)
		(pad "1" smd custom
			(at 0 -0.4318 90)
			(size 0.127 0.127)
			(layers "F.Cu" "F.Mask" "F.Paste")
			(net "M_B_MON2_P")
			(options
				(clearance outline)
				(anchor circle)
			)
			(primitives
				(gr_poly
					(pts
						(arc
							(start -0.2032 -0.2794)
							(mid -0.239121 -0.264521)
							(end -0.254 -0.2286)
						)
						(arc
							(start -0.254 0.2286)
							(mid -0.239121 0.264521)
							(end -0.2032 0.2794)
						)
						(arc
							(start 0.2032 0.2794)
							(mid 0.239121 0.264521)
							(end 0.254 0.2286)
						)
						(arc
							(start 0.254 -0.2286)
							(mid 0.239121 -0.264521)
							(end 0.2032 -0.2794)
						)
					)
					(width 0)
					(fill yes)
				)
			)
		)
		(pad "2" smd custom
			(at 0 0.4318 90)
			(size 0.127 0.127)
			(layers "F.Cu" "F.Mask" "F.Paste")
			(net "M_B_MON2_N")
			(options
				(clearance outline)
				(anchor circle)
			)
			(primitives
				(gr_poly
					(pts
						(arc
							(start -0.2032 -0.2794)
							(mid -0.239121 -0.264521)
							(end -0.254 -0.2286)
						)
						(arc
							(start -0.254 0.2286)
							(mid -0.239121 0.264521)
							(end -0.2032 0.2794)
						)
						(arc
							(start 0.2032 0.2794)
							(mid 0.239121 0.264521)
							(end 0.254 0.2286)
						)
						(arc
							(start 0.254 -0.2286)
							(mid 0.239121 -0.264521)
							(end 0.2032 -0.2794)
						)
					)
					(width 0)
					(fill yes)
				)
			)
		)
	)
	(footprint ""
		(layer "F.Cu")
		(at 13.716 -54.864)
		(property "Reference" "PR70"
			(at 0 0 0)
			(layer "F.SilkS")
			(hide yes)
			(effects
				(font
					(size 1.27 1.27)
				)
			)
		)
		(property "Value" "19K6R2D-GP"
			(at 1.7907 -1.1176 0)
			(unlocked yes)
			(layer "F.Fab")
			(hide yes)
			(effects
				(font
					(size 1.016 1.016)
					(thickness 0.1524)
				)
			)
		)
		(property "Device Type" "R402H16"
			(at 1.7907 -2.6416 0)
			(unlocked yes)
			(layer "F.Fab")
			(hide yes)
			(effects
				(font
					(size 1.016 1.016)
					(thickness 0.1524)
				)
			)
		)
		(duplicate_pad_numbers_are_jumpers no)
		(fp_rect
			(start -0.381 0.8382)
			(end 0.381 -0.8382)
			(stroke
				(width 0)
				(type default)
			)
			(fill no)
			(layer "F.CrtYd")
		)
		(fp_rect
			(start -0.381 0.8382)
			(end 0.381 -0.8382)
			(stroke
				(width 0)
				(type default)
			)
			(fill no)
			(layer "F.Fab")
		)
		(pad "1" smd custom
			(at 0 -0.4318)
			(size 0.127 0.127)
			(layers "F.Cu" "F.Mask" "F.Paste")
			(net "VR_PVCCP_IMON")
			(options
				(clearance outline)
				(anchor circle)
			)
			(primitives
				(gr_poly
					(pts
						(arc
							(start -0.2032 -0.2794)
							(mid -0.239121 -0.264521)
							(end -0.254 -0.2286)
						)
						(arc
							(start -0.254 0.2286)
							(mid -0.239121 0.264521)
							(end -0.2032 0.2794)
						)
						(arc
							(start 0.2032 0.2794)
							(mid 0.239121 0.264521)
							(end 0.254 0.2286)
						)
						(arc
							(start 0.254 -0.2286)
							(mid 0.239121 -0.264521)
							(end 0.2032 -0.2794)
						)
					)
					(width 0)
					(fill yes)
				)
			)
		)
		(pad "2" smd custom
			(at 0 0.4318)
			(size 0.127 0.127)
			(layers "F.Cu" "F.Mask" "F.Paste")
			(net "GND")
			(options
				(clearance outline)
				(anchor circle)
			)
			(primitives
				(gr_poly
					(pts
						(arc
							(start -0.2032 -0.2794)
							(mid -0.239121 -0.264521)
							(end -0.254 -0.2286)
						)
						(arc
							(start -0.254 0.2286)
							(mid -0.239121 0.264521)
							(end -0.2032 0.2794)
						)
						(arc
							(start 0.2032 0.2794)
							(mid 0.239121 0.264521)
							(end 0.254 0.2286)
						)
						(arc
							(start 0.254 -0.2286)
							(mid 0.239121 -0.264521)
							(end 0.2032 -0.2794)
						)
					)
					(width 0)
					(fill yes)
				)
			)
		)
	)
	(footprint ""
		(layer "F.Cu")
		(at 47.2948 -54.6481 -90)
		(property "Reference" "R113"
			(at 0 0 270)
			(layer "F.SilkS")
			(hide yes)
			(effects
				(font
					(size 1.27 1.27)
				)
			)
		)
		(property "Value" "2D2R3J-2-GP"
			(at -0.0254 -2.0193 270)
			(unlocked yes)
			(layer "F.Fab")
			(hide yes)
			(effects
				(font
					(size 1.016 1.016)
					(thickness 0.1524)
				)
			)
		)
		(property "Device Type" "R603H22"
			(at -0.0254 -3.5433 270)
			(unlocked yes)
			(layer "F.Fab")
			(hide yes)
			(effects
				(font
					(size 1.016 1.016)
					(thickness 0.1524)
				)
			)
		)
		(duplicate_pad_numbers_are_jumpers no)
		(fp_line
			(start -0.2032 0)
			(end -0.4191 0)
			(stroke
				(width 0.2032)
				(type default)
			)
			(layer "F.SilkS")
		)
		(fp_line
			(start 0.4318 0)
			(end 0.2032 0)
			(stroke
				(width 0.2032)
				(type default)
			)
			(layer "F.SilkS")
		)
		(fp_rect
			(start -0.635 1.1811)
			(end 0.635 -1.1811)
			(stroke
				(width 0)
				(type default)
			)
			(fill no)
			(layer "F.CrtYd")
		)
		(fp_rect
			(start -0.635 1.1811)
			(end 0.635 -1.1811)
			(stroke
				(width 0)
				(type default)
			)
			(fill no)
			(layer "F.Fab")
		)
		(pad "1" smd custom
			(at 0 -0.6604 270)
			(size 0.19685 0.19685)
			(layers "F.Cu" "F.Mask" "F.Paste")
			(net "P3V3_CLK_R_VDD25")
			(options
				(clearance outline)
				(anchor circle)
			)
			(primitives
				(gr_poly
					(pts
						(arc
							(start 0.508 -0.2921)
							(mid 0.478242 -0.363942)
							(end 0.4064 -0.3937)
						)
						(arc
							(start -0.4064 -0.3937)
							(mid -0.478242 -0.363942)
							(end -0.508 -0.2921)
						)
						(arc
							(start -0.508 0.2921)
							(mid -0.478242 0.363942)
							(end -0.4064 0.3937)
						)
						(arc
							(start 0.4064 0.3937)
							(mid 0.478242 0.363942)
							(end 0.508 0.2921)
						)
					)
					(width 0)
					(fill yes)
				)
			)
		)
		(pad "2" smd custom
			(at 0 0.6604 270)
			(size 0.19685 0.19685)
			(layers "F.Cu" "F.Mask" "F.Paste")
			(net "P3V3_CLK_VDD25")
			(options
				(clearance outline)
				(anchor circle)
			)
			(primitives
				(gr_poly
					(pts
						(arc
							(start 0.508 -0.2921)
							(mid 0.478242 -0.363942)
							(end 0.4064 -0.3937)
						)
						(arc
							(start -0.4064 -0.3937)
							(mid -0.478242 -0.363942)
							(end -0.508 -0.2921)
						)
						(arc
							(start -0.508 0.2921)
							(mid -0.478242 0.363942)
							(end -0.4064 0.3937)
						)
						(arc
							(start 0.4064 0.3937)
							(mid 0.478242 0.363942)
							(end 0.508 0.2921)
						)
					)
					(width 0)
					(fill yes)
				)
			)
		)
	)
	(footprint ""
		(layer "F.Cu")
		(at 10.668 -50.4952 90)
		(property "Reference" "C64"
			(at 0 0 90)
			(layer "F.SilkS")
			(hide yes)
			(effects
				(font
					(size 1.27 1.27)
				)
			)
		)
		(property "Value" "SCD01U16V2KX-3GP"
			(at 1.1811 -2.7051 90)
			(unlocked yes)
			(layer "F.Fab")
			(hide yes)
			(effects
				(font
					(size 1.016 1.016)
					(thickness 0.1524)
				)
			)
		)
		(property "Device Type" "C402H22"
			(at 1.1811 -4.2291 90)
			(unlocked yes)
			(layer "F.Fab")
			(hide yes)
			(effects
				(font
					(size 1.016 1.016)
					(thickness 0.1524)
				)
			)
		)
		(duplicate_pad_numbers_are_jumpers no)
		(fp_rect
			(start -0.381 0.7366)
			(end 0.381 -0.7366)
			(stroke
				(width 0)
				(type default)
			)
			(fill no)
			(layer "F.CrtYd")
		)
		(fp_rect
			(start -0.381 0.7366)
			(end 0.381 -0.7366)
			(stroke
				(width 0)
				(type default)
			)
			(fill no)
			(layer "F.Fab")
		)
		(pad "1" smd custom
			(at 0 -0.4572 90)
			(size 0.1143 0.1143)
			(layers "F.Cu" "F.Mask" "F.Paste")
			(net "SATA3_TX_DP1")
			(options
				(clearance outline)
				(anchor circle)
			)
			(primitives
				(gr_poly
					(pts
						(arc
							(start -0.254 -0.1778)
							(mid -0.239121 -0.213721)
							(end -0.2032 -0.2286)
						)
						(arc
							(start 0.2032 -0.2286)
							(mid 0.239121 -0.213721)
							(end 0.254 -0.1778)
						)
						(arc
							(start 0.254 0.1778)
							(mid 0.239121 0.213721)
							(end 0.2032 0.2286)
						)
						(arc
							(start -0.2032 0.2286)
							(mid -0.239121 0.213721)
							(end -0.254 0.1778)
						)
					)
					(width 0)
					(fill yes)
				)
			)
		)
		(pad "2" smd custom
			(at 0 0.4572 90)
			(size 0.1143 0.1143)
			(layers "F.Cu" "F.Mask" "F.Paste")
			(net "P2E_CPU_NGFF_TX_DP12")
			(options
				(clearance outline)
				(anchor circle)
			)
			(primitives
				(gr_poly
					(pts
						(arc
							(start -0.254 -0.1778)
							(mid -0.239121 -0.213721)
							(end -0.2032 -0.2286)
						)
						(arc
							(start 0.2032 -0.2286)
							(mid 0.239121 -0.213721)
							(end 0.254 -0.1778)
						)
						(arc
							(start 0.254 0.1778)
							(mid 0.239121 0.213721)
							(end 0.2032 0.2286)
						)
						(arc
							(start -0.2032 0.2286)
							(mid -0.239121 0.213721)
							(end -0.254 0.1778)
						)
					)
					(width 0)
					(fill yes)
				)
			)
		)
	)
	(footprint ""
		(layer "F.Cu")
		(at 137.541 -19.177 -90)
		(property "Reference" "R57"
			(at 0 0 270)
			(layer "F.SilkS")
			(hide yes)
			(effects
				(font
					(size 1.27 1.27)
				)
			)
		)
		(property "Value" "4K7R2F-GP"
			(at 0.064008 -3.993896 270)
			(unlocked yes)
			(layer "F.Fab")
			(hide yes)
			(effects
				(font
					(size 1.016 1.016)
					(thickness 0.1524)
				)
			)
		)
		(property "Device Type" "R402H16"
			(at 0.064008 -5.517896 270)
			(unlocked yes)
			(layer "F.Fab")
			(hide yes)
			(effects
				(font
					(size 1.016 1.016)
					(thickness 0.1524)
				)
			)
		)
		(duplicate_pad_numbers_are_jumpers no)
		(fp_rect
			(start -0.381 0.8382)
			(end 0.381 -0.8382)
			(stroke
				(width 0)
				(type default)
			)
			(fill no)
			(layer "F.CrtYd")
		)
		(fp_rect
			(start -0.381 0.8382)
			(end 0.381 -0.8382)
			(stroke
				(width 0)
				(type default)
			)
			(fill no)
			(layer "F.Fab")
		)
		(pad "1" smd custom
			(at 0 -0.4318 270)
			(size 0.127 0.127)
			(layers "F.Cu" "F.Mask" "F.Paste")
			(net "P3V3_STBY")
			(options
				(clearance outline)
				(anchor circle)
			)
			(primitives
				(gr_poly
					(pts
						(arc
							(start -0.2032 -0.2794)
							(mid -0.239121 -0.264521)
							(end -0.254 -0.2286)
						)
						(arc
							(start -0.254 0.2286)
							(mid -0.239121 0.264521)
							(end -0.2032 0.2794)
						)
						(arc
							(start 0.2032 0.2794)
							(mid 0.239121 0.264521)
							(end 0.254 0.2286)
						)
						(arc
							(start 0.254 -0.2286)
							(mid 0.239121 -0.264521)
							(end 0.2032 -0.2794)
						)
					)
					(width 0)
					(fill yes)
				)
			)
		)
		(pad "2" smd custom
			(at 0 0.4318 270)
			(size 0.127 0.127)
			(layers "F.Cu" "F.Mask" "F.Paste")
			(net "HOST_R_RSTBTN#")
			(options
				(clearance outline)
				(anchor circle)
			)
			(primitives
				(gr_poly
					(pts
						(arc
							(start -0.2032 -0.2794)
							(mid -0.239121 -0.264521)
							(end -0.254 -0.2286)
						)
						(arc
							(start -0.254 0.2286)
							(mid -0.239121 0.264521)
							(end -0.2032 0.2794)
						)
						(arc
							(start 0.2032 0.2794)
							(mid 0.239121 0.264521)
							(end 0.254 0.2286)
						)
						(arc
							(start 0.254 -0.2286)
							(mid 0.239121 -0.264521)
							(end 0.2032 -0.2794)
						)
					)
					(width 0)
					(fill yes)
				)
			)
		)
	)
	(footprint ""
		(layer "F.Cu")
		(at 74.1172 -25.1206)
		(property "Reference" "R139"
			(at 0 0 0)
			(layer "F.SilkS")
			(hide yes)
			(effects
				(font
					(size 1.27 1.27)
				)
			)
		)
		(property "Value" "10KR2F-2-GP"
			(at 0.064008 -3.993896 0)
			(unlocked yes)
			(layer "F.Fab")
			(hide yes)
			(effects
				(font
					(size 1.016 1.016)
					(thickness 0.1524)
				)
			)
		)
		(property "Device Type" "R402H16"
			(at 0.064008 -5.517896 0)
			(unlocked yes)
			(layer "F.Fab")
			(hide yes)
			(effects
				(font
					(size 1.016 1.016)
					(thickness 0.1524)
				)
			)
		)
		(duplicate_pad_numbers_are_jumpers no)
		(fp_rect
			(start -0.381 0.8382)
			(end 0.381 -0.8382)
			(stroke
				(width 0)
				(type default)
			)
			(fill no)
			(layer "F.CrtYd")
		)
		(fp_rect
			(start -0.381 0.8382)
			(end 0.381 -0.8382)
			(stroke
				(width 0)
				(type default)
			)
			(fill no)
			(layer "F.Fab")
		)
		(pad "1" smd custom
			(at 0 -0.4318)
			(size 0.127 0.127)
			(layers "F.Cu" "F.Mask" "F.Paste")
			(net "P3V3_CPU")
			(options
				(clearance outline)
				(anchor circle)
			)
			(primitives
				(gr_poly
					(pts
						(arc
							(start -0.2032 -0.2794)
							(mid -0.239121 -0.264521)
							(end -0.254 -0.2286)
						)
						(arc
							(start -0.254 0.2286)
							(mid -0.239121 0.264521)
							(end -0.2032 0.2794)
						)
						(arc
							(start 0.2032 0.2794)
							(mid 0.239121 0.264521)
							(end 0.254 0.2286)
						)
						(arc
							(start 0.254 -0.2286)
							(mid 0.239121 -0.264521)
							(end 0.2032 -0.2794)
						)
					)
					(width 0)
					(fill yes)
				)
			)
		)
		(pad "2" smd custom
			(at 0 0.4318)
			(size 0.127 0.127)
			(layers "F.Cu" "F.Mask" "F.Paste")
			(net "GBE_SMBDATA")
			(options
				(clearance outline)
				(anchor circle)
			)
			(primitives
				(gr_poly
					(pts
						(arc
							(start -0.2032 -0.2794)
							(mid -0.239121 -0.264521)
							(end -0.254 -0.2286)
						)
						(arc
							(start -0.254 0.2286)
							(mid -0.239121 0.264521)
							(end -0.2032 0.2794)
						)
						(arc
							(start 0.2032 0.2794)
							(mid 0.239121 0.264521)
							(end 0.254 0.2286)
						)
						(arc
							(start 0.254 -0.2286)
							(mid 0.239121 -0.264521)
							(end 0.2032 -0.2794)
						)
					)
					(width 0)
					(fill yes)
				)
			)
		)
	)
	(footprint ""
		(layer "F.Cu")
		(at 184.912 -53.848)
		(property "Reference" "R204"
			(at 0 0 0)
			(layer "F.SilkS")
			(hide yes)
			(effects
				(font
					(size 1.27 1.27)
				)
			)
		)
		(property "Value" "100R2F-L1-GP-U"
			(at 0.064008 -3.993896 0)
			(unlocked yes)
			(layer "F.Fab")
			(hide yes)
			(effects
				(font
					(size 1.016 1.016)
					(thickness 0.1524)
				)
			)
		)
		(property "Device Type" "R402H14"
			(at 0.064008 -5.517896 0)
			(unlocked yes)
			(layer "F.Fab")
			(hide yes)
			(effects
				(font
					(size 1.016 1.016)
					(thickness 0.1524)
				)
			)
		)
		(duplicate_pad_numbers_are_jumpers no)
		(fp_rect
			(start -0.381 0.8382)
			(end 0.381 -0.8382)
			(stroke
				(width 0)
				(type default)
			)
			(fill no)
			(layer "F.CrtYd")
		)
		(fp_rect
			(start -0.381 0.8382)
			(end 0.381 -0.8382)
			(stroke
				(width 0)
				(type default)
			)
			(fill no)
			(layer "F.Fab")
		)
		(pad "1" smd custom
			(at 0 -0.4318)
			(size 0.127 0.127)
			(layers "F.Cu" "F.Mask" "F.Paste")
			(net "PV_VDDR")
			(options
				(clearance outline)
				(anchor circle)
			)
			(primitives
				(gr_poly
					(pts
						(arc
							(start -0.2032 -0.2794)
							(mid -0.239121 -0.264521)
							(end -0.254 -0.2286)
						)
						(arc
							(start -0.254 0.2286)
							(mid -0.239121 0.264521)
							(end -0.2032 0.2794)
						)
						(arc
							(start 0.2032 0.2794)
							(mid 0.239121 0.264521)
							(end 0.254 0.2286)
						)
						(arc
							(start 0.254 -0.2286)
							(mid 0.239121 -0.264521)
							(end 0.2032 -0.2794)
						)
					)
					(width 0)
					(fill yes)
				)
			)
		)
		(pad "2" smd custom
			(at 0 0.4318)
			(size 0.127 0.127)
			(layers "F.Cu" "F.Mask" "F.Paste")
			(net "PV_VDDR_VREF_A_FB")
			(options
				(clearance outline)
				(anchor circle)
			)
			(primitives
				(gr_poly
					(pts
						(arc
							(start -0.2032 -0.2794)
							(mid -0.239121 -0.264521)
							(end -0.254 -0.2286)
						)
						(arc
							(start -0.254 0.2286)
							(mid -0.239121 0.264521)
							(end -0.2032 0.2794)
						)
						(arc
							(start 0.2032 0.2794)
							(mid 0.239121 0.264521)
							(end 0.254 0.2286)
						)
						(arc
							(start 0.254 -0.2286)
							(mid 0.239121 -0.264521)
							(end 0.2032 -0.2794)
						)
					)
					(width 0)
					(fill yes)
				)
			)
		)
	)
	(footprint ""
		(layer "F.Cu")
		(at 9.4488 -46.736 90)
		(property "Reference" "R11"
			(at 0 0 90)
			(layer "F.SilkS")
			(hide yes)
			(effects
				(font
					(size 1.27 1.27)
				)
			)
		)
		(property "Value" "4K7R2F-GP"
			(at 0.064008 -3.993896 90)
			(unlocked yes)
			(layer "F.Fab")
			(hide yes)
			(effects
				(font
					(size 1.016 1.016)
					(thickness 0.1524)
				)
			)
		)
		(property "Device Type" "R402H16"
			(at 0.064008 -5.517896 90)
			(unlocked yes)
			(layer "F.Fab")
			(hide yes)
			(effects
				(font
					(size 1.016 1.016)
					(thickness 0.1524)
				)
			)
		)
		(duplicate_pad_numbers_are_jumpers no)
		(fp_rect
			(start -0.381 0.8382)
			(end 0.381 -0.8382)
			(stroke
				(width 0)
				(type default)
			)
			(fill no)
			(layer "F.CrtYd")
		)
		(fp_rect
			(start -0.381 0.8382)
			(end 0.381 -0.8382)
			(stroke
				(width 0)
				(type default)
			)
			(fill no)
			(layer "F.Fab")
		)
		(pad "1" smd custom
			(at 0 -0.4318 90)
			(size 0.127 0.127)
			(layers "F.Cu" "F.Mask" "F.Paste")
			(net "TEMP_1_A2")
			(options
				(clearance outline)
				(anchor circle)
			)
			(primitives
				(gr_poly
					(pts
						(arc
							(start -0.2032 -0.2794)
							(mid -0.239121 -0.264521)
							(end -0.254 -0.2286)
						)
						(arc
							(start -0.254 0.2286)
							(mid -0.239121 0.264521)
							(end -0.2032 0.2794)
						)
						(arc
							(start 0.2032 0.2794)
							(mid 0.239121 0.264521)
							(end 0.254 0.2286)
						)
						(arc
							(start 0.254 -0.2286)
							(mid 0.239121 -0.264521)
							(end 0.2032 -0.2794)
						)
					)
					(width 0)
					(fill yes)
				)
			)
		)
		(pad "2" smd custom
			(at 0 0.4318 90)
			(size 0.127 0.127)
			(layers "F.Cu" "F.Mask" "F.Paste")
			(net "GND")
			(options
				(clearance outline)
				(anchor circle)
			)
			(primitives
				(gr_poly
					(pts
						(arc
							(start -0.2032 -0.2794)
							(mid -0.239121 -0.264521)
							(end -0.254 -0.2286)
						)
						(arc
							(start -0.254 0.2286)
							(mid -0.239121 0.264521)
							(end -0.2032 0.2794)
						)
						(arc
							(start 0.2032 0.2794)
							(mid 0.239121 0.264521)
							(end 0.254 0.2286)
						)
						(arc
							(start 0.254 -0.2286)
							(mid 0.239121 -0.264521)
							(end 0.2032 -0.2794)
						)
					)
					(width 0)
					(fill yes)
				)
			)
		)
	)
	(footprint ""
		(layer "F.Cu")
		(at 56.261 -54.356 180)
		(property "Reference" "PR151"
			(at 0 0 180)
			(layer "F.SilkS")
			(hide yes)
			(effects
				(font
					(size 1.27 1.27)
				)
			)
		)
		(property "Value" "237KR2F-GP"
			(at 1.7907 -1.1176 180)
			(unlocked yes)
			(layer "F.Fab")
			(hide yes)
			(effects
				(font
					(size 1.016 1.016)
					(thickness 0.1524)
				)
			)
		)
		(property "Device Type" "R402H16"
			(at 1.7907 -2.6416 180)
			(unlocked yes)
			(layer "F.Fab")
			(hide yes)
			(effects
				(font
					(size 1.016 1.016)
					(thickness 0.1524)
				)
			)
		)
		(duplicate_pad_numbers_are_jumpers no)
		(fp_rect
			(start -0.381 0.8382)
			(end 0.381 -0.8382)
			(stroke
				(width 0)
				(type default)
			)
			(fill no)
			(layer "F.CrtYd")
		)
		(fp_rect
			(start -0.381 0.8382)
			(end 0.381 -0.8382)
			(stroke
				(width 0)
				(type default)
			)
			(fill no)
			(layer "F.Fab")
		)
		(pad "1" smd custom
			(at 0 -0.4318 180)
			(size 0.127 0.127)
			(layers "F.Cu" "F.Mask" "F.Paste")
			(net "VR_FB_R_P1V0_STBY")
			(options
				(clearance outline)
				(anchor circle)
			)
			(primitives
				(gr_poly
					(pts
						(arc
							(start -0.2032 -0.2794)
							(mid -0.239121 -0.264521)
							(end -0.254 -0.2286)
						)
						(arc
							(start -0.254 0.2286)
							(mid -0.239121 0.264521)
							(end -0.2032 0.2794)
						)
						(arc
							(start 0.2032 0.2794)
							(mid 0.239121 0.264521)
							(end 0.254 0.2286)
						)
						(arc
							(start 0.254 -0.2286)
							(mid 0.239121 -0.264521)
							(end 0.2032 -0.2794)
						)
					)
					(width 0)
					(fill yes)
				)
			)
		)
		(pad "2" smd custom
			(at 0 0.4318 180)
			(size 0.127 0.127)
			(layers "F.Cu" "F.Mask" "F.Paste")
			(net "VR_FB_P1V0_STBY")
			(options
				(clearance outline)
				(anchor circle)
			)
			(primitives
				(gr_poly
					(pts
						(arc
							(start -0.2032 -0.2794)
							(mid -0.239121 -0.264521)
							(end -0.254 -0.2286)
						)
						(arc
							(start -0.254 0.2286)
							(mid -0.239121 0.264521)
							(end -0.2032 0.2794)
						)
						(arc
							(start 0.2032 0.2794)
							(mid 0.239121 0.264521)
							(end 0.254 0.2286)
						)
						(arc
							(start 0.254 -0.2286)
							(mid 0.239121 -0.264521)
							(end 0.2032 -0.2794)
						)
					)
					(width 0)
					(fill yes)
				)
			)
		)
	)
	(footprint ""
		(layer "F.Cu")
		(at 182.9308 -30.4038 90)
		(property "Reference" "PC105"
			(at 0 0 90)
			(layer "F.SilkS")
			(hide yes)
			(effects
				(font
					(size 1.27 1.27)
				)
			)
		)
		(property "Value" "SC68P50V2JN-1GP"
			(at 1.8923 -1.2065 90)
			(unlocked yes)
			(layer "F.Fab")
			(hide yes)
			(effects
				(font
					(size 1.016 1.016)
					(thickness 0.1524)
				)
			)
		)
		(property "Device Type" "C402H22"
			(at 1.8923 -2.7305 90)
			(unlocked yes)
			(layer "F.Fab")
			(hide yes)
			(effects
				(font
					(size 1.016 1.016)
					(thickness 0.1524)
				)
			)
		)
		(duplicate_pad_numbers_are_jumpers no)
		(fp_rect
			(start -0.381 0.7366)
			(end 0.381 -0.7366)
			(stroke
				(width 0)
				(type default)
			)
			(fill no)
			(layer "F.CrtYd")
		)
		(fp_rect
			(start -0.381 0.7366)
			(end 0.381 -0.7366)
			(stroke
				(width 0)
				(type default)
			)
			(fill no)
			(layer "F.Fab")
		)
		(pad "1" smd custom
			(at 0 -0.4572 90)
			(size 0.1143 0.1143)
			(layers "F.Cu" "F.Mask" "F.Paste")
			(net "VR_PVDDR_A_COMP")
			(options
				(clearance outline)
				(anchor circle)
			)
			(primitives
				(gr_poly
					(pts
						(arc
							(start -0.254 -0.1778)
							(mid -0.239121 -0.213721)
							(end -0.2032 -0.2286)
						)
						(arc
							(start 0.2032 -0.2286)
							(mid 0.239121 -0.213721)
							(end 0.254 -0.1778)
						)
						(arc
							(start 0.254 0.1778)
							(mid 0.239121 0.213721)
							(end 0.2032 0.2286)
						)
						(arc
							(start -0.2032 0.2286)
							(mid -0.239121 0.213721)
							(end -0.254 0.1778)
						)
					)
					(width 0)
					(fill yes)
				)
			)
		)
		(pad "2" smd custom
			(at 0 0.4572 90)
			(size 0.1143 0.1143)
			(layers "F.Cu" "F.Mask" "F.Paste")
			(net "VR_PVDDR_A_FB")
			(options
				(clearance outline)
				(anchor circle)
			)
			(primitives
				(gr_poly
					(pts
						(arc
							(start -0.254 -0.1778)
							(mid -0.239121 -0.213721)
							(end -0.2032 -0.2286)
						)
						(arc
							(start 0.2032 -0.2286)
							(mid 0.239121 -0.213721)
							(end 0.254 -0.1778)
						)
						(arc
							(start 0.254 0.1778)
							(mid 0.239121 0.213721)
							(end 0.2032 0.2286)
						)
						(arc
							(start -0.2032 0.2286)
							(mid -0.239121 0.213721)
							(end -0.254 0.1778)
						)
					)
					(width 0)
					(fill yes)
				)
			)
		)
	)
	(footprint ""
		(layer "F.Cu")
		(at 46.1772 -51.3334)
		(property "Reference" "C52"
			(at 0 0 0)
			(layer "F.SilkS")
			(hide yes)
			(effects
				(font
					(size 1.27 1.27)
				)
			)
		)
		(property "Value" "SCD1U10V2KX-5GP"
			(at 1.8923 -1.2065 0)
			(unlocked yes)
			(layer "F.Fab")
			(hide yes)
			(effects
				(font
					(size 1.016 1.016)
					(thickness 0.1524)
				)
			)
		)
		(property "Device Type" "C402H22"
			(at 1.8923 -2.7305 0)
			(unlocked yes)
			(layer "F.Fab")
			(hide yes)
			(effects
				(font
					(size 1.016 1.016)
					(thickness 0.1524)
				)
			)
		)
		(duplicate_pad_numbers_are_jumpers no)
		(fp_rect
			(start -0.381 0.7366)
			(end 0.381 -0.7366)
			(stroke
				(width 0)
				(type default)
			)
			(fill no)
			(layer "F.CrtYd")
		)
		(fp_rect
			(start -0.381 0.7366)
			(end 0.381 -0.7366)
			(stroke
				(width 0)
				(type default)
			)
			(fill no)
			(layer "F.Fab")
		)
		(pad "1" smd custom
			(at 0 -0.4572)
			(size 0.1143 0.1143)
			(layers "F.Cu" "F.Mask" "F.Paste")
			(net "P3V3_CLK_VDD25")
			(options
				(clearance outline)
				(anchor circle)
			)
			(primitives
				(gr_poly
					(pts
						(arc
							(start -0.254 -0.1778)
							(mid -0.239121 -0.213721)
							(end -0.2032 -0.2286)
						)
						(arc
							(start 0.2032 -0.2286)
							(mid 0.239121 -0.213721)
							(end 0.254 -0.1778)
						)
						(arc
							(start 0.254 0.1778)
							(mid 0.239121 0.213721)
							(end 0.2032 0.2286)
						)
						(arc
							(start -0.2032 0.2286)
							(mid -0.239121 0.213721)
							(end -0.254 0.1778)
						)
					)
					(width 0)
					(fill yes)
				)
			)
		)
		(pad "2" smd custom
			(at 0 0.4572)
			(size 0.1143 0.1143)
			(layers "F.Cu" "F.Mask" "F.Paste")
			(net "GND")
			(options
				(clearance outline)
				(anchor circle)
			)
			(primitives
				(gr_poly
					(pts
						(arc
							(start -0.254 -0.1778)
							(mid -0.239121 -0.213721)
							(end -0.2032 -0.2286)
						)
						(arc
							(start 0.2032 -0.2286)
							(mid 0.239121 -0.213721)
							(end 0.254 -0.1778)
						)
						(arc
							(start 0.254 0.1778)
							(mid 0.239121 0.213721)
							(end 0.2032 0.2286)
						)
						(arc
							(start -0.2032 0.2286)
							(mid -0.239121 0.213721)
							(end -0.254 0.1778)
						)
					)
					(width 0)
					(fill yes)
				)
			)
		)
	)
	(footprint ""
		(layer "F.Cu")
		(at 184.16524 -50.82159 -90)
		(property "Reference" "U23"
			(at 0 0 270)
			(layer "F.SilkS")
			(hide yes)
			(effects
				(font
					(size 1.27 1.27)
				)
			)
		)
		(property "Value" "LMV321IDCKR-1-GP"
			(at -2.3368 -8.6868 270)
			(unlocked yes)
			(layer "F.Fab")
			(hide yes)
			(effects
				(font
					(size 1.016 1.016)
					(thickness 0.1524)
				)
			)
		)
		(property "Device Type" "SC70-5H44"
			(at -2.3114 -10.414 270)
			(unlocked yes)
			(layer "F.Fab")
			(hide yes)
			(effects
				(font
					(size 1.016 1.016)
					(thickness 0.1524)
				)
			)
		)
		(duplicate_pad_numbers_are_jumpers no)
		(fp_line
			(start -1.0033 0.3302)
			(end -1.0033 -0.3302)
			(stroke
				(width 0.1524)
				(type default)
			)
			(layer "F.SilkS")
		)
		(fp_line
			(start 1.0033 0.3302)
			(end -1.0033 0.3302)
			(stroke
				(width 0.1524)
				(type default)
			)
			(layer "F.SilkS")
		)
		(fp_line
			(start -1.0033 -0.3302)
			(end 1.0033 -0.3302)
			(stroke
				(width 0.1524)
				(type default)
			)
			(layer "F.SilkS")
		)
		(fp_line
			(start 1.0033 -0.3302)
			(end 1.0033 0.3302)
			(stroke
				(width 0.1524)
				(type default)
			)
			(layer "F.SilkS")
		)
		(fp_poly
			(pts
				(xy -1.0033 1.4859) (xy -1.0033 0.8001) (xy -1.1811 0.8001) (xy -1.1811 -0.8001) (xy -1.0033 -0.8001)
				(xy -1.0033 -1.4859) (xy 1.0033 -1.4859) (xy 1.0033 -0.8001) (xy 1.1811 -0.8001) (xy 1.1811 0.8001)
				(xy 1.0033 0.8001) (xy 1.0033 1.4859) (xy 0.2921 1.4859) (xy 0.2921 0.8001) (xy -0.2921 0.8001)
				(xy -0.2921 1.4859)
			)
			(stroke
				(width 0)
				(type default)
			)
			(fill no)
			(layer "F.CrtYd")
		)
		(fp_poly
			(pts
				(xy -1.0033 1.4859) (xy -1.0033 0.8001) (xy -1.1811 0.8001) (xy -1.1811 -0.8001) (xy -1.0033 -0.8001)
				(xy -1.0033 -1.4859) (xy 1.0033 -1.4859) (xy 1.0033 -0.8001) (xy 1.1811 -0.8001) (xy 1.1811 0.8001)
				(xy 1.0033 0.8001) (xy 1.0033 1.4859) (xy 0.2921 1.4859) (xy 0.2921 0.8001) (xy -0.2921 0.8001)
				(xy -0.2921 1.4859)
			)
			(stroke
				(width 0)
				(type default)
			)
			(fill no)
			(layer "F.Fab")
		)
		(pad "1" smd rect
			(at 0.65024 -0.93472 270)
			(size 0.3556 0.762)
			(layers "F.Cu" "F.Mask" "F.Paste")
			(net "PV_VDDR_VREF_RW")
		)
		(pad "2" smd rect
			(at 0 -0.93472 270)
			(size 0.3556 0.762)
			(layers "F.Cu" "F.Mask" "F.Paste")
			(net "GND")
		)
		(pad "3" smd rect
			(at -0.65024 -0.93472 270)
			(size 0.3556 0.762)
			(layers "F.Cu" "F.Mask" "F.Paste")
			(net "PV_VDDR_VREF_A_FB")
		)
		(pad "4" smd rect
			(at -0.65024 0.93472 270)
			(size 0.3556 0.762)
			(layers "F.Cu" "F.Mask" "F.Paste")
			(net "PV_VDDR_VREF_A_FB")
		)
		(pad "5" smd rect
			(at 0.65024 0.93472 270)
			(size 0.3556 0.762)
			(layers "F.Cu" "F.Mask" "F.Paste")
			(net "P3V3_STBY")
		)
	)
	(footprint ""
		(layer "F.Cu")
		(at 146.558 -20.701)
		(property "Reference" "R100"
			(at 0 0 0)
			(layer "F.SilkS")
			(hide yes)
			(effects
				(font
					(size 1.27 1.27)
				)
			)
		)
		(property "Value" "0R2J-2-GP"
			(at 0.064008 -3.993896 0)
			(unlocked yes)
			(layer "F.Fab")
			(hide yes)
			(effects
				(font
					(size 1.016 1.016)
					(thickness 0.1524)
				)
			)
		)
		(property "Device Type" "R402H16"
			(at 0.064008 -5.517896 0)
			(unlocked yes)
			(layer "F.Fab")
			(hide yes)
			(effects
				(font
					(size 1.016 1.016)
					(thickness 0.1524)
				)
			)
		)
		(duplicate_pad_numbers_are_jumpers no)
		(fp_rect
			(start -0.381 0.8382)
			(end 0.381 -0.8382)
			(stroke
				(width 0)
				(type default)
			)
			(fill no)
			(layer "F.CrtYd")
		)
		(fp_rect
			(start -0.381 0.8382)
			(end 0.381 -0.8382)
			(stroke
				(width 0)
				(type default)
			)
			(fill no)
			(layer "F.Fab")
		)
		(pad "1" smd custom
			(at 0 -0.4318)
			(size 0.127 0.127)
			(layers "F.Cu" "F.Mask" "F.Paste")
			(net "P3V3_STBY")
			(options
				(clearance outline)
				(anchor circle)
			)
			(primitives
				(gr_poly
					(pts
						(arc
							(start -0.2032 -0.2794)
							(mid -0.239121 -0.264521)
							(end -0.254 -0.2286)
						)
						(arc
							(start -0.254 0.2286)
							(mid -0.239121 0.264521)
							(end -0.2032 0.2794)
						)
						(arc
							(start 0.2032 0.2794)
							(mid 0.239121 0.264521)
							(end 0.254 0.2286)
						)
						(arc
							(start 0.254 -0.2286)
							(mid 0.239121 -0.264521)
							(end 0.2032 -0.2794)
						)
					)
					(width 0)
					(fill yes)
				)
			)
		)
		(pad "2" smd custom
			(at 0 0.4318)
			(size 0.127 0.127)
			(layers "F.Cu" "F.Mask" "F.Paste")
			(net "MSEL1")
			(options
				(clearance outline)
				(anchor circle)
			)
			(primitives
				(gr_poly
					(pts
						(arc
							(start -0.2032 -0.2794)
							(mid -0.239121 -0.264521)
							(end -0.254 -0.2286)
						)
						(arc
							(start -0.254 0.2286)
							(mid -0.239121 0.264521)
							(end -0.2032 0.2794)
						)
						(arc
							(start 0.2032 0.2794)
							(mid 0.239121 0.264521)
							(end 0.254 0.2286)
						)
						(arc
							(start 0.254 -0.2286)
							(mid 0.239121 -0.264521)
							(end 0.2032 -0.2794)
						)
					)
					(width 0)
					(fill yes)
				)
			)
		)
	)
	(footprint ""
		(layer "F.Cu")
		(at 23.6728 -37.465)
		(property "Reference" "PC80"
			(at 0 0 0)
			(layer "F.SilkS")
			(hide yes)
			(effects
				(font
					(size 1.27 1.27)
				)
			)
		)
		(property "Value" "SC100U6D3V6MX-GP"
			(at 0.0127 -3.4671 0)
			(unlocked yes)
			(layer "F.Fab")
			(hide yes)
			(effects
				(font
					(size 1.016 1.016)
					(thickness 0.1524)
				)
			)
		)
		(property "Device Type" "C1206H71"
			(at 0.0127 -4.9911 0)
			(unlocked yes)
			(layer "F.Fab")
			(hide yes)
			(effects
				(font
					(size 1.016 1.016)
					(thickness 0.1524)
				)
			)
		)
		(duplicate_pad_numbers_are_jumpers no)
		(fp_rect
			(start -1.0541 1.9812)
			(end 1.0541 -1.9812)
			(stroke
				(width 0)
				(type default)
			)
			(fill no)
			(layer "F.CrtYd")
		)
		(fp_rect
			(start -1.0541 1.9812)
			(end 1.0541 -1.9812)
			(stroke
				(width 0)
				(type default)
			)
			(fill no)
			(layer "F.Fab")
		)
		(pad "1" smd rect
			(at 0 -1.3462)
			(size 1.8542 1.016)
			(layers "F.Cu" "F.Mask" "F.Paste")
			(net "P3V3_STBY_OUT")
		)
		(pad "2" smd rect
			(at 0 1.3462)
			(size 1.8542 1.016)
			(layers "F.Cu" "F.Mask" "F.Paste")
			(net "GND")
		)
	)
	(footprint ""
		(layer "F.Cu")
		(at 190.881 -39.878)
		(property "Reference" "PR124"
			(at 0 0 0)
			(layer "F.SilkS")
			(hide yes)
			(effects
				(font
					(size 1.27 1.27)
				)
			)
		)
		(property "Value" "0R2J-2-GP"
			(at 1.7907 -1.1176 0)
			(unlocked yes)
			(layer "F.Fab")
			(hide yes)
			(effects
				(font
					(size 1.016 1.016)
					(thickness 0.1524)
				)
			)
		)
		(property "Device Type" "R402H16"
			(at 1.7907 -2.6416 0)
			(unlocked yes)
			(layer "F.Fab")
			(hide yes)
			(effects
				(font
					(size 1.016 1.016)
					(thickness 0.1524)
				)
			)
		)
		(duplicate_pad_numbers_are_jumpers no)
		(fp_rect
			(start -0.381 0.8382)
			(end 0.381 -0.8382)
			(stroke
				(width 0)
				(type default)
			)
			(fill no)
			(layer "F.CrtYd")
		)
		(fp_rect
			(start -0.381 0.8382)
			(end 0.381 -0.8382)
			(stroke
				(width 0)
				(type default)
			)
			(fill no)
			(layer "F.Fab")
		)
		(pad "1" smd custom
			(at 0 -0.4318)
			(size 0.127 0.127)
			(layers "F.Cu" "F.Mask" "F.Paste")
			(net "GND")
			(options
				(clearance outline)
				(anchor circle)
			)
			(primitives
				(gr_poly
					(pts
						(arc
							(start -0.2032 -0.2794)
							(mid -0.239121 -0.264521)
							(end -0.254 -0.2286)
						)
						(arc
							(start -0.254 0.2286)
							(mid -0.239121 0.264521)
							(end -0.2032 0.2794)
						)
						(arc
							(start 0.2032 0.2794)
							(mid 0.239121 0.264521)
							(end 0.254 0.2286)
						)
						(arc
							(start 0.254 -0.2286)
							(mid 0.239121 -0.264521)
							(end 0.2032 -0.2794)
						)
					)
					(width 0)
					(fill yes)
				)
			)
		)
		(pad "2" smd custom
			(at 0 0.4318)
			(size 0.127 0.127)
			(layers "F.Cu" "F.Mask" "F.Paste")
			(net "VR_PVDDR_A_PSI")
			(options
				(clearance outline)
				(anchor circle)
			)
			(primitives
				(gr_poly
					(pts
						(arc
							(start -0.2032 -0.2794)
							(mid -0.239121 -0.264521)
							(end -0.254 -0.2286)
						)
						(arc
							(start -0.254 0.2286)
							(mid -0.239121 0.264521)
							(end -0.2032 0.2794)
						)
						(arc
							(start 0.2032 0.2794)
							(mid 0.239121 0.264521)
							(end 0.254 0.2286)
						)
						(arc
							(start 0.254 -0.2286)
							(mid 0.239121 -0.264521)
							(end 0.2032 -0.2794)
						)
					)
					(width 0)
					(fill yes)
				)
			)
		)
	)
	(footprint ""
		(layer "F.Cu")
		(at 59.944 -63.754 180)
		(property "Reference" "PC39"
			(at 0 0 180)
			(layer "F.SilkS")
			(hide yes)
			(effects
				(font
					(size 1.27 1.27)
				)
			)
		)
		(property "Value" "SC47U6D3V5MX-1-GP"
			(at -0.0762 -6.1214 180)
			(unlocked yes)
			(layer "F.Fab")
			(hide yes)
			(effects
				(font
					(size 1.016 1.016)
					(thickness 0.1524)
				)
			)
		)
		(property "Device Type" "C805H54"
			(at -0.0762 -8.1534 180)
			(unlocked yes)
			(layer "F.Fab")
			(hide yes)
			(effects
				(font
					(size 1.016 1.016)
					(thickness 0.1524)
				)
			)
		)
		(duplicate_pad_numbers_are_jumpers no)
		(fp_line
			(start 0.6096 0)
			(end -0.6096 0)
			(stroke
				(width 0.3048)
				(type default)
			)
			(layer "F.SilkS")
		)
		(fp_poly
			(pts
				(xy -0.9017 1.4351) (xy 0.9017 1.4351) (xy 0.9017 -1.4351) (xy -0.9017 -1.4351)
			)
			(stroke
				(width 0)
				(type default)
			)
			(fill no)
			(layer "F.CrtYd")
		)
		(fp_poly
			(pts
				(xy 0.9017 1.4351) (xy 0.9017 -1.4351) (xy -0.9017 -1.4351) (xy -0.9017 1.4351)
			)
			(stroke
				(width 0)
				(type default)
			)
			(fill no)
			(layer "F.Fab")
		)
		(pad "1" smd rect
			(at 0 -0.8382 180)
			(size 1.5494 0.9398)
			(layers "F.Cu" "F.Mask" "F.Paste")
			(net "PVCCP")
		)
		(pad "2" smd rect
			(at 0 0.8382 180)
			(size 1.5494 0.9398)
			(layers "F.Cu" "F.Mask" "F.Paste")
			(net "GND")
		)
	)
	(footprint ""
		(layer "F.Cu")
		(at 20.828 -49.276 90)
		(property "Reference" "PR46"
			(at 0 0 90)
			(layer "F.SilkS")
			(hide yes)
			(effects
				(font
					(size 1.27 1.27)
				)
			)
		)
		(property "Value" "10KR2F-2-GP"
			(at 1.7907 -1.1176 90)
			(unlocked yes)
			(layer "F.Fab")
			(hide yes)
			(effects
				(font
					(size 1.016 1.016)
					(thickness 0.1524)
				)
			)
		)
		(property "Device Type" "R402H16"
			(at 1.7907 -2.6416 90)
			(unlocked yes)
			(layer "F.Fab")
			(hide yes)
			(effects
				(font
					(size 1.016 1.016)
					(thickness 0.1524)
				)
			)
		)
		(duplicate_pad_numbers_are_jumpers no)
		(fp_rect
			(start -0.381 0.8382)
			(end 0.381 -0.8382)
			(stroke
				(width 0)
				(type default)
			)
			(fill no)
			(layer "F.CrtYd")
		)
		(fp_rect
			(start -0.381 0.8382)
			(end 0.381 -0.8382)
			(stroke
				(width 0)
				(type default)
			)
			(fill no)
			(layer "F.Fab")
		)
		(pad "1" smd custom
			(at 0 -0.4318 90)
			(size 0.127 0.127)
			(layers "F.Cu" "F.Mask" "F.Paste")
			(net "VR_PVCCP_ISUMP_R2")
			(options
				(clearance outline)
				(anchor circle)
			)
			(primitives
				(gr_poly
					(pts
						(arc
							(start -0.2032 -0.2794)
							(mid -0.239121 -0.264521)
							(end -0.254 -0.2286)
						)
						(arc
							(start -0.254 0.2286)
							(mid -0.239121 0.264521)
							(end -0.2032 0.2794)
						)
						(arc
							(start 0.2032 0.2794)
							(mid 0.239121 0.264521)
							(end 0.254 0.2286)
						)
						(arc
							(start 0.254 -0.2286)
							(mid 0.239121 -0.264521)
							(end 0.2032 -0.2794)
						)
					)
					(width 0)
					(fill yes)
				)
			)
		)
		(pad "2" smd custom
			(at 0 0.4318 90)
			(size 0.127 0.127)
			(layers "F.Cu" "F.Mask" "F.Paste")
			(net "VR_PVCCP_ISEN1")
			(options
				(clearance outline)
				(anchor circle)
			)
			(primitives
				(gr_poly
					(pts
						(arc
							(start -0.2032 -0.2794)
							(mid -0.239121 -0.264521)
							(end -0.254 -0.2286)
						)
						(arc
							(start -0.254 0.2286)
							(mid -0.239121 0.264521)
							(end -0.2032 0.2794)
						)
						(arc
							(start 0.2032 0.2794)
							(mid 0.239121 0.264521)
							(end 0.254 0.2286)
						)
						(arc
							(start 0.254 -0.2286)
							(mid 0.239121 -0.264521)
							(end 0.2032 -0.2794)
						)
					)
					(width 0)
					(fill yes)
				)
			)
		)
	)
	(footprint ""
		(layer "F.Cu")
		(at 43.0022 -49.9364 -90)
		(property "Reference" "R42"
			(at 0 0 270)
			(layer "F.SilkS")
			(hide yes)
			(effects
				(font
					(size 1.27 1.27)
				)
			)
		)
		(property "Value" "1KR2F-3-GP"
			(at 0.064008 -3.993896 270)
			(unlocked yes)
			(layer "F.Fab")
			(hide yes)
			(effects
				(font
					(size 1.016 1.016)
					(thickness 0.1524)
				)
			)
		)
		(property "Device Type" "R402H16"
			(at 0.064008 -5.517896 270)
			(unlocked yes)
			(layer "F.Fab")
			(hide yes)
			(effects
				(font
					(size 1.016 1.016)
					(thickness 0.1524)
				)
			)
		)
		(duplicate_pad_numbers_are_jumpers no)
		(fp_rect
			(start -0.381 0.8382)
			(end 0.381 -0.8382)
			(stroke
				(width 0)
				(type default)
			)
			(fill no)
			(layer "F.CrtYd")
		)
		(fp_rect
			(start -0.381 0.8382)
			(end 0.381 -0.8382)
			(stroke
				(width 0)
				(type default)
			)
			(fill no)
			(layer "F.Fab")
		)
		(pad "1" smd custom
			(at 0 -0.4318 270)
			(size 0.127 0.127)
			(layers "F.Cu" "F.Mask" "F.Paste")
			(net "P3V3_CPU")
			(options
				(clearance outline)
				(anchor circle)
			)
			(primitives
				(gr_poly
					(pts
						(arc
							(start -0.2032 -0.2794)
							(mid -0.239121 -0.264521)
							(end -0.254 -0.2286)
						)
						(arc
							(start -0.254 0.2286)
							(mid -0.239121 0.264521)
							(end -0.2032 0.2794)
						)
						(arc
							(start 0.2032 0.2794)
							(mid 0.239121 0.264521)
							(end 0.254 0.2286)
						)
						(arc
							(start 0.254 -0.2286)
							(mid 0.239121 -0.264521)
							(end 0.2032 -0.2794)
						)
					)
					(width 0)
					(fill yes)
				)
			)
		)
		(pad "2" smd custom
			(at 0 0.4318 270)
			(size 0.127 0.127)
			(layers "F.Cu" "F.Mask" "F.Paste")
			(net "GND")
			(options
				(clearance outline)
				(anchor circle)
			)
			(primitives
				(gr_poly
					(pts
						(arc
							(start -0.2032 -0.2794)
							(mid -0.239121 -0.264521)
							(end -0.254 -0.2286)
						)
						(arc
							(start -0.254 0.2286)
							(mid -0.239121 0.264521)
							(end -0.2032 0.2794)
						)
						(arc
							(start 0.2032 0.2794)
							(mid 0.239121 0.264521)
							(end 0.254 0.2286)
						)
						(arc
							(start 0.254 -0.2286)
							(mid 0.239121 -0.264521)
							(end 0.2032 -0.2794)
						)
					)
					(width 0)
					(fill yes)
				)
			)
		)
	)
	(footprint ""
		(layer "F.Cu")
		(at 182.118 -51.181 180)
		(property "Reference" "C93"
			(at 0 0 180)
			(layer "F.SilkS")
			(hide yes)
			(effects
				(font
					(size 1.27 1.27)
				)
			)
		)
		(property "Value" "SCD1U16V2KX-3GP"
			(at 1.1811 -2.7051 180)
			(unlocked yes)
			(layer "F.Fab")
			(hide yes)
			(effects
				(font
					(size 1.016 1.016)
					(thickness 0.1524)
				)
			)
		)
		(property "Device Type" "C402H22"
			(at 1.1811 -4.2291 180)
			(unlocked yes)
			(layer "F.Fab")
			(hide yes)
			(effects
				(font
					(size 1.016 1.016)
					(thickness 0.1524)
				)
			)
		)
		(duplicate_pad_numbers_are_jumpers no)
		(fp_rect
			(start -0.381 0.7366)
			(end 0.381 -0.7366)
			(stroke
				(width 0)
				(type default)
			)
			(fill no)
			(layer "F.CrtYd")
		)
		(fp_rect
			(start -0.381 0.7366)
			(end 0.381 -0.7366)
			(stroke
				(width 0)
				(type default)
			)
			(fill no)
			(layer "F.Fab")
		)
		(pad "1" smd custom
			(at 0 -0.4572 180)
			(size 0.1143 0.1143)
			(layers "F.Cu" "F.Mask" "F.Paste")
			(net "P3V3_STBY")
			(options
				(clearance outline)
				(anchor circle)
			)
			(primitives
				(gr_poly
					(pts
						(arc
							(start -0.254 -0.1778)
							(mid -0.239121 -0.213721)
							(end -0.2032 -0.2286)
						)
						(arc
							(start 0.2032 -0.2286)
							(mid 0.239121 -0.213721)
							(end 0.254 -0.1778)
						)
						(arc
							(start 0.254 0.1778)
							(mid 0.239121 0.213721)
							(end 0.2032 0.2286)
						)
						(arc
							(start -0.2032 0.2286)
							(mid -0.239121 0.213721)
							(end -0.254 0.1778)
						)
					)
					(width 0)
					(fill yes)
				)
			)
		)
		(pad "2" smd custom
			(at 0 0.4572 180)
			(size 0.1143 0.1143)
			(layers "F.Cu" "F.Mask" "F.Paste")
			(net "GND")
			(options
				(clearance outline)
				(anchor circle)
			)
			(primitives
				(gr_poly
					(pts
						(arc
							(start -0.254 -0.1778)
							(mid -0.239121 -0.213721)
							(end -0.2032 -0.2286)
						)
						(arc
							(start 0.2032 -0.2286)
							(mid 0.239121 -0.213721)
							(end 0.254 -0.1778)
						)
						(arc
							(start 0.254 0.1778)
							(mid 0.239121 0.213721)
							(end 0.2032 0.2286)
						)
						(arc
							(start -0.2032 0.2286)
							(mid -0.239121 0.213721)
							(end -0.254 0.1778)
						)
					)
					(width 0)
					(fill yes)
				)
			)
		)
	)
	(footprint ""
		(layer "F.Cu")
		(at 135.001 -59.817 180)
		(property "Reference" "PR59"
			(at 0 0 180)
			(layer "F.SilkS")
			(hide yes)
			(effects
				(font
					(size 1.27 1.27)
				)
			)
		)
		(property "Value" "20KR2F-L-GP"
			(at 0.064008 -3.993896 180)
			(unlocked yes)
			(layer "F.Fab")
			(hide yes)
			(effects
				(font
					(size 1.016 1.016)
					(thickness 0.1524)
				)
			)
		)
		(property "Device Type" "R402H16"
			(at 0.064008 -5.517896 180)
			(unlocked yes)
			(layer "F.Fab")
			(hide yes)
			(effects
				(font
					(size 1.016 1.016)
					(thickness 0.1524)
				)
			)
		)
		(duplicate_pad_numbers_are_jumpers no)
		(fp_rect
			(start -0.381 0.8382)
			(end 0.381 -0.8382)
			(stroke
				(width 0)
				(type default)
			)
			(fill no)
			(layer "F.CrtYd")
		)
		(fp_rect
			(start -0.381 0.8382)
			(end 0.381 -0.8382)
			(stroke
				(width 0)
				(type default)
			)
			(fill no)
			(layer "F.Fab")
		)
		(pad "1" smd custom
			(at 0 -0.4318 180)
			(size 0.127 0.127)
			(layers "F.Cu" "F.Mask" "F.Paste")
			(net "PV_VDDR")
			(options
				(clearance outline)
				(anchor circle)
			)
			(primitives
				(gr_poly
					(pts
						(arc
							(start -0.2032 -0.2794)
							(mid -0.239121 -0.264521)
							(end -0.254 -0.2286)
						)
						(arc
							(start -0.254 0.2286)
							(mid -0.239121 0.264521)
							(end -0.2032 0.2794)
						)
						(arc
							(start 0.2032 0.2794)
							(mid 0.239121 0.264521)
							(end 0.254 0.2286)
						)
						(arc
							(start 0.254 -0.2286)
							(mid 0.239121 -0.264521)
							(end 0.2032 -0.2794)
						)
					)
					(width 0)
					(fill yes)
				)
			)
		)
		(pad "2" smd custom
			(at 0 0.4318 180)
			(size 0.127 0.127)
			(layers "F.Cu" "F.Mask" "F.Paste")
			(net "PV_VTT_DDR_REFIN")
			(options
				(clearance outline)
				(anchor circle)
			)
			(primitives
				(gr_poly
					(pts
						(arc
							(start -0.2032 -0.2794)
							(mid -0.239121 -0.264521)
							(end -0.254 -0.2286)
						)
						(arc
							(start -0.254 0.2286)
							(mid -0.239121 0.264521)
							(end -0.2032 0.2794)
						)
						(arc
							(start 0.2032 0.2794)
							(mid 0.239121 0.264521)
							(end 0.254 0.2286)
						)
						(arc
							(start 0.254 -0.2286)
							(mid 0.239121 -0.264521)
							(end 0.2032 -0.2794)
						)
					)
					(width 0)
					(fill yes)
				)
			)
		)
	)
	(footprint ""
		(layer "F.Cu")
		(at 119.8118 -64.643 -90)
		(property "Reference" "C103"
			(at 0 0 270)
			(layer "F.SilkS")
			(hide yes)
			(effects
				(font
					(size 1.27 1.27)
				)
			)
		)
		(property "Value" "SC10U6D3V3MX-GP"
			(at 0 -2.8194 270)
			(unlocked yes)
			(layer "F.Fab")
			(hide yes)
			(effects
				(font
					(size 1.016 1.016)
					(thickness 0.1524)
				)
			)
		)
		(property "Device Type" "C603H38"
			(at 0 -4.3434 270)
			(unlocked yes)
			(layer "F.Fab")
			(hide yes)
			(effects
				(font
					(size 1.016 1.016)
					(thickness 0.1524)
				)
			)
		)
		(duplicate_pad_numbers_are_jumpers no)
		(fp_line
			(start -0.4064 0)
			(end 0.4064 0)
			(stroke
				(width 0.2286)
				(type default)
			)
			(layer "F.SilkS")
		)
		(fp_rect
			(start -0.635 1.1811)
			(end 0.635 -1.1811)
			(stroke
				(width 0)
				(type default)
			)
			(fill no)
			(layer "F.CrtYd")
		)
		(fp_rect
			(start -0.635 1.1811)
			(end 0.635 -1.1811)
			(stroke
				(width 0)
				(type default)
			)
			(fill no)
			(layer "F.Fab")
		)
		(pad "1" smd custom
			(at 0 -0.6604 270)
			(size 0.19685 0.19685)
			(layers "F.Cu" "F.Mask" "F.Paste")
			(net "PV_VTT_DDR_A")
			(options
				(clearance outline)
				(anchor circle)
			)
			(primitives
				(gr_poly
					(pts
						(arc
							(start 0.508 -0.2921)
							(mid 0.478242 -0.363942)
							(end 0.4064 -0.3937)
						)
						(arc
							(start -0.4064 -0.3937)
							(mid -0.478242 -0.363942)
							(end -0.508 -0.2921)
						)
						(arc
							(start -0.508 0.2921)
							(mid -0.478242 0.363942)
							(end -0.4064 0.3937)
						)
						(arc
							(start 0.4064 0.3937)
							(mid 0.478242 0.363942)
							(end 0.508 0.2921)
						)
					)
					(width 0)
					(fill yes)
				)
			)
		)
		(pad "2" smd custom
			(at 0 0.6604 270)
			(size 0.19685 0.19685)
			(layers "F.Cu" "F.Mask" "F.Paste")
			(net "GND")
			(options
				(clearance outline)
				(anchor circle)
			)
			(primitives
				(gr_poly
					(pts
						(arc
							(start 0.508 -0.2921)
							(mid 0.478242 -0.363942)
							(end 0.4064 -0.3937)
						)
						(arc
							(start -0.4064 -0.3937)
							(mid -0.478242 -0.363942)
							(end -0.508 -0.2921)
						)
						(arc
							(start -0.508 0.2921)
							(mid -0.478242 0.363942)
							(end -0.4064 0.3937)
						)
						(arc
							(start 0.4064 0.3937)
							(mid 0.478242 0.363942)
							(end 0.508 0.2921)
						)
					)
					(width 0)
					(fill yes)
				)
			)
		)
	)
	(footprint ""
		(layer "F.Cu")
		(at 21.1836 -52.0954)
		(property "Reference" "PR75"
			(at 0 0 0)
			(layer "F.SilkS")
			(hide yes)
			(effects
				(font
					(size 1.27 1.27)
				)
			)
		)
		(property "Value" "0R2J-2-GP"
			(at 1.7907 -1.1176 0)
			(unlocked yes)
			(layer "F.Fab")
			(hide yes)
			(effects
				(font
					(size 1.016 1.016)
					(thickness 0.1524)
				)
			)
		)
		(property "Device Type" "R402H16"
			(at 1.7907 -2.6416 0)
			(unlocked yes)
			(layer "F.Fab")
			(hide yes)
			(effects
				(font
					(size 1.016 1.016)
					(thickness 0.1524)
				)
			)
		)
		(duplicate_pad_numbers_are_jumpers no)
		(fp_rect
			(start -0.381 0.8382)
			(end 0.381 -0.8382)
			(stroke
				(width 0)
				(type default)
			)
			(fill no)
			(layer "F.CrtYd")
		)
		(fp_rect
			(start -0.381 0.8382)
			(end 0.381 -0.8382)
			(stroke
				(width 0)
				(type default)
			)
			(fill no)
			(layer "F.Fab")
		)
		(pad "1" smd custom
			(at 0 -0.4318)
			(size 0.127 0.127)
			(layers "F.Cu" "F.Mask" "F.Paste")
			(net "VR_PVCCP_ISEN1_R")
			(options
				(clearance outline)
				(anchor circle)
			)
			(primitives
				(gr_poly
					(pts
						(arc
							(start -0.2032 -0.2794)
							(mid -0.239121 -0.264521)
							(end -0.254 -0.2286)
						)
						(arc
							(start -0.254 0.2286)
							(mid -0.239121 0.264521)
							(end -0.2032 0.2794)
						)
						(arc
							(start 0.2032 0.2794)
							(mid 0.239121 0.264521)
							(end 0.254 0.2286)
						)
						(arc
							(start 0.254 -0.2286)
							(mid 0.239121 -0.264521)
							(end 0.2032 -0.2794)
						)
					)
					(width 0)
					(fill yes)
				)
			)
		)
		(pad "2" smd custom
			(at 0 0.4318)
			(size 0.127 0.127)
			(layers "F.Cu" "F.Mask" "F.Paste")
			(net "VR_PVCCP_ISEN1")
			(options
				(clearance outline)
				(anchor circle)
			)
			(primitives
				(gr_poly
					(pts
						(arc
							(start -0.2032 -0.2794)
							(mid -0.239121 -0.264521)
							(end -0.254 -0.2286)
						)
						(arc
							(start -0.254 0.2286)
							(mid -0.239121 0.264521)
							(end -0.2032 0.2794)
						)
						(arc
							(start 0.2032 0.2794)
							(mid 0.239121 0.264521)
							(end 0.254 0.2286)
						)
						(arc
							(start 0.254 -0.2286)
							(mid 0.239121 -0.264521)
							(end 0.2032 -0.2794)
						)
					)
					(width 0)
					(fill yes)
				)
			)
		)
	)
	(footprint ""
		(layer "F.Cu")
		(at 18.3896 -50.9524)
		(property "Reference" "PR88"
			(at 0 0 0)
			(layer "F.SilkS")
			(hide yes)
			(effects
				(font
					(size 1.27 1.27)
				)
			)
		)
		(property "Value" "100R3F-1-GP"
			(at -0.0254 -2.0193 0)
			(unlocked yes)
			(layer "F.Fab")
			(hide yes)
			(effects
				(font
					(size 1.016 1.016)
					(thickness 0.1524)
				)
			)
		)
		(property "Device Type" "R603H22"
			(at -0.0254 -3.5433 0)
			(unlocked yes)
			(layer "F.Fab")
			(hide yes)
			(effects
				(font
					(size 1.016 1.016)
					(thickness 0.1524)
				)
			)
		)
		(duplicate_pad_numbers_are_jumpers no)
		(fp_line
			(start -0.2032 0)
			(end -0.4191 0)
			(stroke
				(width 0.2032)
				(type default)
			)
			(layer "F.SilkS")
		)
		(fp_line
			(start 0.4318 0)
			(end 0.2032 0)
			(stroke
				(width 0.2032)
				(type default)
			)
			(layer "F.SilkS")
		)
		(fp_rect
			(start -0.635 1.1811)
			(end 0.635 -1.1811)
			(stroke
				(width 0)
				(type default)
			)
			(fill no)
			(layer "F.CrtYd")
		)
		(fp_rect
			(start -0.635 1.1811)
			(end 0.635 -1.1811)
			(stroke
				(width 0)
				(type default)
			)
			(fill no)
			(layer "F.Fab")
		)
		(pad "1" smd custom
			(at 0 -0.6604)
			(size 0.19685 0.19685)
			(layers "F.Cu" "F.Mask" "F.Paste")
			(net "VR_PVCCP_FB")
			(options
				(clearance outline)
				(anchor circle)
			)
			(primitives
				(gr_poly
					(pts
						(arc
							(start 0.508 -0.2921)
							(mid 0.478242 -0.363942)
							(end 0.4064 -0.3937)
						)
						(arc
							(start -0.4064 -0.3937)
							(mid -0.478242 -0.363942)
							(end -0.508 -0.2921)
						)
						(arc
							(start -0.508 0.2921)
							(mid -0.478242 0.363942)
							(end -0.4064 0.3937)
						)
						(arc
							(start 0.4064 0.3937)
							(mid 0.478242 0.363942)
							(end 0.508 0.2921)
						)
					)
					(width 0)
					(fill yes)
				)
			)
		)
		(pad "2" smd custom
			(at 0 0.6604)
			(size 0.19685 0.19685)
			(layers "F.Cu" "F.Mask" "F.Paste")
			(net "VR_PVCCP_VSEN_R")
			(options
				(clearance outline)
				(anchor circle)
			)
			(primitives
				(gr_poly
					(pts
						(arc
							(start 0.508 -0.2921)
							(mid 0.478242 -0.363942)
							(end 0.4064 -0.3937)
						)
						(arc
							(start -0.4064 -0.3937)
							(mid -0.478242 -0.363942)
							(end -0.508 -0.2921)
						)
						(arc
							(start -0.508 0.2921)
							(mid -0.478242 0.363942)
							(end -0.4064 0.3937)
						)
						(arc
							(start 0.4064 0.3937)
							(mid 0.478242 0.363942)
							(end 0.508 0.2921)
						)
					)
					(width 0)
					(fill yes)
				)
			)
		)
	)
	(footprint ""
		(layer "F.Cu")
		(at 181.102 -38.862 -90)
		(property "Reference" "R90"
			(at 0 0 270)
			(layer "F.SilkS")
			(hide yes)
			(effects
				(font
					(size 1.27 1.27)
				)
			)
		)
		(property "Value" "100R2F-L1-GP-U"
			(at 0.064008 -3.993896 270)
			(unlocked yes)
			(layer "F.Fab")
			(hide yes)
			(effects
				(font
					(size 1.016 1.016)
					(thickness 0.1524)
				)
			)
		)
		(property "Device Type" "R402H14"
			(at 0.064008 -5.517896 270)
			(unlocked yes)
			(layer "F.Fab")
			(hide yes)
			(effects
				(font
					(size 1.016 1.016)
					(thickness 0.1524)
				)
			)
		)
		(duplicate_pad_numbers_are_jumpers no)
		(fp_rect
			(start -0.381 0.8382)
			(end 0.381 -0.8382)
			(stroke
				(width 0)
				(type default)
			)
			(fill no)
			(layer "F.CrtYd")
		)
		(fp_rect
			(start -0.381 0.8382)
			(end 0.381 -0.8382)
			(stroke
				(width 0)
				(type default)
			)
			(fill no)
			(layer "F.Fab")
		)
		(pad "1" smd custom
			(at 0 -0.4318 270)
			(size 0.127 0.127)
			(layers "F.Cu" "F.Mask" "F.Paste")
			(net "SVID_CPU_DATA")
			(options
				(clearance outline)
				(anchor circle)
			)
			(primitives
				(gr_poly
					(pts
						(arc
							(start -0.2032 -0.2794)
							(mid -0.239121 -0.264521)
							(end -0.254 -0.2286)
						)
						(arc
							(start -0.254 0.2286)
							(mid -0.239121 0.264521)
							(end -0.2032 0.2794)
						)
						(arc
							(start 0.2032 0.2794)
							(mid 0.239121 0.264521)
							(end 0.254 0.2286)
						)
						(arc
							(start 0.254 -0.2286)
							(mid 0.239121 -0.264521)
							(end 0.2032 -0.2794)
						)
					)
					(width 0)
					(fill yes)
				)
			)
		)
		(pad "2" smd custom
			(at 0 0.4318 270)
			(size 0.127 0.127)
			(layers "F.Cu" "F.Mask" "F.Paste")
			(net "P1V0")
			(options
				(clearance outline)
				(anchor circle)
			)
			(primitives
				(gr_poly
					(pts
						(arc
							(start -0.2032 -0.2794)
							(mid -0.239121 -0.264521)
							(end -0.254 -0.2286)
						)
						(arc
							(start -0.254 0.2286)
							(mid -0.239121 0.264521)
							(end -0.2032 0.2794)
						)
						(arc
							(start 0.2032 0.2794)
							(mid 0.239121 0.264521)
							(end 0.254 0.2286)
						)
						(arc
							(start 0.254 -0.2286)
							(mid 0.239121 -0.264521)
							(end 0.2032 -0.2794)
						)
					)
					(width 0)
					(fill yes)
				)
			)
		)
	)
	(footprint ""
		(layer "F.Cu")
		(at 13.97 -25.781 -90)
		(property "Reference" "PU7"
			(at 0 0 270)
			(layer "F.SilkS")
			(hide yes)
			(effects
				(font
					(size 1.27 1.27)
				)
			)
		)
		(property "Value" "TPS53319DQPR-GP"
			(at 4.1402 -3.8227 270)
			(unlocked yes)
			(layer "F.Fab")
			(hide yes)
			(effects
				(font
					(size 1.016 1.016)
					(thickness 0.1524)
				)
			)
		)
		(property "Device Type" "QFN22G6050-G6133H60"
			(at 4.1402 -5.3467 270)
			(unlocked yes)
			(layer "F.Fab")
			(hide yes)
			(effects
				(font
					(size 1.016 1.016)
					(thickness 0.1524)
				)
			)
		)
		(duplicate_pad_numbers_are_jumpers no)
		(fp_poly
			(pts
				(xy 2.49301 -2.897124) (xy 2.885186 -3.2893) (xy 2.100834 -3.2893)
			)
			(stroke
				(width 0)
				(type default)
			)
			(fill yes)
			(layer "F.SilkS")
		)
		(fp_rect
			(start -3.2512 2.8829)
			(end 3.2512 -2.8829)
			(stroke
				(width 0)
				(type default)
			)
			(fill no)
			(layer "F.CrtYd")
		)
		(fp_rect
			(start -3.2512 2.8829)
			(end 3.2512 -2.8829)
			(stroke
				(width 0)
				(type default)
			)
			(fill no)
			(layer "F.Fab")
		)
		(pad "1" smd rect
			(at 2.500122 -2.322322 270)
			(size 0.3048 0.8636)
			(layers "F.Cu" "F.Mask" "F.Paste")
			(net "P1V0_VFB")
		)
		(pad "2" smd rect
			(at 1.999996 -2.322322 270)
			(size 0.3048 0.8636)
			(layers "F.Cu" "F.Mask" "F.Paste")
			(net "P1V0_EN")
		)
		(pad "3" smd rect
			(at 1.500124 -2.322322 270)
			(size 0.3048 0.8636)
			(layers "F.Cu" "F.Mask" "F.Paste")
			(net "PG_P1V0")
		)
		(pad "4" smd rect
			(at 0.999998 -2.322322 270)
			(size 0.3048 0.8636)
			(layers "F.Cu" "F.Mask" "F.Paste")
			(net "P1V0_VBST")
		)
		(pad "5" smd rect
			(at 0.500126 -2.322322 270)
			(size 0.3048 0.8636)
			(layers "F.Cu" "F.Mask" "F.Paste")
			(net "P1V0_ROVP")
		)
		(pad "6" smd rect
			(at 0 -2.322322 270)
			(size 0.3048 0.8636)
			(layers "F.Cu" "F.Mask" "F.Paste")
			(net "P1V0_LX")
		)
		(pad "7" smd rect
			(at -0.500126 -2.322322 270)
			(size 0.3048 0.8636)
			(layers "F.Cu" "F.Mask" "F.Paste")
			(net "P1V0_LX")
		)
		(pad "8" smd rect
			(at -0.999998 -2.322322 270)
			(size 0.3048 0.8636)
			(layers "F.Cu" "F.Mask" "F.Paste")
			(net "P1V0_LX")
		)
		(pad "9" smd rect
			(at -1.500124 -2.322322 270)
			(size 0.3048 0.8636)
			(layers "F.Cu" "F.Mask" "F.Paste")
			(net "P1V0_LX")
		)
		(pad "10" smd rect
			(at -1.999996 -2.322322 270)
			(size 0.3048 0.8636)
			(layers "F.Cu" "F.Mask" "F.Paste")
			(net "P1V0_LX")
		)
		(pad "11" smd rect
			(at -2.500122 -2.322322 270)
			(size 0.3048 0.8636)
			(layers "F.Cu" "F.Mask" "F.Paste")
			(net "P1V0_LX")
		)
		(pad "12" smd rect
			(at -2.500122 2.322322 270)
			(size 0.3048 0.8636)
			(layers "F.Cu" "F.Mask" "F.Paste")
			(net "P1V0_VIN")
		)
		(pad "13" smd rect
			(at -1.999996 2.322322 270)
			(size 0.3048 0.8636)
			(layers "F.Cu" "F.Mask" "F.Paste")
			(net "P1V0_VIN")
		)
		(pad "14" smd rect
			(at -1.500124 2.322322 270)
			(size 0.3048 0.8636)
			(layers "F.Cu" "F.Mask" "F.Paste")
			(net "P1V0_VIN")
		)
		(pad "15" smd rect
			(at -0.999998 2.322322 270)
			(size 0.3048 0.8636)
			(layers "F.Cu" "F.Mask" "F.Paste")
			(net "P1V0_VIN")
		)
		(pad "16" smd rect
			(at -0.500126 2.322322 270)
			(size 0.3048 0.8636)
			(layers "F.Cu" "F.Mask" "F.Paste")
			(net "P1V0_VIN")
		)
		(pad "17" smd rect
			(at 0 2.322322 270)
			(size 0.3048 0.8636)
			(layers "F.Cu" "F.Mask" "F.Paste")
			(net "P1V0_VIN")
		)
		(pad "18" smd rect
			(at 0.500126 2.322322 270)
			(size 0.3048 0.8636)
			(layers "F.Cu" "F.Mask" "F.Paste")
			(net "P1V0_VREG")
		)
		(pad "19" smd rect
			(at 0.999998 2.322322 270)
			(size 0.3048 0.8636)
			(layers "F.Cu" "F.Mask" "F.Paste")
			(net "P1V0_VDD")
		)
		(pad "20" smd rect
			(at 1.500124 2.322322 270)
			(size 0.3048 0.8636)
			(layers "F.Cu" "F.Mask" "F.Paste")
			(net "P1V0_MODE")
		)
		(pad "21" smd rect
			(at 1.999996 2.322322 270)
			(size 0.3048 0.8636)
			(layers "F.Cu" "F.Mask" "F.Paste")
			(net "P1V0_TRIP")
		)
		(pad "22" smd rect
			(at 2.500122 2.322322 270)
			(size 0.3048 0.8636)
			(layers "F.Cu" "F.Mask" "F.Paste")
			(net "P1V0_RF")
		)
		(pad "23" smd custom
			(at 0 0 270)
			(size 0.83185 0.83185)
			(layers "F.Cu" "F.Mask" "F.Paste")
			(net "GND")
			(options
				(clearance outline)
				(anchor circle)
			)
			(primitives
				(gr_poly
					(pts
						(xy -2.7813 1.6637) (xy -2.7813 1.2954) (xy -3.048 1.2954) (xy -3.048 0.9525) (xy -2.7813 0.9525)
						(xy -2.7813 -0.9525) (xy -3.048 -0.9525) (xy -3.048 -1.2954) (xy -2.7813 -1.2954) (xy -2.7813 -1.6637)
						(xy 2.7813 -1.6637) (xy 2.7813 -1.2954) (xy 3.048 -1.2954) (xy 3.048 -0.9525) (xy 2.7813 -0.9525)
						(xy 2.7813 0.9525) (xy 3.048 0.9525) (xy 3.048 1.2954) (xy 2.7813 1.2954) (xy 2.7813 1.6637)
					)
					(width 0)
					(fill yes)
				)
			)
		)
	)
	(footprint ""
		(layer "F.Cu")
		(at 130.302 -44.704 -90)
		(property "Reference" "C12"
			(at 0 0 270)
			(layer "F.SilkS")
			(hide yes)
			(effects
				(font
					(size 1.27 1.27)
				)
			)
		)
		(property "Value" "SCD1U10V2KX-5GP"
			(at 1.1811 -2.7051 270)
			(unlocked yes)
			(layer "F.Fab")
			(hide yes)
			(effects
				(font
					(size 1.016 1.016)
					(thickness 0.1524)
				)
			)
		)
		(property "Device Type" "C402H22"
			(at 1.1811 -4.2291 270)
			(unlocked yes)
			(layer "F.Fab")
			(hide yes)
			(effects
				(font
					(size 1.016 1.016)
					(thickness 0.1524)
				)
			)
		)
		(duplicate_pad_numbers_are_jumpers no)
		(fp_rect
			(start -0.381 0.7366)
			(end 0.381 -0.7366)
			(stroke
				(width 0)
				(type default)
			)
			(fill no)
			(layer "F.CrtYd")
		)
		(fp_rect
			(start -0.381 0.7366)
			(end 0.381 -0.7366)
			(stroke
				(width 0)
				(type default)
			)
			(fill no)
			(layer "F.Fab")
		)
		(pad "1" smd custom
			(at 0 -0.4572 270)
			(size 0.1143 0.1143)
			(layers "F.Cu" "F.Mask" "F.Paste")
			(net "P1V2_FPGA_A")
			(options
				(clearance outline)
				(anchor circle)
			)
			(primitives
				(gr_poly
					(pts
						(arc
							(start -0.254 -0.1778)
							(mid -0.239121 -0.213721)
							(end -0.2032 -0.2286)
						)
						(arc
							(start 0.2032 -0.2286)
							(mid 0.239121 -0.213721)
							(end 0.254 -0.1778)
						)
						(arc
							(start 0.254 0.1778)
							(mid 0.239121 0.213721)
							(end 0.2032 0.2286)
						)
						(arc
							(start -0.2032 0.2286)
							(mid -0.239121 0.213721)
							(end -0.254 0.1778)
						)
					)
					(width 0)
					(fill yes)
				)
			)
		)
		(pad "2" smd custom
			(at 0 0.4572 270)
			(size 0.1143 0.1143)
			(layers "F.Cu" "F.Mask" "F.Paste")
			(net "GND")
			(options
				(clearance outline)
				(anchor circle)
			)
			(primitives
				(gr_poly
					(pts
						(arc
							(start -0.254 -0.1778)
							(mid -0.239121 -0.213721)
							(end -0.2032 -0.2286)
						)
						(arc
							(start 0.2032 -0.2286)
							(mid 0.239121 -0.213721)
							(end 0.254 -0.1778)
						)
						(arc
							(start 0.254 0.1778)
							(mid 0.239121 0.213721)
							(end 0.2032 0.2286)
						)
						(arc
							(start -0.2032 0.2286)
							(mid -0.239121 0.213721)
							(end -0.254 0.1778)
						)
					)
					(width 0)
					(fill yes)
				)
			)
		)
	)
	(footprint ""
		(layer "F.Cu")
		(at 197.993 -9.272778)
		(property "Reference" "R391"
			(at 0 0 0)
			(layer "F.SilkS")
			(hide yes)
			(effects
				(font
					(size 1.27 1.27)
				)
			)
		)
		(property "Value" "0R2J-2-GP"
			(at 0.064008 -3.993896 0)
			(unlocked yes)
			(layer "F.Fab")
			(hide yes)
			(effects
				(font
					(size 1.016 1.016)
					(thickness 0.1524)
				)
			)
		)
		(property "Device Type" "R402H16"
			(at 0.064008 -5.517896 0)
			(unlocked yes)
			(layer "F.Fab")
			(hide yes)
			(effects
				(font
					(size 1.016 1.016)
					(thickness 0.1524)
				)
			)
		)
		(duplicate_pad_numbers_are_jumpers no)
		(fp_rect
			(start -0.381 0.8382)
			(end 0.381 -0.8382)
			(stroke
				(width 0)
				(type default)
			)
			(fill no)
			(layer "F.CrtYd")
		)
		(fp_rect
			(start -0.381 0.8382)
			(end 0.381 -0.8382)
			(stroke
				(width 0)
				(type default)
			)
			(fill no)
			(layer "F.Fab")
		)
		(pad "1" smd custom
			(at 0 -0.4318)
			(size 0.127 0.127)
			(layers "F.Cu" "F.Mask" "F.Paste")
			(net "SMB_M_B1_R_DATA")
			(options
				(clearance outline)
				(anchor circle)
			)
			(primitives
				(gr_poly
					(pts
						(arc
							(start -0.2032 -0.2794)
							(mid -0.239121 -0.264521)
							(end -0.254 -0.2286)
						)
						(arc
							(start -0.254 0.2286)
							(mid -0.239121 0.264521)
							(end -0.2032 0.2794)
						)
						(arc
							(start 0.2032 0.2794)
							(mid 0.239121 0.264521)
							(end 0.254 0.2286)
						)
						(arc
							(start 0.254 -0.2286)
							(mid 0.239121 -0.264521)
							(end 0.2032 -0.2794)
						)
					)
					(width 0)
					(fill yes)
				)
			)
		)
		(pad "2" smd custom
			(at 0 0.4318)
			(size 0.127 0.127)
			(layers "F.Cu" "F.Mask" "F.Paste")
			(net "SMB_HOST_LV_DATA")
			(options
				(clearance outline)
				(anchor circle)
			)
			(primitives
				(gr_poly
					(pts
						(arc
							(start -0.2032 -0.2794)
							(mid -0.239121 -0.264521)
							(end -0.254 -0.2286)
						)
						(arc
							(start -0.254 0.2286)
							(mid -0.239121 0.264521)
							(end -0.2032 0.2794)
						)
						(arc
							(start 0.2032 0.2794)
							(mid 0.239121 0.264521)
							(end 0.254 0.2286)
						)
						(arc
							(start 0.254 -0.2286)
							(mid 0.239121 -0.264521)
							(end 0.2032 -0.2794)
						)
					)
					(width 0)
					(fill yes)
				)
			)
		)
	)
	(footprint ""
		(layer "F.Cu")
		(at 70.358 -57.6072)
		(property "Reference" "C78"
			(at 0 0 0)
			(layer "F.SilkS")
			(hide yes)
			(effects
				(font
					(size 1.27 1.27)
				)
			)
		)
		(property "Value" "SCD1U16V2KX-3GP"
			(at 1.8923 -1.2065 0)
			(unlocked yes)
			(layer "F.Fab")
			(hide yes)
			(effects
				(font
					(size 1.016 1.016)
					(thickness 0.1524)
				)
			)
		)
		(property "Device Type" "C402H22"
			(at 1.8923 -2.7305 0)
			(unlocked yes)
			(layer "F.Fab")
			(hide yes)
			(effects
				(font
					(size 1.016 1.016)
					(thickness 0.1524)
				)
			)
		)
		(duplicate_pad_numbers_are_jumpers no)
		(fp_rect
			(start -0.381 0.7366)
			(end 0.381 -0.7366)
			(stroke
				(width 0)
				(type default)
			)
			(fill no)
			(layer "F.CrtYd")
		)
		(fp_rect
			(start -0.381 0.7366)
			(end 0.381 -0.7366)
			(stroke
				(width 0)
				(type default)
			)
			(fill no)
			(layer "F.Fab")
		)
		(pad "1" smd custom
			(at 0 -0.4572)
			(size 0.1143 0.1143)
			(layers "F.Cu" "F.Mask" "F.Paste")
			(net "P1V8_SENSE")
			(options
				(clearance outline)
				(anchor circle)
			)
			(primitives
				(gr_poly
					(pts
						(arc
							(start -0.254 -0.1778)
							(mid -0.239121 -0.213721)
							(end -0.2032 -0.2286)
						)
						(arc
							(start 0.2032 -0.2286)
							(mid 0.239121 -0.213721)
							(end 0.254 -0.1778)
						)
						(arc
							(start 0.254 0.1778)
							(mid 0.239121 0.213721)
							(end 0.2032 0.2286)
						)
						(arc
							(start -0.2032 0.2286)
							(mid -0.239121 0.213721)
							(end -0.254 0.1778)
						)
					)
					(width 0)
					(fill yes)
				)
			)
		)
		(pad "2" smd custom
			(at 0 0.4572)
			(size 0.1143 0.1143)
			(layers "F.Cu" "F.Mask" "F.Paste")
			(net "GND")
			(options
				(clearance outline)
				(anchor circle)
			)
			(primitives
				(gr_poly
					(pts
						(arc
							(start -0.254 -0.1778)
							(mid -0.239121 -0.213721)
							(end -0.2032 -0.2286)
						)
						(arc
							(start 0.2032 -0.2286)
							(mid 0.239121 -0.213721)
							(end 0.254 -0.1778)
						)
						(arc
							(start 0.254 0.1778)
							(mid 0.239121 0.213721)
							(end 0.2032 0.2286)
						)
						(arc
							(start -0.2032 0.2286)
							(mid -0.239121 0.213721)
							(end -0.254 0.1778)
						)
					)
					(width 0)
					(fill yes)
				)
			)
		)
	)
	(footprint ""
		(layer "F.Cu")
		(at 81.026 -65.913)
		(property "Reference" "R186"
			(at 0 0 0)
			(layer "F.SilkS")
			(hide yes)
			(effects
				(font
					(size 1.27 1.27)
				)
			)
		)
		(property "Value" "4K7R2F-GP"
			(at 0.064008 -3.993896 0)
			(unlocked yes)
			(layer "F.Fab")
			(hide yes)
			(effects
				(font
					(size 1.016 1.016)
					(thickness 0.1524)
				)
			)
		)
		(property "Device Type" "R402H16"
			(at 0.064008 -5.517896 0)
			(unlocked yes)
			(layer "F.Fab")
			(hide yes)
			(effects
				(font
					(size 1.016 1.016)
					(thickness 0.1524)
				)
			)
		)
		(duplicate_pad_numbers_are_jumpers no)
		(fp_rect
			(start -0.381 0.8382)
			(end 0.381 -0.8382)
			(stroke
				(width 0)
				(type default)
			)
			(fill no)
			(layer "F.CrtYd")
		)
		(fp_rect
			(start -0.381 0.8382)
			(end 0.381 -0.8382)
			(stroke
				(width 0)
				(type default)
			)
			(fill no)
			(layer "F.Fab")
		)
		(pad "1" smd custom
			(at 0 -0.4318)
			(size 0.127 0.127)
			(layers "F.Cu" "F.Mask" "F.Paste")
			(net "P3V3_STBY")
			(options
				(clearance outline)
				(anchor circle)
			)
			(primitives
				(gr_poly
					(pts
						(arc
							(start -0.2032 -0.2794)
							(mid -0.239121 -0.264521)
							(end -0.254 -0.2286)
						)
						(arc
							(start -0.254 0.2286)
							(mid -0.239121 0.264521)
							(end -0.2032 0.2794)
						)
						(arc
							(start 0.2032 0.2794)
							(mid 0.239121 0.264521)
							(end 0.254 0.2286)
						)
						(arc
							(start 0.254 -0.2286)
							(mid 0.239121 -0.264521)
							(end 0.2032 -0.2794)
						)
					)
					(width 0)
					(fill yes)
				)
			)
		)
		(pad "2" smd custom
			(at 0 0.4318)
			(size 0.127 0.127)
			(layers "F.Cu" "F.Mask" "F.Paste")
			(net "VOL1_SEN_ADDR0")
			(options
				(clearance outline)
				(anchor circle)
			)
			(primitives
				(gr_poly
					(pts
						(arc
							(start -0.2032 -0.2794)
							(mid -0.239121 -0.264521)
							(end -0.254 -0.2286)
						)
						(arc
							(start -0.254 0.2286)
							(mid -0.239121 0.264521)
							(end -0.2032 0.2794)
						)
						(arc
							(start 0.2032 0.2794)
							(mid 0.239121 0.264521)
							(end 0.254 0.2286)
						)
						(arc
							(start 0.254 -0.2286)
							(mid 0.239121 -0.264521)
							(end 0.2032 -0.2794)
						)
					)
					(width 0)
					(fill yes)
				)
			)
		)
	)
	(footprint ""
		(layer "F.Cu")
		(at 8.509 -62.738 90)
		(property "Reference" "C196"
			(at 0 0 90)
			(layer "F.SilkS")
			(hide yes)
			(effects
				(font
					(size 1.27 1.27)
				)
			)
		)
		(property "Value" "SCD1U16V2KX-3GP"
			(at 1.1811 -2.7051 90)
			(unlocked yes)
			(layer "F.Fab")
			(hide yes)
			(effects
				(font
					(size 1.016 1.016)
					(thickness 0.1524)
				)
			)
		)
		(property "Device Type" "C402H22"
			(at 1.1811 -4.2291 90)
			(unlocked yes)
			(layer "F.Fab")
			(hide yes)
			(effects
				(font
					(size 1.016 1.016)
					(thickness 0.1524)
				)
			)
		)
		(duplicate_pad_numbers_are_jumpers no)
		(fp_rect
			(start -0.381 0.7366)
			(end 0.381 -0.7366)
			(stroke
				(width 0)
				(type default)
			)
			(fill no)
			(layer "F.CrtYd")
		)
		(fp_rect
			(start -0.381 0.7366)
			(end 0.381 -0.7366)
			(stroke
				(width 0)
				(type default)
			)
			(fill no)
			(layer "F.Fab")
		)
		(pad "1" smd custom
			(at 0 -0.4572 90)
			(size 0.1143 0.1143)
			(layers "F.Cu" "F.Mask" "F.Paste")
			(net "P2E_CPU_NGFF_TX_DP15")
			(options
				(clearance outline)
				(anchor circle)
			)
			(primitives
				(gr_poly
					(pts
						(arc
							(start -0.254 -0.1778)
							(mid -0.239121 -0.213721)
							(end -0.2032 -0.2286)
						)
						(arc
							(start 0.2032 -0.2286)
							(mid 0.239121 -0.213721)
							(end 0.254 -0.1778)
						)
						(arc
							(start 0.254 0.1778)
							(mid 0.239121 0.213721)
							(end 0.2032 0.2286)
						)
						(arc
							(start -0.2032 0.2286)
							(mid -0.239121 0.213721)
							(end -0.254 0.1778)
						)
					)
					(width 0)
					(fill yes)
				)
			)
		)
		(pad "2" smd custom
			(at 0 0.4572 90)
			(size 0.1143 0.1143)
			(layers "F.Cu" "F.Mask" "F.Paste")
			(net "P2E_CPU_NGFF_C_TX_DP15")
			(options
				(clearance outline)
				(anchor circle)
			)
			(primitives
				(gr_poly
					(pts
						(arc
							(start -0.254 -0.1778)
							(mid -0.239121 -0.213721)
							(end -0.2032 -0.2286)
						)
						(arc
							(start 0.2032 -0.2286)
							(mid 0.239121 -0.213721)
							(end 0.254 -0.1778)
						)
						(arc
							(start 0.254 0.1778)
							(mid 0.239121 0.213721)
							(end 0.2032 0.2286)
						)
						(arc
							(start -0.2032 0.2286)
							(mid -0.239121 0.213721)
							(end -0.254 0.1778)
						)
					)
					(width 0)
					(fill yes)
				)
			)
		)
	)
	(footprint ""
		(layer "F.Cu")
		(at 79.883 -65.913)
		(property "Reference" "R183"
			(at 0 0 0)
			(layer "F.SilkS")
			(hide yes)
			(effects
				(font
					(size 1.27 1.27)
				)
			)
		)
		(property "Value" "4K7R2F-GP"
			(at 1.7907 -1.1176 0)
			(unlocked yes)
			(layer "F.Fab")
			(hide yes)
			(effects
				(font
					(size 1.016 1.016)
					(thickness 0.1524)
				)
			)
		)
		(property "Device Type" "R402H16"
			(at 1.7907 -2.6416 0)
			(unlocked yes)
			(layer "F.Fab")
			(hide yes)
			(effects
				(font
					(size 1.016 1.016)
					(thickness 0.1524)
				)
			)
		)
		(duplicate_pad_numbers_are_jumpers no)
		(fp_rect
			(start -0.381 0.8382)
			(end 0.381 -0.8382)
			(stroke
				(width 0)
				(type default)
			)
			(fill no)
			(layer "F.CrtYd")
		)
		(fp_rect
			(start -0.381 0.8382)
			(end 0.381 -0.8382)
			(stroke
				(width 0)
				(type default)
			)
			(fill no)
			(layer "F.Fab")
		)
		(pad "1" smd custom
			(at 0 -0.4318)
			(size 0.127 0.127)
			(layers "F.Cu" "F.Mask" "F.Paste")
			(net "P3V3_STBY")
			(options
				(clearance outline)
				(anchor circle)
			)
			(primitives
				(gr_poly
					(pts
						(arc
							(start -0.2032 -0.2794)
							(mid -0.239121 -0.264521)
							(end -0.254 -0.2286)
						)
						(arc
							(start -0.254 0.2286)
							(mid -0.239121 0.264521)
							(end -0.2032 0.2794)
						)
						(arc
							(start 0.2032 0.2794)
							(mid 0.239121 0.264521)
							(end 0.254 0.2286)
						)
						(arc
							(start 0.254 -0.2286)
							(mid 0.239121 -0.264521)
							(end 0.2032 -0.2794)
						)
					)
					(width 0)
					(fill yes)
				)
			)
		)
		(pad "2" smd custom
			(at 0 0.4318)
			(size 0.127 0.127)
			(layers "F.Cu" "F.Mask" "F.Paste")
			(net "VOL1_SEN_ADDR1")
			(options
				(clearance outline)
				(anchor circle)
			)
			(primitives
				(gr_poly
					(pts
						(arc
							(start -0.2032 -0.2794)
							(mid -0.239121 -0.264521)
							(end -0.254 -0.2286)
						)
						(arc
							(start -0.254 0.2286)
							(mid -0.239121 0.264521)
							(end -0.2032 0.2794)
						)
						(arc
							(start 0.2032 0.2794)
							(mid 0.239121 0.264521)
							(end 0.254 0.2286)
						)
						(arc
							(start 0.254 -0.2286)
							(mid 0.239121 -0.264521)
							(end 0.2032 -0.2794)
						)
					)
					(width 0)
					(fill yes)
				)
			)
		)
	)
	(footprint ""
		(layer "F.Cu")
		(at 118.237 -37.735002 180)
		(property "Reference" "PC79"
			(at 0 0 180)
			(layer "F.SilkS")
			(hide yes)
			(effects
				(font
					(size 1.27 1.27)
				)
			)
		)
		(property "Value" "SCD01U16V2KX-3GP"
			(at 1.1811 -2.7051 180)
			(unlocked yes)
			(layer "F.Fab")
			(hide yes)
			(effects
				(font
					(size 1.016 1.016)
					(thickness 0.1524)
				)
			)
		)
		(property "Device Type" "C402H22"
			(at 1.1811 -4.2291 180)
			(unlocked yes)
			(layer "F.Fab")
			(hide yes)
			(effects
				(font
					(size 1.016 1.016)
					(thickness 0.1524)
				)
			)
		)
		(duplicate_pad_numbers_are_jumpers no)
		(fp_rect
			(start -0.381 0.7366)
			(end 0.381 -0.7366)
			(stroke
				(width 0)
				(type default)
			)
			(fill no)
			(layer "F.CrtYd")
		)
		(fp_rect
			(start -0.381 0.7366)
			(end 0.381 -0.7366)
			(stroke
				(width 0)
				(type default)
			)
			(fill no)
			(layer "F.Fab")
		)
		(pad "1" smd custom
			(at 0 -0.4572 180)
			(size 0.1143 0.1143)
			(layers "F.Cu" "F.Mask" "F.Paste")
			(net "VR_PVCCP_RTN")
			(options
				(clearance outline)
				(anchor circle)
			)
			(primitives
				(gr_poly
					(pts
						(arc
							(start -0.254 -0.1778)
							(mid -0.239121 -0.213721)
							(end -0.2032 -0.2286)
						)
						(arc
							(start 0.2032 -0.2286)
							(mid 0.239121 -0.213721)
							(end 0.254 -0.1778)
						)
						(arc
							(start 0.254 0.1778)
							(mid 0.239121 0.213721)
							(end 0.2032 0.2286)
						)
						(arc
							(start -0.2032 0.2286)
							(mid -0.239121 0.213721)
							(end -0.254 0.1778)
						)
					)
					(width 0)
					(fill yes)
				)
			)
		)
		(pad "2" smd custom
			(at 0 0.4572 180)
			(size 0.1143 0.1143)
			(layers "F.Cu" "F.Mask" "F.Paste")
			(net "GND")
			(options
				(clearance outline)
				(anchor circle)
			)
			(primitives
				(gr_poly
					(pts
						(arc
							(start -0.254 -0.1778)
							(mid -0.239121 -0.213721)
							(end -0.2032 -0.2286)
						)
						(arc
							(start 0.2032 -0.2286)
							(mid 0.239121 -0.213721)
							(end 0.254 -0.1778)
						)
						(arc
							(start 0.254 0.1778)
							(mid 0.239121 0.213721)
							(end 0.2032 0.2286)
						)
						(arc
							(start -0.2032 0.2286)
							(mid -0.239121 0.213721)
							(end -0.254 0.1778)
						)
					)
					(width 0)
					(fill yes)
				)
			)
		)
	)
	(footprint ""
		(layer "F.Cu")
		(at 18.796 -14.224 180)
		(property "Reference" "C321"
			(at 0 0 180)
			(layer "F.SilkS")
			(hide yes)
			(effects
				(font
					(size 1.27 1.27)
				)
			)
		)
		(property "Value" "SC22U25V5MX-GP"
			(at 0 -4.9022 180)
			(unlocked yes)
			(layer "F.Fab")
			(hide yes)
			(effects
				(font
					(size 1.016 1.016)
					(thickness 0.1524)
				)
			)
		)
		(property "Device Type" "C805H58"
			(at 0 -6.8072 180)
			(unlocked yes)
			(layer "F.Fab")
			(hide yes)
			(effects
				(font
					(size 1.016 1.016)
					(thickness 0.1524)
				)
			)
		)
		(duplicate_pad_numbers_are_jumpers no)
		(fp_line
			(start 0.6096 0)
			(end -0.6096 0)
			(stroke
				(width 0.3048)
				(type default)
			)
			(layer "F.SilkS")
		)
		(fp_poly
			(pts
				(xy -0.9017 1.4351) (xy 0.9017 1.4351) (xy 0.9017 -1.4351) (xy -0.9017 -1.4351)
			)
			(stroke
				(width 0)
				(type default)
			)
			(fill no)
			(layer "F.CrtYd")
		)
		(fp_poly
			(pts
				(xy 0.9017 1.4351) (xy 0.9017 -1.4351) (xy -0.9017 -1.4351) (xy -0.9017 1.4351)
			)
			(stroke
				(width 0)
				(type default)
			)
			(fill no)
			(layer "F.Fab")
		)
		(pad "1" smd rect
			(at 0 -0.8382 180)
			(size 1.5494 0.9398)
			(layers "F.Cu" "F.Mask" "F.Paste")
			(net "P12V")
		)
		(pad "2" smd rect
			(at 0 0.8382 180)
			(size 1.5494 0.9398)
			(layers "F.Cu" "F.Mask" "F.Paste")
			(net "GND")
		)
	)
	(footprint ""
		(layer "F.Cu")
		(at 19.2278 -49.276 -90)
		(property "Reference" "PC67"
			(at 0 0 270)
			(layer "F.SilkS")
			(hide yes)
			(effects
				(font
					(size 1.27 1.27)
				)
			)
		)
		(property "Value" "SC4700P50V2KX-1GP"
			(at 1.8923 -1.2065 270)
			(unlocked yes)
			(layer "F.Fab")
			(hide yes)
			(effects
				(font
					(size 1.016 1.016)
					(thickness 0.1524)
				)
			)
		)
		(property "Device Type" "C402H22"
			(at 1.8923 -2.7305 270)
			(unlocked yes)
			(layer "F.Fab")
			(hide yes)
			(effects
				(font
					(size 1.016 1.016)
					(thickness 0.1524)
				)
			)
		)
		(duplicate_pad_numbers_are_jumpers no)
		(fp_rect
			(start -0.381 0.7366)
			(end 0.381 -0.7366)
			(stroke
				(width 0)
				(type default)
			)
			(fill no)
			(layer "F.CrtYd")
		)
		(fp_rect
			(start -0.381 0.7366)
			(end 0.381 -0.7366)
			(stroke
				(width 0)
				(type default)
			)
			(fill no)
			(layer "F.Fab")
		)
		(pad "1" smd custom
			(at 0 -0.4572 270)
			(size 0.1143 0.1143)
			(layers "F.Cu" "F.Mask" "F.Paste")
			(net "VR_PVCCP_FB_RC1")
			(options
				(clearance outline)
				(anchor circle)
			)
			(primitives
				(gr_poly
					(pts
						(arc
							(start -0.254 -0.1778)
							(mid -0.239121 -0.213721)
							(end -0.2032 -0.2286)
						)
						(arc
							(start 0.2032 -0.2286)
							(mid 0.239121 -0.213721)
							(end 0.254 -0.1778)
						)
						(arc
							(start 0.254 0.1778)
							(mid 0.239121 0.213721)
							(end 0.2032 0.2286)
						)
						(arc
							(start -0.2032 0.2286)
							(mid -0.239121 0.213721)
							(end -0.254 0.1778)
						)
					)
					(width 0)
					(fill yes)
				)
			)
		)
		(pad "2" smd custom
			(at 0 0.4572 270)
			(size 0.1143 0.1143)
			(layers "F.Cu" "F.Mask" "F.Paste")
			(net "VR_PVCCP_VSEN_R")
			(options
				(clearance outline)
				(anchor circle)
			)
			(primitives
				(gr_poly
					(pts
						(arc
							(start -0.254 -0.1778)
							(mid -0.239121 -0.213721)
							(end -0.2032 -0.2286)
						)
						(arc
							(start 0.2032 -0.2286)
							(mid 0.239121 -0.213721)
							(end 0.254 -0.1778)
						)
						(arc
							(start 0.254 0.1778)
							(mid 0.239121 0.213721)
							(end 0.2032 0.2286)
						)
						(arc
							(start -0.2032 0.2286)
							(mid -0.239121 0.213721)
							(end -0.254 0.1778)
						)
					)
					(width 0)
					(fill yes)
				)
			)
		)
	)
	(footprint ""
		(layer "F.Cu")
		(at 168.275 -48.895 -90)
		(property "Reference" "R471"
			(at 0 0 270)
			(layer "F.SilkS")
			(hide yes)
			(effects
				(font
					(size 1.27 1.27)
				)
			)
		)
		(property "Value" "1KR2F-3-GP"
			(at 1.7907 -1.1176 270)
			(unlocked yes)
			(layer "F.Fab")
			(hide yes)
			(effects
				(font
					(size 1.016 1.016)
					(thickness 0.1524)
				)
			)
		)
		(property "Device Type" "R402H16"
			(at 1.7907 -2.6416 270)
			(unlocked yes)
			(layer "F.Fab")
			(hide yes)
			(effects
				(font
					(size 1.016 1.016)
					(thickness 0.1524)
				)
			)
		)
		(duplicate_pad_numbers_are_jumpers no)
		(fp_rect
			(start -0.381 0.8382)
			(end 0.381 -0.8382)
			(stroke
				(width 0)
				(type default)
			)
			(fill no)
			(layer "F.CrtYd")
		)
		(fp_rect
			(start -0.381 0.8382)
			(end 0.381 -0.8382)
			(stroke
				(width 0)
				(type default)
			)
			(fill no)
			(layer "F.Fab")
		)
		(pad "1" smd custom
			(at 0 -0.4318 270)
			(size 0.127 0.127)
			(layers "F.Cu" "F.Mask" "F.Paste")
			(net "P3V3_STBY")
			(options
				(clearance outline)
				(anchor circle)
			)
			(primitives
				(gr_poly
					(pts
						(arc
							(start -0.2032 -0.2794)
							(mid -0.239121 -0.264521)
							(end -0.254 -0.2286)
						)
						(arc
							(start -0.254 0.2286)
							(mid -0.239121 0.264521)
							(end -0.2032 0.2794)
						)
						(arc
							(start 0.2032 0.2794)
							(mid 0.239121 0.264521)
							(end 0.254 0.2286)
						)
						(arc
							(start 0.254 -0.2286)
							(mid 0.239121 -0.264521)
							(end 0.2032 -0.2794)
						)
					)
					(width 0)
					(fill yes)
				)
			)
		)
		(pad "2" smd custom
			(at 0 0.4318 270)
			(size 0.127 0.127)
			(layers "F.Cu" "F.Mask" "F.Paste")
			(net "JTAG_RST#")
			(options
				(clearance outline)
				(anchor circle)
			)
			(primitives
				(gr_poly
					(pts
						(arc
							(start -0.2032 -0.2794)
							(mid -0.239121 -0.264521)
							(end -0.254 -0.2286)
						)
						(arc
							(start -0.254 0.2286)
							(mid -0.239121 0.264521)
							(end -0.2032 0.2794)
						)
						(arc
							(start 0.2032 0.2794)
							(mid 0.239121 0.264521)
							(end 0.254 0.2286)
						)
						(arc
							(start 0.254 -0.2286)
							(mid 0.239121 -0.264521)
							(end 0.2032 -0.2794)
						)
					)
					(width 0)
					(fill yes)
				)
			)
		)
	)
	(footprint ""
		(layer "F.Cu")
		(at 55.499 -12.573)
		(property "Reference" "TP58"
			(at 0 0 0)
			(layer "F.SilkS")
			(hide yes)
			(effects
				(font
					(size 1.27 1.27)
				)
			)
		)
		(property "Value" "TPAD28-1-GP-U"
			(at 0.0508 -1.9304 0)
			(unlocked yes)
			(layer "F.Fab")
			(hide yes)
			(effects
				(font
					(size 1.016 1.016)
					(thickness 0.1524)
				)
			)
		)
		(property "Device Type" "TPAD28-1-U"
			(at 0.0508 -3.4544 0)
			(unlocked yes)
			(layer "F.Fab")
			(hide yes)
			(effects
				(font
					(size 1.016 1.016)
					(thickness 0.1524)
				)
			)
		)
		(duplicate_pad_numbers_are_jumpers no)
		(fp_poly
			(pts
				(arc
					(start 0.3556 0)
					(mid -0.3556 0)
					(end 0.3556 0)
				)
			)
			(stroke
				(width 0)
				(type default)
			)
			(fill no)
			(layer "F.CrtYd")
		)
		(fp_poly
			(pts
				(arc
					(start 0.9525 0)
					(mid -0.9525 0)
					(end 0.9525 0)
				)
			)
			(stroke
				(width 0)
				(type default)
			)
			(fill no)
			(layer "F.Fab")
		)
		(pad "1" smd circle
			(at 0 0)
			(size 0.7112 0.7112)
			(layers "F.Cu" "F.Mask" "F.Paste")
			(net "PCIE_RSVD_A41")
		)
	)
	(footprint ""
		(layer "F.Cu")
		(at 136.398 -60.2234 90)
		(property "Reference" "PR53"
			(at 0 0 90)
			(layer "F.SilkS")
			(hide yes)
			(effects
				(font
					(size 1.27 1.27)
				)
			)
		)
		(property "Value" "20KR2F-L-GP"
			(at 0.064008 -3.993896 90)
			(unlocked yes)
			(layer "F.Fab")
			(hide yes)
			(effects
				(font
					(size 1.016 1.016)
					(thickness 0.1524)
				)
			)
		)
		(property "Device Type" "R402H16"
			(at 0.064008 -5.517896 90)
			(unlocked yes)
			(layer "F.Fab")
			(hide yes)
			(effects
				(font
					(size 1.016 1.016)
					(thickness 0.1524)
				)
			)
		)
		(duplicate_pad_numbers_are_jumpers no)
		(fp_rect
			(start -0.381 0.8382)
			(end 0.381 -0.8382)
			(stroke
				(width 0)
				(type default)
			)
			(fill no)
			(layer "F.CrtYd")
		)
		(fp_rect
			(start -0.381 0.8382)
			(end 0.381 -0.8382)
			(stroke
				(width 0)
				(type default)
			)
			(fill no)
			(layer "F.Fab")
		)
		(pad "1" smd custom
			(at 0 -0.4318 90)
			(size 0.127 0.127)
			(layers "F.Cu" "F.Mask" "F.Paste")
			(net "PV_VTT_DDR_REFIN")
			(options
				(clearance outline)
				(anchor circle)
			)
			(primitives
				(gr_poly
					(pts
						(arc
							(start -0.2032 -0.2794)
							(mid -0.239121 -0.264521)
							(end -0.254 -0.2286)
						)
						(arc
							(start -0.254 0.2286)
							(mid -0.239121 0.264521)
							(end -0.2032 0.2794)
						)
						(arc
							(start 0.2032 0.2794)
							(mid 0.239121 0.264521)
							(end 0.254 0.2286)
						)
						(arc
							(start 0.254 -0.2286)
							(mid 0.239121 -0.264521)
							(end 0.2032 -0.2794)
						)
					)
					(width 0)
					(fill yes)
				)
			)
		)
		(pad "2" smd custom
			(at 0 0.4318 90)
			(size 0.127 0.127)
			(layers "F.Cu" "F.Mask" "F.Paste")
			(net "GND")
			(options
				(clearance outline)
				(anchor circle)
			)
			(primitives
				(gr_poly
					(pts
						(arc
							(start -0.2032 -0.2794)
							(mid -0.239121 -0.264521)
							(end -0.254 -0.2286)
						)
						(arc
							(start -0.254 0.2286)
							(mid -0.239121 0.264521)
							(end -0.2032 0.2794)
						)
						(arc
							(start 0.2032 0.2794)
							(mid 0.239121 0.264521)
							(end 0.254 0.2286)
						)
						(arc
							(start 0.254 -0.2286)
							(mid 0.239121 -0.264521)
							(end 0.2032 -0.2794)
						)
					)
					(width 0)
					(fill yes)
				)
			)
		)
	)
	(footprint ""
		(layer "F.Cu")
		(at 60.452 -41.91 180)
		(property "Reference" "R36"
			(at 0 0 180)
			(layer "F.SilkS")
			(hide yes)
			(effects
				(font
					(size 1.27 1.27)
				)
			)
		)
		(property "Value" "0R2J-2-GP"
			(at 0.064008 -3.993896 180)
			(unlocked yes)
			(layer "F.Fab")
			(hide yes)
			(effects
				(font
					(size 1.016 1.016)
					(thickness 0.1524)
				)
			)
		)
		(property "Device Type" "R402H16"
			(at 0.064008 -5.517896 180)
			(unlocked yes)
			(layer "F.Fab")
			(hide yes)
			(effects
				(font
					(size 1.016 1.016)
					(thickness 0.1524)
				)
			)
		)
		(duplicate_pad_numbers_are_jumpers no)
		(fp_rect
			(start -0.381 0.8382)
			(end 0.381 -0.8382)
			(stroke
				(width 0)
				(type default)
			)
			(fill no)
			(layer "F.CrtYd")
		)
		(fp_rect
			(start -0.381 0.8382)
			(end 0.381 -0.8382)
			(stroke
				(width 0)
				(type default)
			)
			(fill no)
			(layer "F.Fab")
		)
		(pad "1" smd custom
			(at 0 -0.4318 180)
			(size 0.127 0.127)
			(layers "F.Cu" "F.Mask" "F.Paste")
			(net "SMBUS_HOST_R_DATA")
			(options
				(clearance outline)
				(anchor circle)
			)
			(primitives
				(gr_poly
					(pts
						(arc
							(start -0.2032 -0.2794)
							(mid -0.239121 -0.264521)
							(end -0.254 -0.2286)
						)
						(arc
							(start -0.254 0.2286)
							(mid -0.239121 0.264521)
							(end -0.2032 0.2794)
						)
						(arc
							(start 0.2032 0.2794)
							(mid 0.239121 0.264521)
							(end 0.254 0.2286)
						)
						(arc
							(start 0.254 -0.2286)
							(mid 0.239121 -0.264521)
							(end 0.2032 -0.2794)
						)
					)
					(width 0)
					(fill yes)
				)
			)
		)
		(pad "2" smd custom
			(at 0 0.4318 180)
			(size 0.127 0.127)
			(layers "F.Cu" "F.Mask" "F.Paste")
			(net "SMBUS_HOST_DATA")
			(options
				(clearance outline)
				(anchor circle)
			)
			(primitives
				(gr_poly
					(pts
						(arc
							(start -0.2032 -0.2794)
							(mid -0.239121 -0.264521)
							(end -0.254 -0.2286)
						)
						(arc
							(start -0.254 0.2286)
							(mid -0.239121 0.264521)
							(end -0.2032 0.2794)
						)
						(arc
							(start 0.2032 0.2794)
							(mid 0.239121 0.264521)
							(end 0.254 0.2286)
						)
						(arc
							(start 0.254 -0.2286)
							(mid 0.239121 -0.264521)
							(end 0.2032 -0.2794)
						)
					)
					(width 0)
					(fill yes)
				)
			)
		)
	)
	(footprint ""
		(layer "F.Cu")
		(at 158.115 -22.098 180)
		(property "Reference" "R114"
			(at 0 0 180)
			(layer "F.SilkS")
			(hide yes)
			(effects
				(font
					(size 1.27 1.27)
				)
			)
		)
		(property "Value" "4K7R2F-GP"
			(at 0.064008 -3.993896 180)
			(unlocked yes)
			(layer "F.Fab")
			(hide yes)
			(effects
				(font
					(size 1.016 1.016)
					(thickness 0.1524)
				)
			)
		)
		(property "Device Type" "R402H16"
			(at 0.064008 -5.517896 180)
			(unlocked yes)
			(layer "F.Fab")
			(hide yes)
			(effects
				(font
					(size 1.016 1.016)
					(thickness 0.1524)
				)
			)
		)
		(duplicate_pad_numbers_are_jumpers no)
		(fp_rect
			(start -0.381 0.8382)
			(end 0.381 -0.8382)
			(stroke
				(width 0)
				(type default)
			)
			(fill no)
			(layer "F.CrtYd")
		)
		(fp_rect
			(start -0.381 0.8382)
			(end 0.381 -0.8382)
			(stroke
				(width 0)
				(type default)
			)
			(fill no)
			(layer "F.Fab")
		)
		(pad "1" smd custom
			(at 0 -0.4318 180)
			(size 0.127 0.127)
			(layers "F.Cu" "F.Mask" "F.Paste")
			(net "CPU_FPGA_DISABLE")
			(options
				(clearance outline)
				(anchor circle)
			)
			(primitives
				(gr_poly
					(pts
						(arc
							(start -0.2032 -0.2794)
							(mid -0.239121 -0.264521)
							(end -0.254 -0.2286)
						)
						(arc
							(start -0.254 0.2286)
							(mid -0.239121 0.264521)
							(end -0.2032 0.2794)
						)
						(arc
							(start 0.2032 0.2794)
							(mid 0.239121 0.264521)
							(end 0.254 0.2286)
						)
						(arc
							(start 0.254 -0.2286)
							(mid 0.239121 -0.264521)
							(end 0.2032 -0.2794)
						)
					)
					(width 0)
					(fill yes)
				)
			)
		)
		(pad "2" smd custom
			(at 0 0.4318 180)
			(size 0.127 0.127)
			(layers "F.Cu" "F.Mask" "F.Paste")
			(net "GND")
			(options
				(clearance outline)
				(anchor circle)
			)
			(primitives
				(gr_poly
					(pts
						(arc
							(start -0.2032 -0.2794)
							(mid -0.239121 -0.264521)
							(end -0.254 -0.2286)
						)
						(arc
							(start -0.254 0.2286)
							(mid -0.239121 0.264521)
							(end -0.2032 0.2794)
						)
						(arc
							(start 0.2032 0.2794)
							(mid 0.239121 0.264521)
							(end 0.254 0.2286)
						)
						(arc
							(start 0.254 -0.2286)
							(mid 0.239121 -0.264521)
							(end 0.2032 -0.2794)
						)
					)
					(width 0)
					(fill yes)
				)
			)
		)
	)
	(footprint ""
		(layer "F.Cu")
		(at 27.0764 -59.7916 90)
		(property "Reference" "PC35"
			(at 0 0 90)
			(layer "F.SilkS")
			(hide yes)
			(effects
				(font
					(size 1.27 1.27)
				)
			)
		)
		(property "Value" "SC1U16V3KX-5GP"
			(at -0.0254 -2.0193 90)
			(unlocked yes)
			(layer "F.Fab")
			(hide yes)
			(effects
				(font
					(size 1.016 1.016)
					(thickness 0.1524)
				)
			)
		)
		(property "Device Type" "C603H36"
			(at -0.0254 -3.5433 90)
			(unlocked yes)
			(layer "F.Fab")
			(hide yes)
			(effects
				(font
					(size 1.016 1.016)
					(thickness 0.1524)
				)
			)
		)
		(duplicate_pad_numbers_are_jumpers no)
		(fp_line
			(start -0.4064 0)
			(end 0.4064 0)
			(stroke
				(width 0.2286)
				(type default)
			)
			(layer "F.SilkS")
		)
		(fp_rect
			(start -0.635 1.1811)
			(end 0.635 -1.1811)
			(stroke
				(width 0)
				(type default)
			)
			(fill no)
			(layer "F.CrtYd")
		)
		(fp_rect
			(start -0.635 1.1811)
			(end 0.635 -1.1811)
			(stroke
				(width 0)
				(type default)
			)
			(fill no)
			(layer "F.Fab")
		)
		(pad "1" smd custom
			(at 0 -0.6604 90)
			(size 0.19685 0.19685)
			(layers "F.Cu" "F.Mask" "F.Paste")
			(net "VR_PVCCP_PVNN_VCCP")
			(options
				(clearance outline)
				(anchor circle)
			)
			(primitives
				(gr_poly
					(pts
						(arc
							(start 0.508 -0.2921)
							(mid 0.478242 -0.363942)
							(end 0.4064 -0.3937)
						)
						(arc
							(start -0.4064 -0.3937)
							(mid -0.478242 -0.363942)
							(end -0.508 -0.2921)
						)
						(arc
							(start -0.508 0.2921)
							(mid -0.478242 0.363942)
							(end -0.4064 0.3937)
						)
						(arc
							(start 0.4064 0.3937)
							(mid 0.478242 0.363942)
							(end 0.508 0.2921)
						)
					)
					(width 0)
					(fill yes)
				)
			)
		)
		(pad "2" smd custom
			(at 0 0.6604 90)
			(size 0.19685 0.19685)
			(layers "F.Cu" "F.Mask" "F.Paste")
			(net "GND")
			(options
				(clearance outline)
				(anchor circle)
			)
			(primitives
				(gr_poly
					(pts
						(arc
							(start 0.508 -0.2921)
							(mid 0.478242 -0.363942)
							(end 0.4064 -0.3937)
						)
						(arc
							(start -0.4064 -0.3937)
							(mid -0.478242 -0.363942)
							(end -0.508 -0.2921)
						)
						(arc
							(start -0.508 0.2921)
							(mid -0.478242 0.363942)
							(end -0.4064 0.3937)
						)
						(arc
							(start 0.4064 0.3937)
							(mid 0.478242 0.363942)
							(end 0.508 0.2921)
						)
					)
					(width 0)
					(fill yes)
				)
			)
		)
	)
	(footprint ""
		(layer "F.Cu")
		(at 194.31 -36.2966 -90)
		(property "Reference" "PR137"
			(at 0 0 270)
			(layer "F.SilkS")
			(hide yes)
			(effects
				(font
					(size 1.27 1.27)
				)
			)
		)
		(property "Value" "0R2J-2-GP"
			(at 1.7907 -1.1176 270)
			(unlocked yes)
			(layer "F.Fab")
			(hide yes)
			(effects
				(font
					(size 1.016 1.016)
					(thickness 0.1524)
				)
			)
		)
		(property "Device Type" "R402H16"
			(at 1.7907 -2.6416 270)
			(unlocked yes)
			(layer "F.Fab")
			(hide yes)
			(effects
				(font
					(size 1.016 1.016)
					(thickness 0.1524)
				)
			)
		)
		(duplicate_pad_numbers_are_jumpers no)
		(fp_rect
			(start -0.381 0.8382)
			(end 0.381 -0.8382)
			(stroke
				(width 0)
				(type default)
			)
			(fill no)
			(layer "F.CrtYd")
		)
		(fp_rect
			(start -0.381 0.8382)
			(end 0.381 -0.8382)
			(stroke
				(width 0)
				(type default)
			)
			(fill no)
			(layer "F.Fab")
		)
		(pad "1" smd custom
			(at 0 -0.4318 270)
			(size 0.127 0.127)
			(layers "F.Cu" "F.Mask" "F.Paste")
			(net "VR_PVDDR_A_VDD")
			(options
				(clearance outline)
				(anchor circle)
			)
			(primitives
				(gr_poly
					(pts
						(arc
							(start -0.2032 -0.2794)
							(mid -0.239121 -0.264521)
							(end -0.254 -0.2286)
						)
						(arc
							(start -0.254 0.2286)
							(mid -0.239121 0.264521)
							(end -0.2032 0.2794)
						)
						(arc
							(start 0.2032 0.2794)
							(mid 0.239121 0.264521)
							(end 0.254 0.2286)
						)
						(arc
							(start 0.254 -0.2286)
							(mid 0.239121 -0.264521)
							(end 0.2032 -0.2794)
						)
					)
					(width 0)
					(fill yes)
				)
			)
		)
		(pad "2" smd custom
			(at 0 0.4318 270)
			(size 0.127 0.127)
			(layers "F.Cu" "F.Mask" "F.Paste")
			(net "VR_PVDDR_A_PWM3")
			(options
				(clearance outline)
				(anchor circle)
			)
			(primitives
				(gr_poly
					(pts
						(arc
							(start -0.2032 -0.2794)
							(mid -0.239121 -0.264521)
							(end -0.254 -0.2286)
						)
						(arc
							(start -0.254 0.2286)
							(mid -0.239121 0.264521)
							(end -0.2032 0.2794)
						)
						(arc
							(start 0.2032 0.2794)
							(mid 0.239121 0.264521)
							(end 0.254 0.2286)
						)
						(arc
							(start 0.254 -0.2286)
							(mid 0.239121 -0.264521)
							(end 0.2032 -0.2794)
						)
					)
					(width 0)
					(fill yes)
				)
			)
		)
	)
	(footprint ""
		(layer "F.Cu")
		(at 29.845 -51.816 90)
		(property "Reference" "PC129"
			(at 0 0 90)
			(layer "F.SilkS")
			(hide yes)
			(effects
				(font
					(size 1.27 1.27)
				)
			)
		)
		(property "Value" "SC10U6D3V5KX-4GP"
			(at 0 -4.9022 90)
			(unlocked yes)
			(layer "F.Fab")
			(hide yes)
			(effects
				(font
					(size 1.016 1.016)
					(thickness 0.1524)
				)
			)
		)
		(property "Device Type" "C805H58"
			(at 0 -6.8072 90)
			(unlocked yes)
			(layer "F.Fab")
			(hide yes)
			(effects
				(font
					(size 1.016 1.016)
					(thickness 0.1524)
				)
			)
		)
		(duplicate_pad_numbers_are_jumpers no)
		(fp_line
			(start 0.6096 0)
			(end -0.6096 0)
			(stroke
				(width 0.3048)
				(type default)
			)
			(layer "F.SilkS")
		)
		(fp_poly
			(pts
				(xy -0.9017 1.4351) (xy 0.9017 1.4351) (xy 0.9017 -1.4351) (xy -0.9017 -1.4351)
			)
			(stroke
				(width 0)
				(type default)
			)
			(fill no)
			(layer "F.CrtYd")
		)
		(fp_poly
			(pts
				(xy 0.9017 1.4351) (xy 0.9017 -1.4351) (xy -0.9017 -1.4351) (xy -0.9017 1.4351)
			)
			(stroke
				(width 0)
				(type default)
			)
			(fill no)
			(layer "F.Fab")
		)
		(pad "1" smd rect
			(at 0 -0.8382 90)
			(size 1.5494 0.9398)
			(layers "F.Cu" "F.Mask" "F.Paste")
			(net "P1V5_STBY_IN")
		)
		(pad "2" smd rect
			(at 0 0.8382 90)
			(size 1.5494 0.9398)
			(layers "F.Cu" "F.Mask" "F.Paste")
			(net "GND")
		)
	)
	(footprint ""
		(layer "F.Cu")
		(at 67.056 -13.462 90)
		(property "Reference" "R474"
			(at 0 0 90)
			(layer "F.SilkS")
			(hide yes)
			(effects
				(font
					(size 1.27 1.27)
				)
			)
		)
		(property "Value" "4K7R2F-GP"
			(at 1.7907 -1.1176 90)
			(unlocked yes)
			(layer "F.Fab")
			(hide yes)
			(effects
				(font
					(size 1.016 1.016)
					(thickness 0.1524)
				)
			)
		)
		(property "Device Type" "R402H16"
			(at 1.7907 -2.6416 90)
			(unlocked yes)
			(layer "F.Fab")
			(hide yes)
			(effects
				(font
					(size 1.016 1.016)
					(thickness 0.1524)
				)
			)
		)
		(duplicate_pad_numbers_are_jumpers no)
		(fp_rect
			(start -0.381 0.8382)
			(end 0.381 -0.8382)
			(stroke
				(width 0)
				(type default)
			)
			(fill no)
			(layer "F.CrtYd")
		)
		(fp_rect
			(start -0.381 0.8382)
			(end 0.381 -0.8382)
			(stroke
				(width 0)
				(type default)
			)
			(fill no)
			(layer "F.Fab")
		)
		(pad "1" smd custom
			(at 0 -0.4318 90)
			(size 0.127 0.127)
			(layers "F.Cu" "F.Mask" "F.Paste")
			(net "P3V3")
			(options
				(clearance outline)
				(anchor circle)
			)
			(primitives
				(gr_poly
					(pts
						(arc
							(start -0.2032 -0.2794)
							(mid -0.239121 -0.264521)
							(end -0.254 -0.2286)
						)
						(arc
							(start -0.254 0.2286)
							(mid -0.239121 0.264521)
							(end -0.2032 0.2794)
						)
						(arc
							(start 0.2032 0.2794)
							(mid 0.239121 0.264521)
							(end 0.254 0.2286)
						)
						(arc
							(start 0.254 -0.2286)
							(mid 0.239121 -0.264521)
							(end 0.2032 -0.2794)
						)
					)
					(width 0)
					(fill yes)
				)
			)
		)
		(pad "2" smd custom
			(at 0 0.4318 90)
			(size 0.127 0.127)
			(layers "F.Cu" "F.Mask" "F.Paste")
			(net "HOST_LV_RSTBTN#")
			(options
				(clearance outline)
				(anchor circle)
			)
			(primitives
				(gr_poly
					(pts
						(arc
							(start -0.2032 -0.2794)
							(mid -0.239121 -0.264521)
							(end -0.254 -0.2286)
						)
						(arc
							(start -0.254 0.2286)
							(mid -0.239121 0.264521)
							(end -0.2032 0.2794)
						)
						(arc
							(start 0.2032 0.2794)
							(mid 0.239121 0.264521)
							(end 0.254 0.2286)
						)
						(arc
							(start 0.254 -0.2286)
							(mid 0.239121 -0.264521)
							(end 0.2032 -0.2794)
						)
					)
					(width 0)
					(fill yes)
				)
			)
		)
	)
	(footprint ""
		(layer "F.Cu")
		(at 181.356 -17.653 180)
		(property "Reference" "PR168"
			(at 0 0 180)
			(layer "F.SilkS")
			(hide yes)
			(effects
				(font
					(size 1.27 1.27)
				)
			)
		)
		(property "Value" "20KR2F-L-GP"
			(at 0.064008 -3.993896 180)
			(unlocked yes)
			(layer "F.Fab")
			(hide yes)
			(effects
				(font
					(size 1.016 1.016)
					(thickness 0.1524)
				)
			)
		)
		(property "Device Type" "R402H16"
			(at 0.064008 -5.517896 180)
			(unlocked yes)
			(layer "F.Fab")
			(hide yes)
			(effects
				(font
					(size 1.016 1.016)
					(thickness 0.1524)
				)
			)
		)
		(duplicate_pad_numbers_are_jumpers no)
		(fp_rect
			(start -0.381 0.8382)
			(end 0.381 -0.8382)
			(stroke
				(width 0)
				(type default)
			)
			(fill no)
			(layer "F.CrtYd")
		)
		(fp_rect
			(start -0.381 0.8382)
			(end 0.381 -0.8382)
			(stroke
				(width 0)
				(type default)
			)
			(fill no)
			(layer "F.Fab")
		)
		(pad "1" smd custom
			(at 0 -0.4318 180)
			(size 0.127 0.127)
			(layers "F.Cu" "F.Mask" "F.Paste")
			(net "PV_VTT_DDR_B_REFIN")
			(options
				(clearance outline)
				(anchor circle)
			)
			(primitives
				(gr_poly
					(pts
						(arc
							(start -0.2032 -0.2794)
							(mid -0.239121 -0.264521)
							(end -0.254 -0.2286)
						)
						(arc
							(start -0.254 0.2286)
							(mid -0.239121 0.264521)
							(end -0.2032 0.2794)
						)
						(arc
							(start 0.2032 0.2794)
							(mid 0.239121 0.264521)
							(end 0.254 0.2286)
						)
						(arc
							(start 0.254 -0.2286)
							(mid 0.239121 -0.264521)
							(end 0.2032 -0.2794)
						)
					)
					(width 0)
					(fill yes)
				)
			)
		)
		(pad "2" smd custom
			(at 0 0.4318 180)
			(size 0.127 0.127)
			(layers "F.Cu" "F.Mask" "F.Paste")
			(net "GND")
			(options
				(clearance outline)
				(anchor circle)
			)
			(primitives
				(gr_poly
					(pts
						(arc
							(start -0.2032 -0.2794)
							(mid -0.239121 -0.264521)
							(end -0.254 -0.2286)
						)
						(arc
							(start -0.254 0.2286)
							(mid -0.239121 0.264521)
							(end -0.2032 0.2794)
						)
						(arc
							(start 0.2032 0.2794)
							(mid 0.239121 0.264521)
							(end 0.254 0.2286)
						)
						(arc
							(start 0.254 -0.2286)
							(mid 0.239121 -0.264521)
							(end 0.2032 -0.2794)
						)
					)
					(width 0)
					(fill yes)
				)
			)
		)
	)
	(footprint ""
		(layer "F.Cu")
		(at 174.3456 -44.3992 180)
		(property "Reference" "PC209"
			(at 0 0 180)
			(layer "F.SilkS")
			(hide yes)
			(effects
				(font
					(size 1.27 1.27)
				)
			)
		)
		(property "Value" "SC1U6D3V2KX-GP"
			(at 1.8923 -1.2065 180)
			(unlocked yes)
			(layer "F.Fab")
			(hide yes)
			(effects
				(font
					(size 1.016 1.016)
					(thickness 0.1524)
				)
			)
		)
		(property "Device Type" "C402H22"
			(at 1.8923 -2.7305 180)
			(unlocked yes)
			(layer "F.Fab")
			(hide yes)
			(effects
				(font
					(size 1.016 1.016)
					(thickness 0.1524)
				)
			)
		)
		(duplicate_pad_numbers_are_jumpers no)
		(fp_rect
			(start -0.381 0.7366)
			(end 0.381 -0.7366)
			(stroke
				(width 0)
				(type default)
			)
			(fill no)
			(layer "F.CrtYd")
		)
		(fp_rect
			(start -0.381 0.7366)
			(end 0.381 -0.7366)
			(stroke
				(width 0)
				(type default)
			)
			(fill no)
			(layer "F.Fab")
		)
		(pad "1" smd custom
			(at 0 -0.4572 180)
			(size 0.1143 0.1143)
			(layers "F.Cu" "F.Mask" "F.Paste")
			(net "P3V3_STBY")
			(options
				(clearance outline)
				(anchor circle)
			)
			(primitives
				(gr_poly
					(pts
						(arc
							(start -0.254 -0.1778)
							(mid -0.239121 -0.213721)
							(end -0.2032 -0.2286)
						)
						(arc
							(start 0.2032 -0.2286)
							(mid 0.239121 -0.213721)
							(end 0.254 -0.1778)
						)
						(arc
							(start 0.254 0.1778)
							(mid 0.239121 0.213721)
							(end 0.2032 0.2286)
						)
						(arc
							(start -0.2032 0.2286)
							(mid -0.239121 0.213721)
							(end -0.254 0.1778)
						)
					)
					(width 0)
					(fill yes)
				)
			)
		)
		(pad "2" smd custom
			(at 0 0.4572 180)
			(size 0.1143 0.1143)
			(layers "F.Cu" "F.Mask" "F.Paste")
			(net "GND")
			(options
				(clearance outline)
				(anchor circle)
			)
			(primitives
				(gr_poly
					(pts
						(arc
							(start -0.254 -0.1778)
							(mid -0.239121 -0.213721)
							(end -0.2032 -0.2286)
						)
						(arc
							(start 0.2032 -0.2286)
							(mid 0.239121 -0.213721)
							(end 0.254 -0.1778)
						)
						(arc
							(start 0.254 0.1778)
							(mid 0.239121 0.213721)
							(end 0.2032 0.2286)
						)
						(arc
							(start -0.2032 0.2286)
							(mid -0.239121 0.213721)
							(end -0.254 0.1778)
						)
					)
					(width 0)
					(fill yes)
				)
			)
		)
	)
	(footprint ""
		(layer "F.Cu")
		(at 111.379 -70.612 90)
		(property "Reference" "C6"
			(at 0 0 90)
			(layer "F.SilkS")
			(hide yes)
			(effects
				(font
					(size 1.27 1.27)
				)
			)
		)
		(property "Value" "SCD1U10V2KX-5GP"
			(at 1.1811 -2.7051 90)
			(unlocked yes)
			(layer "F.Fab")
			(hide yes)
			(effects
				(font
					(size 1.016 1.016)
					(thickness 0.1524)
				)
			)
		)
		(property "Device Type" "C402H22"
			(at 1.1811 -4.2291 90)
			(unlocked yes)
			(layer "F.Fab")
			(hide yes)
			(effects
				(font
					(size 1.016 1.016)
					(thickness 0.1524)
				)
			)
		)
		(duplicate_pad_numbers_are_jumpers no)
		(fp_rect
			(start -0.381 0.7366)
			(end 0.381 -0.7366)
			(stroke
				(width 0)
				(type default)
			)
			(fill no)
			(layer "F.CrtYd")
		)
		(fp_rect
			(start -0.381 0.7366)
			(end 0.381 -0.7366)
			(stroke
				(width 0)
				(type default)
			)
			(fill no)
			(layer "F.Fab")
		)
		(pad "1" smd custom
			(at 0 -0.4572 90)
			(size 0.1143 0.1143)
			(layers "F.Cu" "F.Mask" "F.Paste")
			(net "CLK_GEN_OUT_R")
			(options
				(clearance outline)
				(anchor circle)
			)
			(primitives
				(gr_poly
					(pts
						(arc
							(start -0.254 -0.1778)
							(mid -0.239121 -0.213721)
							(end -0.2032 -0.2286)
						)
						(arc
							(start 0.2032 -0.2286)
							(mid 0.239121 -0.213721)
							(end 0.254 -0.1778)
						)
						(arc
							(start 0.254 0.1778)
							(mid 0.239121 0.213721)
							(end 0.2032 0.2286)
						)
						(arc
							(start -0.2032 0.2286)
							(mid -0.239121 0.213721)
							(end -0.254 0.1778)
						)
					)
					(width 0)
					(fill yes)
				)
			)
		)
		(pad "2" smd custom
			(at 0 0.4572 90)
			(size 0.1143 0.1143)
			(layers "F.Cu" "F.Mask" "F.Paste")
			(net "GND")
			(options
				(clearance outline)
				(anchor circle)
			)
			(primitives
				(gr_poly
					(pts
						(arc
							(start -0.254 -0.1778)
							(mid -0.239121 -0.213721)
							(end -0.2032 -0.2286)
						)
						(arc
							(start 0.2032 -0.2286)
							(mid 0.239121 -0.213721)
							(end 0.254 -0.1778)
						)
						(arc
							(start 0.254 0.1778)
							(mid 0.239121 0.213721)
							(end 0.2032 0.2286)
						)
						(arc
							(start -0.2032 0.2286)
							(mid -0.239121 0.213721)
							(end -0.254 0.1778)
						)
					)
					(width 0)
					(fill yes)
				)
			)
		)
	)
	(footprint ""
		(layer "F.Cu")
		(at 107.061 -19.939 -90)
		(property "Reference" "R165"
			(at 0 0 270)
			(layer "F.SilkS")
			(hide yes)
			(effects
				(font
					(size 1.27 1.27)
				)
			)
		)
		(property "Value" "0R2J-2-GP"
			(at 0.064008 -3.993896 270)
			(unlocked yes)
			(layer "F.Fab")
			(hide yes)
			(effects
				(font
					(size 1.016 1.016)
					(thickness 0.1524)
				)
			)
		)
		(property "Device Type" "R402H16"
			(at 0.064008 -5.517896 270)
			(unlocked yes)
			(layer "F.Fab")
			(hide yes)
			(effects
				(font
					(size 1.016 1.016)
					(thickness 0.1524)
				)
			)
		)
		(duplicate_pad_numbers_are_jumpers no)
		(fp_rect
			(start -0.381 0.8382)
			(end 0.381 -0.8382)
			(stroke
				(width 0)
				(type default)
			)
			(fill no)
			(layer "F.CrtYd")
		)
		(fp_rect
			(start -0.381 0.8382)
			(end 0.381 -0.8382)
			(stroke
				(width 0)
				(type default)
			)
			(fill no)
			(layer "F.Fab")
		)
		(pad "1" smd custom
			(at 0 -0.4318 270)
			(size 0.127 0.127)
			(layers "F.Cu" "F.Mask" "F.Paste")
			(net "M_B_RESET#")
			(options
				(clearance outline)
				(anchor circle)
			)
			(primitives
				(gr_poly
					(pts
						(arc
							(start -0.2032 -0.2794)
							(mid -0.239121 -0.264521)
							(end -0.254 -0.2286)
						)
						(arc
							(start -0.254 0.2286)
							(mid -0.239121 0.264521)
							(end -0.2032 0.2794)
						)
						(arc
							(start 0.2032 0.2794)
							(mid 0.239121 0.264521)
							(end 0.254 0.2286)
						)
						(arc
							(start 0.254 -0.2286)
							(mid 0.239121 -0.264521)
							(end 0.2032 -0.2794)
						)
					)
					(width 0)
					(fill yes)
				)
			)
		)
		(pad "2" smd custom
			(at 0 0.4318 270)
			(size 0.127 0.127)
			(layers "F.Cu" "F.Mask" "F.Paste")
			(net "M_B_R_RESET#")
			(options
				(clearance outline)
				(anchor circle)
			)
			(primitives
				(gr_poly
					(pts
						(arc
							(start -0.2032 -0.2794)
							(mid -0.239121 -0.264521)
							(end -0.254 -0.2286)
						)
						(arc
							(start -0.254 0.2286)
							(mid -0.239121 0.264521)
							(end -0.2032 0.2794)
						)
						(arc
							(start 0.2032 0.2794)
							(mid 0.239121 0.264521)
							(end 0.254 0.2286)
						)
						(arc
							(start 0.254 -0.2286)
							(mid 0.239121 -0.264521)
							(end 0.2032 -0.2794)
						)
					)
					(width 0)
					(fill yes)
				)
			)
		)
	)
	(footprint ""
		(layer "F.Cu")
		(at 158.623 -12.955778 180)
		(property "Reference" "C370"
			(at 0 0 180)
			(layer "F.SilkS")
			(hide yes)
			(effects
				(font
					(size 1.27 1.27)
				)
			)
		)
		(property "Value" "SC47U6D3V5MX-1-GP"
			(at 0 -4.9022 180)
			(unlocked yes)
			(layer "F.Fab")
			(hide yes)
			(effects
				(font
					(size 1.016 1.016)
					(thickness 0.1524)
				)
			)
		)
		(property "Device Type" "C805H54"
			(at 0 -6.8072 180)
			(unlocked yes)
			(layer "F.Fab")
			(hide yes)
			(effects
				(font
					(size 1.016 1.016)
					(thickness 0.1524)
				)
			)
		)
		(duplicate_pad_numbers_are_jumpers no)
		(fp_line
			(start 0.6096 0)
			(end -0.6096 0)
			(stroke
				(width 0.3048)
				(type default)
			)
			(layer "F.SilkS")
		)
		(fp_poly
			(pts
				(xy -0.9017 1.4351) (xy 0.9017 1.4351) (xy 0.9017 -1.4351) (xy -0.9017 -1.4351)
			)
			(stroke
				(width 0)
				(type default)
			)
			(fill no)
			(layer "F.CrtYd")
		)
		(fp_poly
			(pts
				(xy 0.9017 1.4351) (xy 0.9017 -1.4351) (xy -0.9017 -1.4351) (xy -0.9017 1.4351)
			)
			(stroke
				(width 0)
				(type default)
			)
			(fill no)
			(layer "F.Fab")
		)
		(pad "1" smd rect
			(at 0 -0.8382 180)
			(size 1.5494 0.9398)
			(layers "F.Cu" "F.Mask" "F.Paste")
			(net "PV_VDDR")
		)
		(pad "2" smd rect
			(at 0 0.8382 180)
			(size 1.5494 0.9398)
			(layers "F.Cu" "F.Mask" "F.Paste")
			(net "GND")
		)
	)
	(footprint ""
		(layer "F.Cu")
		(at 130.429 -48.514 180)
		(property "Reference" "R10"
			(at 0 0 180)
			(layer "F.SilkS")
			(hide yes)
			(effects
				(font
					(size 1.27 1.27)
				)
			)
		)
		(property "Value" "3K3R3F-GP"
			(at -0.0254 -2.0193 180)
			(unlocked yes)
			(layer "F.Fab")
			(hide yes)
			(effects
				(font
					(size 1.016 1.016)
					(thickness 0.1524)
				)
			)
		)
		(property "Device Type" "R603H22"
			(at -0.0254 -3.5433 180)
			(unlocked yes)
			(layer "F.Fab")
			(hide yes)
			(effects
				(font
					(size 1.016 1.016)
					(thickness 0.1524)
				)
			)
		)
		(duplicate_pad_numbers_are_jumpers no)
		(fp_line
			(start 0.4318 0)
			(end 0.2032 0)
			(stroke
				(width 0.2032)
				(type default)
			)
			(layer "F.SilkS")
		)
		(fp_line
			(start -0.2032 0)
			(end -0.4191 0)
			(stroke
				(width 0.2032)
				(type default)
			)
			(layer "F.SilkS")
		)
		(fp_rect
			(start -0.635 1.1811)
			(end 0.635 -1.1811)
			(stroke
				(width 0)
				(type default)
			)
			(fill no)
			(layer "F.CrtYd")
		)
		(fp_rect
			(start -0.635 1.1811)
			(end 0.635 -1.1811)
			(stroke
				(width 0)
				(type default)
			)
			(fill no)
			(layer "F.Fab")
		)
		(pad "1" smd custom
			(at 0 -0.6604 180)
			(size 0.19685 0.19685)
			(layers "F.Cu" "F.Mask" "F.Paste")
			(net "P3V3")
			(options
				(clearance outline)
				(anchor circle)
			)
			(primitives
				(gr_poly
					(pts
						(arc
							(start 0.508 -0.2921)
							(mid 0.478242 -0.363942)
							(end 0.4064 -0.3937)
						)
						(arc
							(start -0.4064 -0.3937)
							(mid -0.478242 -0.363942)
							(end -0.508 -0.2921)
						)
						(arc
							(start -0.508 0.2921)
							(mid -0.478242 0.363942)
							(end -0.4064 0.3937)
						)
						(arc
							(start 0.4064 0.3937)
							(mid 0.478242 0.363942)
							(end 0.508 0.2921)
						)
					)
					(width 0)
					(fill yes)
				)
			)
		)
		(pad "2" smd custom
			(at 0 0.6604 180)
			(size 0.19685 0.19685)
			(layers "F.Cu" "F.Mask" "F.Paste")
			(net "MEMORY_FPGA_HOT#")
			(options
				(clearance outline)
				(anchor circle)
			)
			(primitives
				(gr_poly
					(pts
						(arc
							(start 0.508 -0.2921)
							(mid 0.478242 -0.363942)
							(end 0.4064 -0.3937)
						)
						(arc
							(start -0.4064 -0.3937)
							(mid -0.478242 -0.363942)
							(end -0.508 -0.2921)
						)
						(arc
							(start -0.508 0.2921)
							(mid -0.478242 0.363942)
							(end -0.4064 0.3937)
						)
						(arc
							(start 0.4064 0.3937)
							(mid 0.478242 0.363942)
							(end 0.508 0.2921)
						)
					)
					(width 0)
					(fill yes)
				)
			)
		)
	)
	(footprint ""
		(layer "F.Cu")
		(at 11.176 -59.436 180)
		(property "Reference" "TP5"
			(at 0 0 180)
			(layer "F.SilkS")
			(hide yes)
			(effects
				(font
					(size 1.27 1.27)
				)
			)
		)
		(property "Value" "TPAD28-1-GP-U"
			(at 0.0508 -1.9304 180)
			(unlocked yes)
			(layer "F.Fab")
			(hide yes)
			(effects
				(font
					(size 1.016 1.016)
					(thickness 0.1524)
				)
			)
		)
		(property "Device Type" "TPAD28-1-U"
			(at 0.0508 -3.4544 180)
			(unlocked yes)
			(layer "F.Fab")
			(hide yes)
			(effects
				(font
					(size 1.016 1.016)
					(thickness 0.1524)
				)
			)
		)
		(duplicate_pad_numbers_are_jumpers no)
		(fp_poly
			(pts
				(arc
					(start -0.3556 0)
					(mid 0.3556 0)
					(end -0.3556 0)
				)
			)
			(stroke
				(width 0)
				(type default)
			)
			(fill no)
			(layer "F.CrtYd")
		)
		(fp_poly
			(pts
				(arc
					(start -0.9525 0)
					(mid 0.9525 0)
					(end -0.9525 0)
				)
			)
			(stroke
				(width 0)
				(type default)
			)
			(fill no)
			(layer "F.Fab")
		)
		(pad "1" smd circle
			(at 0 0 180)
			(size 0.7112 0.7112)
			(layers "F.Cu" "F.Mask" "F.Paste")
			(net "TP_PVCCP_ALERT")
		)
	)
	(footprint ""
		(layer "F.Cu")
		(at 38.1508 -54.483)
		(property "Reference" "PC33"
			(at 0 0 0)
			(layer "F.SilkS")
			(hide yes)
			(effects
				(font
					(size 1.27 1.27)
				)
			)
		)
		(property "Value" "SCD1U25V2KX-2-GP"
			(at 1.8923 -1.2065 0)
			(unlocked yes)
			(layer "F.Fab")
			(hide yes)
			(effects
				(font
					(size 1.016 1.016)
					(thickness 0.1524)
				)
			)
		)
		(property "Device Type" "C402H22"
			(at 1.8923 -2.7305 0)
			(unlocked yes)
			(layer "F.Fab")
			(hide yes)
			(effects
				(font
					(size 1.016 1.016)
					(thickness 0.1524)
				)
			)
		)
		(duplicate_pad_numbers_are_jumpers no)
		(fp_rect
			(start -0.381 0.7366)
			(end 0.381 -0.7366)
			(stroke
				(width 0)
				(type default)
			)
			(fill no)
			(layer "F.CrtYd")
		)
		(fp_rect
			(start -0.381 0.7366)
			(end 0.381 -0.7366)
			(stroke
				(width 0)
				(type default)
			)
			(fill no)
			(layer "F.Fab")
		)
		(pad "1" smd custom
			(at 0 -0.4572)
			(size 0.1143 0.1143)
			(layers "F.Cu" "F.Mask" "F.Paste")
			(net "VR_FET_SW_P12V_PVCCP_PVNN")
			(options
				(clearance outline)
				(anchor circle)
			)
			(primitives
				(gr_poly
					(pts
						(arc
							(start -0.254 -0.1778)
							(mid -0.239121 -0.213721)
							(end -0.2032 -0.2286)
						)
						(arc
							(start 0.2032 -0.2286)
							(mid 0.239121 -0.213721)
							(end 0.254 -0.1778)
						)
						(arc
							(start 0.254 0.1778)
							(mid 0.239121 0.213721)
							(end 0.2032 0.2286)
						)
						(arc
							(start -0.2032 0.2286)
							(mid -0.239121 0.213721)
							(end -0.254 0.1778)
						)
					)
					(width 0)
					(fill yes)
				)
			)
		)
		(pad "2" smd custom
			(at 0 0.4572)
			(size 0.1143 0.1143)
			(layers "F.Cu" "F.Mask" "F.Paste")
			(net "GND")
			(options
				(clearance outline)
				(anchor circle)
			)
			(primitives
				(gr_poly
					(pts
						(arc
							(start -0.254 -0.1778)
							(mid -0.239121 -0.213721)
							(end -0.2032 -0.2286)
						)
						(arc
							(start 0.2032 -0.2286)
							(mid 0.239121 -0.213721)
							(end 0.254 -0.1778)
						)
						(arc
							(start 0.254 0.1778)
							(mid 0.239121 0.213721)
							(end 0.2032 0.2286)
						)
						(arc
							(start -0.2032 0.2286)
							(mid -0.239121 0.213721)
							(end -0.254 0.1778)
						)
					)
					(width 0)
					(fill yes)
				)
			)
		)
	)
	(footprint ""
		(layer "F.Cu")
		(at 53.467 -54.864 90)
		(property "Reference" "PRT1"
			(at 0 0 90)
			(layer "F.SilkS")
			(hide yes)
			(effects
				(font
					(size 1.27 1.27)
				)
			)
		)
		(property "Value" "NTC-10K-19-GP-U"
			(at 1.7907 -1.1176 90)
			(unlocked yes)
			(layer "F.Fab")
			(hide yes)
			(effects
				(font
					(size 1.016 1.016)
					(thickness 0.1524)
				)
			)
		)
		(property "Device Type" "NTC-402H22-U"
			(at 1.7907 -2.6416 90)
			(unlocked yes)
			(layer "F.Fab")
			(hide yes)
			(effects
				(font
					(size 1.016 1.016)
					(thickness 0.1524)
				)
			)
		)
		(duplicate_pad_numbers_are_jumpers no)
		(fp_rect
			(start -0.381 0.8382)
			(end 0.381 -0.8382)
			(stroke
				(width 0)
				(type default)
			)
			(fill no)
			(layer "F.CrtYd")
		)
		(fp_rect
			(start -0.381 0.8382)
			(end 0.381 -0.8382)
			(stroke
				(width 0)
				(type default)
			)
			(fill no)
			(layer "F.Fab")
		)
		(pad "1" smd custom
			(at 0 -0.4318 90)
			(size 0.127 0.127)
			(layers "F.Cu" "F.Mask" "F.Paste")
			(net "VR_PVCCP_ISUMN")
			(options
				(clearance outline)
				(anchor circle)
			)
			(primitives
				(gr_poly
					(pts
						(arc
							(start -0.2032 -0.2794)
							(mid -0.239121 -0.264521)
							(end -0.254 -0.2286)
						)
						(arc
							(start -0.254 0.2286)
							(mid -0.239121 0.264521)
							(end -0.2032 0.2794)
						)
						(arc
							(start 0.2032 0.2794)
							(mid 0.239121 0.264521)
							(end 0.254 0.2286)
						)
						(arc
							(start 0.254 -0.2286)
							(mid 0.239121 -0.264521)
							(end 0.2032 -0.2794)
						)
					)
					(width 0)
					(fill yes)
				)
			)
		)
		(pad "2" smd custom
			(at 0 0.4318 90)
			(size 0.127 0.127)
			(layers "F.Cu" "F.Mask" "F.Paste")
			(net "VR_PVCCP_NTC")
			(options
				(clearance outline)
				(anchor circle)
			)
			(primitives
				(gr_poly
					(pts
						(arc
							(start -0.2032 -0.2794)
							(mid -0.239121 -0.264521)
							(end -0.254 -0.2286)
						)
						(arc
							(start -0.254 0.2286)
							(mid -0.239121 0.264521)
							(end -0.2032 0.2794)
						)
						(arc
							(start 0.2032 0.2794)
							(mid 0.239121 0.264521)
							(end 0.254 0.2286)
						)
						(arc
							(start 0.254 -0.2286)
							(mid 0.239121 -0.264521)
							(end 0.2032 -0.2794)
						)
					)
					(width 0)
					(fill yes)
				)
			)
		)
	)
	(footprint ""
		(layer "F.Cu")
		(at 187.198 -48.26 90)
		(property "Reference" "U27"
			(at 0 0 90)
			(layer "F.SilkS")
			(hide yes)
			(effects
				(font
					(size 1.27 1.27)
				)
			)
		)
		(property "Value" "LMV321IDCKR-1-GP"
			(at -2.3368 -8.6868 90)
			(unlocked yes)
			(layer "F.Fab")
			(hide yes)
			(effects
				(font
					(size 1.016 1.016)
					(thickness 0.1524)
				)
			)
		)
		(property "Device Type" "SC70-5H44"
			(at -2.3114 -10.414 90)
			(unlocked yes)
			(layer "F.Fab")
			(hide yes)
			(effects
				(font
					(size 1.016 1.016)
					(thickness 0.1524)
				)
			)
		)
		(duplicate_pad_numbers_are_jumpers no)
		(fp_line
			(start 1.0033 -0.3302)
			(end 1.0033 0.3302)
			(stroke
				(width 0.1524)
				(type default)
			)
			(layer "F.SilkS")
		)
		(fp_line
			(start -1.0033 -0.3302)
			(end 1.0033 -0.3302)
			(stroke
				(width 0.1524)
				(type default)
			)
			(layer "F.SilkS")
		)
		(fp_line
			(start 1.0033 0.3302)
			(end -1.0033 0.3302)
			(stroke
				(width 0.1524)
				(type default)
			)
			(layer "F.SilkS")
		)
		(fp_line
			(start -1.0033 0.3302)
			(end -1.0033 -0.3302)
			(stroke
				(width 0.1524)
				(type default)
			)
			(layer "F.SilkS")
		)
		(fp_poly
			(pts
				(xy -1.0033 1.4859) (xy -1.0033 0.8001) (xy -1.1811 0.8001) (xy -1.1811 -0.8001) (xy -1.0033 -0.8001)
				(xy -1.0033 -1.4859) (xy 1.0033 -1.4859) (xy 1.0033 -0.8001) (xy 1.1811 -0.8001) (xy 1.1811 0.8001)
				(xy 1.0033 0.8001) (xy 1.0033 1.4859) (xy 0.2921 1.4859) (xy 0.2921 0.8001) (xy -0.2921 0.8001)
				(xy -0.2921 1.4859)
			)
			(stroke
				(width 0)
				(type default)
			)
			(fill no)
			(layer "F.CrtYd")
		)
		(fp_poly
			(pts
				(xy -1.0033 1.4859) (xy -1.0033 0.8001) (xy -1.1811 0.8001) (xy -1.1811 -0.8001) (xy -1.0033 -0.8001)
				(xy -1.0033 -1.4859) (xy 1.0033 -1.4859) (xy 1.0033 -0.8001) (xy 1.1811 -0.8001) (xy 1.1811 0.8001)
				(xy 1.0033 0.8001) (xy 1.0033 1.4859) (xy 0.2921 1.4859) (xy 0.2921 0.8001) (xy -0.2921 0.8001)
				(xy -0.2921 1.4859)
			)
			(stroke
				(width 0)
				(type default)
			)
			(fill no)
			(layer "F.Fab")
		)
		(pad "1" smd rect
			(at 0.65024 -0.93472 90)
			(size 0.3556 0.762)
			(layers "F.Cu" "F.Mask" "F.Paste")
			(net "PV_VDDR_VREF_RW")
		)
		(pad "2" smd rect
			(at 0 -0.93472 90)
			(size 0.3556 0.762)
			(layers "F.Cu" "F.Mask" "F.Paste")
			(net "GND")
		)
		(pad "3" smd rect
			(at -0.65024 -0.93472 90)
			(size 0.3556 0.762)
			(layers "F.Cu" "F.Mask" "F.Paste")
			(net "PV_VDDR_VREF_B_FB")
		)
		(pad "4" smd rect
			(at -0.65024 0.93472 90)
			(size 0.3556 0.762)
			(layers "F.Cu" "F.Mask" "F.Paste")
			(net "PV_VDDR_VREF_B_FB")
		)
		(pad "5" smd rect
			(at 0.65024 0.93472 90)
			(size 0.3556 0.762)
			(layers "F.Cu" "F.Mask" "F.Paste")
			(net "P3V3_STBY")
		)
	)
	(footprint ""
		(layer "F.Cu")
		(at 128.143 -37.592 -90)
		(property "Reference" "R31"
			(at 0 0 270)
			(layer "F.SilkS")
			(hide yes)
			(effects
				(font
					(size 1.27 1.27)
				)
			)
		)
		(property "Value" "33R2F-3-GP"
			(at 0.064008 -3.993896 270)
			(unlocked yes)
			(layer "F.Fab")
			(hide yes)
			(effects
				(font
					(size 1.016 1.016)
					(thickness 0.1524)
				)
			)
		)
		(property "Device Type" "R402H16"
			(at 0.064008 -5.517896 270)
			(unlocked yes)
			(layer "F.Fab")
			(hide yes)
			(effects
				(font
					(size 1.016 1.016)
					(thickness 0.1524)
				)
			)
		)
		(duplicate_pad_numbers_are_jumpers no)
		(fp_rect
			(start -0.381 0.8382)
			(end 0.381 -0.8382)
			(stroke
				(width 0)
				(type default)
			)
			(fill no)
			(layer "F.CrtYd")
		)
		(fp_rect
			(start -0.381 0.8382)
			(end 0.381 -0.8382)
			(stroke
				(width 0)
				(type default)
			)
			(fill no)
			(layer "F.Fab")
		)
		(pad "1" smd custom
			(at 0 -0.4318 270)
			(size 0.127 0.127)
			(layers "F.Cu" "F.Mask" "F.Paste")
			(net "LPC_AD_3")
			(options
				(clearance outline)
				(anchor circle)
			)
			(primitives
				(gr_poly
					(pts
						(arc
							(start -0.2032 -0.2794)
							(mid -0.239121 -0.264521)
							(end -0.254 -0.2286)
						)
						(arc
							(start -0.254 0.2286)
							(mid -0.239121 0.264521)
							(end -0.2032 0.2794)
						)
						(arc
							(start 0.2032 0.2794)
							(mid 0.239121 0.264521)
							(end 0.254 0.2286)
						)
						(arc
							(start 0.254 -0.2286)
							(mid 0.239121 -0.264521)
							(end 0.2032 -0.2794)
						)
					)
					(width 0)
					(fill yes)
				)
			)
		)
		(pad "2" smd custom
			(at 0 0.4318 270)
			(size 0.127 0.127)
			(layers "F.Cu" "F.Mask" "F.Paste")
			(net "LPC_CPU_LAD3")
			(options
				(clearance outline)
				(anchor circle)
			)
			(primitives
				(gr_poly
					(pts
						(arc
							(start -0.2032 -0.2794)
							(mid -0.239121 -0.264521)
							(end -0.254 -0.2286)
						)
						(arc
							(start -0.254 0.2286)
							(mid -0.239121 0.264521)
							(end -0.2032 0.2794)
						)
						(arc
							(start 0.2032 0.2794)
							(mid 0.239121 0.264521)
							(end 0.254 0.2286)
						)
						(arc
							(start 0.254 -0.2286)
							(mid 0.239121 -0.264521)
							(end 0.2032 -0.2794)
						)
					)
					(width 0)
					(fill yes)
				)
			)
		)
	)
	(footprint ""
		(layer "F.Cu")
		(at 141.2748 -57.5818 -90)
		(property "Reference" "PR65"
			(at 0 0 270)
			(layer "F.SilkS")
			(hide yes)
			(effects
				(font
					(size 1.27 1.27)
				)
			)
		)
		(property "Value" "10KR2F-2-GP"
			(at 0.064008 -3.993896 270)
			(unlocked yes)
			(layer "F.Fab")
			(hide yes)
			(effects
				(font
					(size 1.016 1.016)
					(thickness 0.1524)
				)
			)
		)
		(property "Device Type" "R402H16"
			(at 0.064008 -5.517896 270)
			(unlocked yes)
			(layer "F.Fab")
			(hide yes)
			(effects
				(font
					(size 1.016 1.016)
					(thickness 0.1524)
				)
			)
		)
		(duplicate_pad_numbers_are_jumpers no)
		(fp_rect
			(start -0.381 0.8382)
			(end 0.381 -0.8382)
			(stroke
				(width 0)
				(type default)
			)
			(fill no)
			(layer "F.CrtYd")
		)
		(fp_rect
			(start -0.381 0.8382)
			(end 0.381 -0.8382)
			(stroke
				(width 0)
				(type default)
			)
			(fill no)
			(layer "F.Fab")
		)
		(pad "1" smd custom
			(at 0 -0.4318 270)
			(size 0.127 0.127)
			(layers "F.Cu" "F.Mask" "F.Paste")
			(net "P3V3_STBY")
			(options
				(clearance outline)
				(anchor circle)
			)
			(primitives
				(gr_poly
					(pts
						(arc
							(start -0.2032 -0.2794)
							(mid -0.239121 -0.264521)
							(end -0.254 -0.2286)
						)
						(arc
							(start -0.254 0.2286)
							(mid -0.239121 0.264521)
							(end -0.2032 0.2794)
						)
						(arc
							(start 0.2032 0.2794)
							(mid 0.239121 0.264521)
							(end 0.254 0.2286)
						)
						(arc
							(start 0.254 -0.2286)
							(mid 0.239121 -0.264521)
							(end 0.2032 -0.2794)
						)
					)
					(width 0)
					(fill yes)
				)
			)
		)
		(pad "2" smd custom
			(at 0 0.4318 270)
			(size 0.127 0.127)
			(layers "F.Cu" "F.Mask" "F.Paste")
			(net "PV_VTT_DDR_R_PG")
			(options
				(clearance outline)
				(anchor circle)
			)
			(primitives
				(gr_poly
					(pts
						(arc
							(start -0.2032 -0.2794)
							(mid -0.239121 -0.264521)
							(end -0.254 -0.2286)
						)
						(arc
							(start -0.254 0.2286)
							(mid -0.239121 0.264521)
							(end -0.2032 0.2794)
						)
						(arc
							(start 0.2032 0.2794)
							(mid 0.239121 0.264521)
							(end 0.254 0.2286)
						)
						(arc
							(start 0.254 -0.2286)
							(mid 0.239121 -0.264521)
							(end 0.2032 -0.2794)
						)
					)
					(width 0)
					(fill yes)
				)
			)
		)
	)
	(footprint ""
		(layer "F.Cu")
		(at 5.08 -28.829)
		(property "Reference" "PL8"
			(at 0 0 0)
			(layer "F.SilkS")
			(hide yes)
			(effects
				(font
					(size 1.27 1.27)
				)
			)
		)
		(property "Value" "BLM18PG330SN1D-GP"
			(at -0.0254 -2.0193 0)
			(unlocked yes)
			(layer "F.Fab")
			(hide yes)
			(effects
				(font
					(size 1.016 1.016)
					(thickness 0.1524)
				)
			)
		)
		(property "Device Type" "L1608-UH38"
			(at -0.0254 -3.5433 0)
			(unlocked yes)
			(layer "F.Fab")
			(hide yes)
			(effects
				(font
					(size 1.016 1.016)
					(thickness 0.1524)
				)
			)
		)
		(duplicate_pad_numbers_are_jumpers no)
		(fp_line
			(start -0.4064 0)
			(end 0.4064 0)
			(stroke
				(width 0.2032)
				(type default)
			)
			(layer "F.SilkS")
		)
		(fp_rect
			(start -0.635 1.1811)
			(end 0.635 -1.1811)
			(stroke
				(width 0)
				(type default)
			)
			(fill no)
			(layer "F.CrtYd")
		)
		(fp_rect
			(start -0.635 1.1811)
			(end 0.635 -1.1811)
			(stroke
				(width 0)
				(type default)
			)
			(fill no)
			(layer "F.Fab")
		)
		(pad "1" smd custom
			(at 0 -0.6604)
			(size 0.19685 0.19685)
			(layers "F.Cu" "F.Mask" "F.Paste")
			(net "P12V")
			(options
				(clearance outline)
				(anchor circle)
			)
			(primitives
				(gr_poly
					(pts
						(arc
							(start 0.508 -0.2921)
							(mid 0.478242 -0.363942)
							(end 0.4064 -0.3937)
						)
						(arc
							(start -0.4064 -0.3937)
							(mid -0.478242 -0.363942)
							(end -0.508 -0.2921)
						)
						(arc
							(start -0.508 0.2921)
							(mid -0.478242 0.363942)
							(end -0.4064 0.3937)
						)
						(arc
							(start 0.4064 0.3937)
							(mid 0.478242 0.363942)
							(end 0.508 0.2921)
						)
					)
					(width 0)
					(fill yes)
				)
			)
		)
		(pad "2" smd custom
			(at 0 0.6604)
			(size 0.19685 0.19685)
			(layers "F.Cu" "F.Mask" "F.Paste")
			(net "P1V0_VIN")
			(options
				(clearance outline)
				(anchor circle)
			)
			(primitives
				(gr_poly
					(pts
						(arc
							(start 0.508 -0.2921)
							(mid 0.478242 -0.363942)
							(end 0.4064 -0.3937)
						)
						(arc
							(start -0.4064 -0.3937)
							(mid -0.478242 -0.363942)
							(end -0.508 -0.2921)
						)
						(arc
							(start -0.508 0.2921)
							(mid -0.478242 0.363942)
							(end -0.4064 0.3937)
						)
						(arc
							(start 0.4064 0.3937)
							(mid 0.478242 0.363942)
							(end 0.508 0.2921)
						)
					)
					(width 0)
					(fill yes)
				)
			)
		)
	)
	(footprint ""
		(layer "F.Cu")
		(at 184.912 -26.924 180)
		(property "Reference" "PR158"
			(at 0 0 180)
			(layer "F.SilkS")
			(hide yes)
			(effects
				(font
					(size 1.27 1.27)
				)
			)
		)
		(property "Value" "0R2J-2-GP"
			(at 1.7907 -1.1176 180)
			(unlocked yes)
			(layer "F.Fab")
			(hide yes)
			(effects
				(font
					(size 1.016 1.016)
					(thickness 0.1524)
				)
			)
		)
		(property "Device Type" "R402H16"
			(at 1.7907 -2.6416 180)
			(unlocked yes)
			(layer "F.Fab")
			(hide yes)
			(effects
				(font
					(size 1.016 1.016)
					(thickness 0.1524)
				)
			)
		)
		(duplicate_pad_numbers_are_jumpers no)
		(fp_rect
			(start -0.381 0.8382)
			(end 0.381 -0.8382)
			(stroke
				(width 0)
				(type default)
			)
			(fill no)
			(layer "F.CrtYd")
		)
		(fp_rect
			(start -0.381 0.8382)
			(end 0.381 -0.8382)
			(stroke
				(width 0)
				(type default)
			)
			(fill no)
			(layer "F.Fab")
		)
		(pad "1" smd custom
			(at 0 -0.4318 180)
			(size 0.127 0.127)
			(layers "F.Cu" "F.Mask" "F.Paste")
			(net "VR_PVDDR_A_VDD")
			(options
				(clearance outline)
				(anchor circle)
			)
			(primitives
				(gr_poly
					(pts
						(arc
							(start -0.2032 -0.2794)
							(mid -0.239121 -0.264521)
							(end -0.254 -0.2286)
						)
						(arc
							(start -0.254 0.2286)
							(mid -0.239121 0.264521)
							(end -0.2032 0.2794)
						)
						(arc
							(start 0.2032 0.2794)
							(mid 0.239121 0.264521)
							(end 0.254 0.2286)
						)
						(arc
							(start 0.254 -0.2286)
							(mid 0.239121 -0.264521)
							(end 0.2032 -0.2794)
						)
					)
					(width 0)
					(fill yes)
				)
			)
		)
		(pad "2" smd custom
			(at 0 0.4318 180)
			(size 0.127 0.127)
			(layers "F.Cu" "F.Mask" "F.Paste")
			(net "VR_PVDDR_A_ISEN2")
			(options
				(clearance outline)
				(anchor circle)
			)
			(primitives
				(gr_poly
					(pts
						(arc
							(start -0.2032 -0.2794)
							(mid -0.239121 -0.264521)
							(end -0.254 -0.2286)
						)
						(arc
							(start -0.254 0.2286)
							(mid -0.239121 0.264521)
							(end -0.2032 0.2794)
						)
						(arc
							(start 0.2032 0.2794)
							(mid 0.239121 0.264521)
							(end 0.254 0.2286)
						)
						(arc
							(start 0.254 -0.2286)
							(mid 0.239121 -0.264521)
							(end 0.2032 -0.2794)
						)
					)
					(width 0)
					(fill yes)
				)
			)
		)
	)
	(footprint ""
		(layer "F.Cu")
		(at 203.962 -66.1924 90)
		(property "Reference" "PC169"
			(at 0 0 90)
			(layer "F.SilkS")
			(hide yes)
			(effects
				(font
					(size 1.27 1.27)
				)
			)
		)
		(property "Value" "SC10U6D3V3MX-GP"
			(at -0.0254 -2.0193 90)
			(unlocked yes)
			(layer "F.Fab")
			(hide yes)
			(effects
				(font
					(size 1.016 1.016)
					(thickness 0.1524)
				)
			)
		)
		(property "Device Type" "C603H38"
			(at -0.0254 -3.5433 90)
			(unlocked yes)
			(layer "F.Fab")
			(hide yes)
			(effects
				(font
					(size 1.016 1.016)
					(thickness 0.1524)
				)
			)
		)
		(duplicate_pad_numbers_are_jumpers no)
		(fp_line
			(start -0.4064 0)
			(end 0.4064 0)
			(stroke
				(width 0.2286)
				(type default)
			)
			(layer "F.SilkS")
		)
		(fp_rect
			(start -0.635 1.1811)
			(end 0.635 -1.1811)
			(stroke
				(width 0)
				(type default)
			)
			(fill no)
			(layer "F.CrtYd")
		)
		(fp_rect
			(start -0.635 1.1811)
			(end 0.635 -1.1811)
			(stroke
				(width 0)
				(type default)
			)
			(fill no)
			(layer "F.Fab")
		)
		(pad "1" smd custom
			(at 0 -0.6604 90)
			(size 0.19685 0.19685)
			(layers "F.Cu" "F.Mask" "F.Paste")
			(net "PV_VDDR")
			(options
				(clearance outline)
				(anchor circle)
			)
			(primitives
				(gr_poly
					(pts
						(arc
							(start 0.508 -0.2921)
							(mid 0.478242 -0.363942)
							(end 0.4064 -0.3937)
						)
						(arc
							(start -0.4064 -0.3937)
							(mid -0.478242 -0.363942)
							(end -0.508 -0.2921)
						)
						(arc
							(start -0.508 0.2921)
							(mid -0.478242 0.363942)
							(end -0.4064 0.3937)
						)
						(arc
							(start 0.4064 0.3937)
							(mid 0.478242 0.363942)
							(end 0.508 0.2921)
						)
					)
					(width 0)
					(fill yes)
				)
			)
		)
		(pad "2" smd custom
			(at 0 0.6604 90)
			(size 0.19685 0.19685)
			(layers "F.Cu" "F.Mask" "F.Paste")
			(net "GND")
			(options
				(clearance outline)
				(anchor circle)
			)
			(primitives
				(gr_poly
					(pts
						(arc
							(start 0.508 -0.2921)
							(mid 0.478242 -0.363942)
							(end 0.4064 -0.3937)
						)
						(arc
							(start -0.4064 -0.3937)
							(mid -0.478242 -0.363942)
							(end -0.508 -0.2921)
						)
						(arc
							(start -0.508 0.2921)
							(mid -0.478242 0.363942)
							(end -0.4064 0.3937)
						)
						(arc
							(start 0.4064 0.3937)
							(mid 0.478242 0.363942)
							(end 0.508 0.2921)
						)
					)
					(width 0)
					(fill yes)
				)
			)
		)
	)
	(footprint ""
		(layer "F.Cu")
		(at 52.9844 -12.827 180)
		(property "Reference" "C316"
			(at 0 0 180)
			(layer "F.SilkS")
			(hide yes)
			(effects
				(font
					(size 1.27 1.27)
				)
			)
		)
		(property "Value" "SCD047U25V2KX-GP"
			(at 1.8923 -1.2065 180)
			(unlocked yes)
			(layer "F.Fab")
			(hide yes)
			(effects
				(font
					(size 1.016 1.016)
					(thickness 0.1524)
				)
			)
		)
		(property "Device Type" "C402H22"
			(at 1.8923 -2.7305 180)
			(unlocked yes)
			(layer "F.Fab")
			(hide yes)
			(effects
				(font
					(size 1.016 1.016)
					(thickness 0.1524)
				)
			)
		)
		(duplicate_pad_numbers_are_jumpers no)
		(fp_rect
			(start -0.381 0.7366)
			(end 0.381 -0.7366)
			(stroke
				(width 0)
				(type default)
			)
			(fill no)
			(layer "F.CrtYd")
		)
		(fp_rect
			(start -0.381 0.7366)
			(end 0.381 -0.7366)
			(stroke
				(width 0)
				(type default)
			)
			(fill no)
			(layer "F.Fab")
		)
		(pad "1" smd custom
			(at 0 -0.4572 180)
			(size 0.1143 0.1143)
			(layers "F.Cu" "F.Mask" "F.Paste")
			(net "CPU_GBE_RX_C_DP0")
			(options
				(clearance outline)
				(anchor circle)
			)
			(primitives
				(gr_poly
					(pts
						(arc
							(start -0.254 -0.1778)
							(mid -0.239121 -0.213721)
							(end -0.2032 -0.2286)
						)
						(arc
							(start 0.2032 -0.2286)
							(mid 0.239121 -0.213721)
							(end 0.254 -0.1778)
						)
						(arc
							(start 0.254 0.1778)
							(mid 0.239121 0.213721)
							(end 0.2032 0.2286)
						)
						(arc
							(start -0.2032 0.2286)
							(mid -0.239121 0.213721)
							(end -0.254 0.1778)
						)
					)
					(width 0)
					(fill yes)
				)
			)
		)
		(pad "2" smd custom
			(at 0 0.4572 180)
			(size 0.1143 0.1143)
			(layers "F.Cu" "F.Mask" "F.Paste")
			(net "CPU_GBE_RX_DP0")
			(options
				(clearance outline)
				(anchor circle)
			)
			(primitives
				(gr_poly
					(pts
						(arc
							(start -0.254 -0.1778)
							(mid -0.239121 -0.213721)
							(end -0.2032 -0.2286)
						)
						(arc
							(start 0.2032 -0.2286)
							(mid 0.239121 -0.213721)
							(end 0.254 -0.1778)
						)
						(arc
							(start 0.254 0.1778)
							(mid 0.239121 0.213721)
							(end 0.2032 0.2286)
						)
						(arc
							(start -0.2032 0.2286)
							(mid -0.239121 0.213721)
							(end -0.254 0.1778)
						)
					)
					(width 0)
					(fill yes)
				)
			)
		)
	)
	(footprint ""
		(layer "F.Cu")
		(at 182.118 -48.768)
		(property "Reference" "C95"
			(at 0 0 0)
			(layer "F.SilkS")
			(hide yes)
			(effects
				(font
					(size 1.27 1.27)
				)
			)
		)
		(property "Value" "SCD1U16V2KX-3GP"
			(at 1.1811 -2.7051 0)
			(unlocked yes)
			(layer "F.Fab")
			(hide yes)
			(effects
				(font
					(size 1.016 1.016)
					(thickness 0.1524)
				)
			)
		)
		(property "Device Type" "C402H22"
			(at 1.1811 -4.2291 0)
			(unlocked yes)
			(layer "F.Fab")
			(hide yes)
			(effects
				(font
					(size 1.016 1.016)
					(thickness 0.1524)
				)
			)
		)
		(duplicate_pad_numbers_are_jumpers no)
		(fp_rect
			(start -0.381 0.7366)
			(end 0.381 -0.7366)
			(stroke
				(width 0)
				(type default)
			)
			(fill no)
			(layer "F.CrtYd")
		)
		(fp_rect
			(start -0.381 0.7366)
			(end 0.381 -0.7366)
			(stroke
				(width 0)
				(type default)
			)
			(fill no)
			(layer "F.Fab")
		)
		(pad "1" smd custom
			(at 0 -0.4572)
			(size 0.1143 0.1143)
			(layers "F.Cu" "F.Mask" "F.Paste")
			(net "P3V3_STBY")
			(options
				(clearance outline)
				(anchor circle)
			)
			(primitives
				(gr_poly
					(pts
						(arc
							(start -0.254 -0.1778)
							(mid -0.239121 -0.213721)
							(end -0.2032 -0.2286)
						)
						(arc
							(start 0.2032 -0.2286)
							(mid 0.239121 -0.213721)
							(end 0.254 -0.1778)
						)
						(arc
							(start 0.254 0.1778)
							(mid 0.239121 0.213721)
							(end 0.2032 0.2286)
						)
						(arc
							(start -0.2032 0.2286)
							(mid -0.239121 0.213721)
							(end -0.254 0.1778)
						)
					)
					(width 0)
					(fill yes)
				)
			)
		)
		(pad "2" smd custom
			(at 0 0.4572)
			(size 0.1143 0.1143)
			(layers "F.Cu" "F.Mask" "F.Paste")
			(net "GND")
			(options
				(clearance outline)
				(anchor circle)
			)
			(primitives
				(gr_poly
					(pts
						(arc
							(start -0.254 -0.1778)
							(mid -0.239121 -0.213721)
							(end -0.2032 -0.2286)
						)
						(arc
							(start 0.2032 -0.2286)
							(mid 0.239121 -0.213721)
							(end 0.254 -0.1778)
						)
						(arc
							(start 0.254 0.1778)
							(mid 0.239121 0.213721)
							(end 0.2032 0.2286)
						)
						(arc
							(start -0.2032 0.2286)
							(mid -0.239121 0.213721)
							(end -0.254 0.1778)
						)
					)
					(width 0)
					(fill yes)
				)
			)
		)
	)
	(footprint ""
		(layer "F.Cu")
		(at 187.96 -59.944)
		(property "Reference" "C353"
			(at 0 0 0)
			(layer "F.SilkS")
			(hide yes)
			(effects
				(font
					(size 1.27 1.27)
				)
			)
		)
		(property "Value" "SC1U6D3V3KX-2GP"
			(at -0.0254 -2.0193 0)
			(unlocked yes)
			(layer "F.Fab")
			(hide yes)
			(effects
				(font
					(size 1.016 1.016)
					(thickness 0.1524)
				)
			)
		)
		(property "Device Type" "C603H36"
			(at -0.0254 -3.5433 0)
			(unlocked yes)
			(layer "F.Fab")
			(hide yes)
			(effects
				(font
					(size 1.016 1.016)
					(thickness 0.1524)
				)
			)
		)
		(duplicate_pad_numbers_are_jumpers no)
		(fp_line
			(start -0.4064 0)
			(end 0.4064 0)
			(stroke
				(width 0.2286)
				(type default)
			)
			(layer "F.SilkS")
		)
		(fp_rect
			(start -0.635 1.1811)
			(end 0.635 -1.1811)
			(stroke
				(width 0)
				(type default)
			)
			(fill no)
			(layer "F.CrtYd")
		)
		(fp_rect
			(start -0.635 1.1811)
			(end 0.635 -1.1811)
			(stroke
				(width 0)
				(type default)
			)
			(fill no)
			(layer "F.Fab")
		)
		(pad "1" smd custom
			(at 0 -0.6604)
			(size 0.19685 0.19685)
			(layers "F.Cu" "F.Mask" "F.Paste")
			(net "DDR3_M_A_VREF_DQ1")
			(options
				(clearance outline)
				(anchor circle)
			)
			(primitives
				(gr_poly
					(pts
						(arc
							(start 0.508 -0.2921)
							(mid 0.478242 -0.363942)
							(end 0.4064 -0.3937)
						)
						(arc
							(start -0.4064 -0.3937)
							(mid -0.478242 -0.363942)
							(end -0.508 -0.2921)
						)
						(arc
							(start -0.508 0.2921)
							(mid -0.478242 0.363942)
							(end -0.4064 0.3937)
						)
						(arc
							(start 0.4064 0.3937)
							(mid 0.478242 0.363942)
							(end 0.508 0.2921)
						)
					)
					(width 0)
					(fill yes)
				)
			)
		)
		(pad "2" smd custom
			(at 0 0.6604)
			(size 0.19685 0.19685)
			(layers "F.Cu" "F.Mask" "F.Paste")
			(net "GND")
			(options
				(clearance outline)
				(anchor circle)
			)
			(primitives
				(gr_poly
					(pts
						(arc
							(start 0.508 -0.2921)
							(mid 0.478242 -0.363942)
							(end 0.4064 -0.3937)
						)
						(arc
							(start -0.4064 -0.3937)
							(mid -0.478242 -0.363942)
							(end -0.508 -0.2921)
						)
						(arc
							(start -0.508 0.2921)
							(mid -0.478242 0.363942)
							(end -0.4064 0.3937)
						)
						(arc
							(start 0.4064 0.3937)
							(mid 0.478242 0.363942)
							(end 0.508 0.2921)
						)
					)
					(width 0)
					(fill yes)
				)
			)
		)
	)
	(footprint ""
		(layer "F.Cu")
		(at 8.509 -57.404 90)
		(property "Reference" "C44"
			(at 0 0 90)
			(layer "F.SilkS")
			(hide yes)
			(effects
				(font
					(size 1.27 1.27)
				)
			)
		)
		(property "Value" "SCD1U16V2KX-3GP"
			(at 1.1811 -2.7051 90)
			(unlocked yes)
			(layer "F.Fab")
			(hide yes)
			(effects
				(font
					(size 1.016 1.016)
					(thickness 0.1524)
				)
			)
		)
		(property "Device Type" "C402H22"
			(at 1.1811 -4.2291 90)
			(unlocked yes)
			(layer "F.Fab")
			(hide yes)
			(effects
				(font
					(size 1.016 1.016)
					(thickness 0.1524)
				)
			)
		)
		(duplicate_pad_numbers_are_jumpers no)
		(fp_rect
			(start -0.381 0.7366)
			(end 0.381 -0.7366)
			(stroke
				(width 0)
				(type default)
			)
			(fill no)
			(layer "F.CrtYd")
		)
		(fp_rect
			(start -0.381 0.7366)
			(end 0.381 -0.7366)
			(stroke
				(width 0)
				(type default)
			)
			(fill no)
			(layer "F.Fab")
		)
		(pad "1" smd custom
			(at 0 -0.4572 90)
			(size 0.1143 0.1143)
			(layers "F.Cu" "F.Mask" "F.Paste")
			(net "P2E_CPU_NGFF_C_RX_DP13")
			(options
				(clearance outline)
				(anchor circle)
			)
			(primitives
				(gr_poly
					(pts
						(arc
							(start -0.254 -0.1778)
							(mid -0.239121 -0.213721)
							(end -0.2032 -0.2286)
						)
						(arc
							(start 0.2032 -0.2286)
							(mid 0.239121 -0.213721)
							(end 0.254 -0.1778)
						)
						(arc
							(start 0.254 0.1778)
							(mid 0.239121 0.213721)
							(end 0.2032 0.2286)
						)
						(arc
							(start -0.2032 0.2286)
							(mid -0.239121 0.213721)
							(end -0.254 0.1778)
						)
					)
					(width 0)
					(fill yes)
				)
			)
		)
		(pad "2" smd custom
			(at 0 0.4572 90)
			(size 0.1143 0.1143)
			(layers "F.Cu" "F.Mask" "F.Paste")
			(net "P2E_CPU_NGFF_RX_DP13")
			(options
				(clearance outline)
				(anchor circle)
			)
			(primitives
				(gr_poly
					(pts
						(arc
							(start -0.254 -0.1778)
							(mid -0.239121 -0.213721)
							(end -0.2032 -0.2286)
						)
						(arc
							(start 0.2032 -0.2286)
							(mid 0.239121 -0.213721)
							(end 0.254 -0.1778)
						)
						(arc
							(start 0.254 0.1778)
							(mid 0.239121 0.213721)
							(end 0.2032 0.2286)
						)
						(arc
							(start -0.2032 0.2286)
							(mid -0.239121 0.213721)
							(end -0.254 0.1778)
						)
					)
					(width 0)
					(fill yes)
				)
			)
		)
	)
	(footprint ""
		(layer "F.Cu")
		(at 119.8118 -63.373 -90)
		(property "Reference" "C110"
			(at 0 0 270)
			(layer "F.SilkS")
			(hide yes)
			(effects
				(font
					(size 1.27 1.27)
				)
			)
		)
		(property "Value" "SC10U6D3V3MX-GP"
			(at 0 -2.8194 270)
			(unlocked yes)
			(layer "F.Fab")
			(hide yes)
			(effects
				(font
					(size 1.016 1.016)
					(thickness 0.1524)
				)
			)
		)
		(property "Device Type" "C603H38"
			(at 0 -4.3434 270)
			(unlocked yes)
			(layer "F.Fab")
			(hide yes)
			(effects
				(font
					(size 1.016 1.016)
					(thickness 0.1524)
				)
			)
		)
		(duplicate_pad_numbers_are_jumpers no)
		(fp_line
			(start -0.4064 0)
			(end 0.4064 0)
			(stroke
				(width 0.2286)
				(type default)
			)
			(layer "F.SilkS")
		)
		(fp_rect
			(start -0.635 1.1811)
			(end 0.635 -1.1811)
			(stroke
				(width 0)
				(type default)
			)
			(fill no)
			(layer "F.CrtYd")
		)
		(fp_rect
			(start -0.635 1.1811)
			(end 0.635 -1.1811)
			(stroke
				(width 0)
				(type default)
			)
			(fill no)
			(layer "F.Fab")
		)
		(pad "1" smd custom
			(at 0 -0.6604 270)
			(size 0.19685 0.19685)
			(layers "F.Cu" "F.Mask" "F.Paste")
			(net "PV_VTT_DDR_A")
			(options
				(clearance outline)
				(anchor circle)
			)
			(primitives
				(gr_poly
					(pts
						(arc
							(start 0.508 -0.2921)
							(mid 0.478242 -0.363942)
							(end 0.4064 -0.3937)
						)
						(arc
							(start -0.4064 -0.3937)
							(mid -0.478242 -0.363942)
							(end -0.508 -0.2921)
						)
						(arc
							(start -0.508 0.2921)
							(mid -0.478242 0.363942)
							(end -0.4064 0.3937)
						)
						(arc
							(start 0.4064 0.3937)
							(mid 0.478242 0.363942)
							(end 0.508 0.2921)
						)
					)
					(width 0)
					(fill yes)
				)
			)
		)
		(pad "2" smd custom
			(at 0 0.6604 270)
			(size 0.19685 0.19685)
			(layers "F.Cu" "F.Mask" "F.Paste")
			(net "GND")
			(options
				(clearance outline)
				(anchor circle)
			)
			(primitives
				(gr_poly
					(pts
						(arc
							(start 0.508 -0.2921)
							(mid 0.478242 -0.363942)
							(end 0.4064 -0.3937)
						)
						(arc
							(start -0.4064 -0.3937)
							(mid -0.478242 -0.363942)
							(end -0.508 -0.2921)
						)
						(arc
							(start -0.508 0.2921)
							(mid -0.478242 0.363942)
							(end -0.4064 0.3937)
						)
						(arc
							(start 0.4064 0.3937)
							(mid 0.478242 0.363942)
							(end 0.508 0.2921)
						)
					)
					(width 0)
					(fill yes)
				)
			)
		)
	)
	(footprint ""
		(layer "F.Cu")
		(at 204.597 -33.782)
		(property "Reference" "PRT2"
			(at 0 0 0)
			(layer "F.SilkS")
			(hide yes)
			(effects
				(font
					(size 1.27 1.27)
				)
			)
		)
		(property "Value" "NTC-100K-11-GP-U"
			(at 1.6256 -1.6637 0)
			(unlocked yes)
			(layer "F.Fab")
			(hide yes)
			(effects
				(font
					(size 1.016 1.016)
					(thickness 0.1524)
				)
			)
		)
		(property "Device Type" "NTC-402H24-U"
			(at 1.6256 -3.1877 0)
			(unlocked yes)
			(layer "F.Fab")
			(hide yes)
			(effects
				(font
					(size 1.016 1.016)
					(thickness 0.1524)
				)
			)
		)
		(duplicate_pad_numbers_are_jumpers no)
		(fp_rect
			(start -0.381 0.8382)
			(end 0.381 -0.8382)
			(stroke
				(width 0)
				(type default)
			)
			(fill no)
			(layer "F.CrtYd")
		)
		(fp_rect
			(start -0.381 0.8382)
			(end 0.381 -0.8382)
			(stroke
				(width 0)
				(type default)
			)
			(fill no)
			(layer "F.Fab")
		)
		(pad "1" smd custom
			(at 0 -0.4318)
			(size 0.127 0.127)
			(layers "F.Cu" "F.Mask" "F.Paste")
			(net "GND")
			(options
				(clearance outline)
				(anchor circle)
			)
			(primitives
				(gr_poly
					(pts
						(arc
							(start -0.2032 -0.2794)
							(mid -0.239121 -0.264521)
							(end -0.254 -0.2286)
						)
						(arc
							(start -0.254 0.2286)
							(mid -0.239121 0.264521)
							(end -0.2032 0.2794)
						)
						(arc
							(start 0.2032 0.2794)
							(mid 0.239121 0.264521)
							(end 0.254 0.2286)
						)
						(arc
							(start 0.254 -0.2286)
							(mid 0.239121 -0.264521)
							(end 0.2032 -0.2794)
						)
					)
					(width 0)
					(fill yes)
				)
			)
		)
		(pad "2" smd custom
			(at 0 0.4318)
			(size 0.127 0.127)
			(layers "F.Cu" "F.Mask" "F.Paste")
			(net "VR_PVDDR_A_NTC_R")
			(options
				(clearance outline)
				(anchor circle)
			)
			(primitives
				(gr_poly
					(pts
						(arc
							(start -0.2032 -0.2794)
							(mid -0.239121 -0.264521)
							(end -0.254 -0.2286)
						)
						(arc
							(start -0.254 0.2286)
							(mid -0.239121 0.264521)
							(end -0.2032 0.2794)
						)
						(arc
							(start 0.2032 0.2794)
							(mid 0.239121 0.264521)
							(end 0.254 0.2286)
						)
						(arc
							(start 0.254 -0.2286)
							(mid 0.239121 -0.264521)
							(end 0.2032 -0.2794)
						)
					)
					(width 0)
					(fill yes)
				)
			)
		)
	)
	(footprint ""
		(layer "F.Cu")
		(at 30.734 -55.245 180)
		(property "Reference" "PC56"
			(at 0 0 180)
			(layer "F.SilkS")
			(hide yes)
			(effects
				(font
					(size 1.27 1.27)
				)
			)
		)
		(property "Value" "SCD22U16V3KX-2-GP"
			(at -0.0254 -2.0193 180)
			(unlocked yes)
			(layer "F.Fab")
			(hide yes)
			(effects
				(font
					(size 1.016 1.016)
					(thickness 0.1524)
				)
			)
		)
		(property "Device Type" "C603H36"
			(at -0.0254 -3.5433 180)
			(unlocked yes)
			(layer "F.Fab")
			(hide yes)
			(effects
				(font
					(size 1.016 1.016)
					(thickness 0.1524)
				)
			)
		)
		(duplicate_pad_numbers_are_jumpers no)
		(fp_line
			(start -0.4064 0)
			(end 0.4064 0)
			(stroke
				(width 0.2286)
				(type default)
			)
			(layer "F.SilkS")
		)
		(fp_rect
			(start -0.635 1.1811)
			(end 0.635 -1.1811)
			(stroke
				(width 0)
				(type default)
			)
			(fill no)
			(layer "F.CrtYd")
		)
		(fp_rect
			(start -0.635 1.1811)
			(end 0.635 -1.1811)
			(stroke
				(width 0)
				(type default)
			)
			(fill no)
			(layer "F.Fab")
		)
		(pad "1" smd custom
			(at 0 -0.6604 180)
			(size 0.19685 0.19685)
			(layers "F.Cu" "F.Mask" "F.Paste")
			(net "VR_PVCCP_PVNN_VIN")
			(options
				(clearance outline)
				(anchor circle)
			)
			(primitives
				(gr_poly
					(pts
						(arc
							(start 0.508 -0.2921)
							(mid 0.478242 -0.363942)
							(end 0.4064 -0.3937)
						)
						(arc
							(start -0.4064 -0.3937)
							(mid -0.478242 -0.363942)
							(end -0.508 -0.2921)
						)
						(arc
							(start -0.508 0.2921)
							(mid -0.478242 0.363942)
							(end -0.4064 0.3937)
						)
						(arc
							(start 0.4064 0.3937)
							(mid 0.478242 0.363942)
							(end 0.508 0.2921)
						)
					)
					(width 0)
					(fill yes)
				)
			)
		)
		(pad "2" smd custom
			(at 0 0.6604 180)
			(size 0.19685 0.19685)
			(layers "F.Cu" "F.Mask" "F.Paste")
			(net "GND")
			(options
				(clearance outline)
				(anchor circle)
			)
			(primitives
				(gr_poly
					(pts
						(arc
							(start 0.508 -0.2921)
							(mid 0.478242 -0.363942)
							(end 0.4064 -0.3937)
						)
						(arc
							(start -0.4064 -0.3937)
							(mid -0.478242 -0.363942)
							(end -0.508 -0.2921)
						)
						(arc
							(start -0.508 0.2921)
							(mid -0.478242 0.363942)
							(end -0.4064 0.3937)
						)
						(arc
							(start 0.4064 0.3937)
							(mid 0.478242 0.363942)
							(end 0.508 0.2921)
						)
					)
					(width 0)
					(fill yes)
				)
			)
		)
	)
	(footprint ""
		(layer "F.Cu")
		(at 174.117 -57.15)
		(property "Reference" "R192"
			(at 0 0 0)
			(layer "F.SilkS")
			(hide yes)
			(effects
				(font
					(size 1.27 1.27)
				)
			)
		)
		(property "Value" "4K7R2F-GP"
			(at 0.064008 -3.993896 0)
			(unlocked yes)
			(layer "F.Fab")
			(hide yes)
			(effects
				(font
					(size 1.016 1.016)
					(thickness 0.1524)
				)
			)
		)
		(property "Device Type" "R402H16"
			(at 0.064008 -5.517896 0)
			(unlocked yes)
			(layer "F.Fab")
			(hide yes)
			(effects
				(font
					(size 1.016 1.016)
					(thickness 0.1524)
				)
			)
		)
		(duplicate_pad_numbers_are_jumpers no)
		(fp_rect
			(start -0.381 0.8382)
			(end 0.381 -0.8382)
			(stroke
				(width 0)
				(type default)
			)
			(fill no)
			(layer "F.CrtYd")
		)
		(fp_rect
			(start -0.381 0.8382)
			(end 0.381 -0.8382)
			(stroke
				(width 0)
				(type default)
			)
			(fill no)
			(layer "F.Fab")
		)
		(pad "1" smd custom
			(at 0 -0.4318)
			(size 0.127 0.127)
			(layers "F.Cu" "F.Mask" "F.Paste")
			(net "P3V3_STBY")
			(options
				(clearance outline)
				(anchor circle)
			)
			(primitives
				(gr_poly
					(pts
						(arc
							(start -0.2032 -0.2794)
							(mid -0.239121 -0.264521)
							(end -0.254 -0.2286)
						)
						(arc
							(start -0.254 0.2286)
							(mid -0.239121 0.264521)
							(end -0.2032 0.2794)
						)
						(arc
							(start 0.2032 0.2794)
							(mid 0.239121 0.264521)
							(end 0.254 0.2286)
						)
						(arc
							(start 0.254 -0.2286)
							(mid 0.239121 -0.264521)
							(end 0.2032 -0.2794)
						)
					)
					(width 0)
					(fill yes)
				)
			)
		)
		(pad "2" smd custom
			(at 0 0.4318)
			(size 0.127 0.127)
			(layers "F.Cu" "F.Mask" "F.Paste")
			(net "EEPROM_A2")
			(options
				(clearance outline)
				(anchor circle)
			)
			(primitives
				(gr_poly
					(pts
						(arc
							(start -0.2032 -0.2794)
							(mid -0.239121 -0.264521)
							(end -0.254 -0.2286)
						)
						(arc
							(start -0.254 0.2286)
							(mid -0.239121 0.264521)
							(end -0.2032 0.2794)
						)
						(arc
							(start 0.2032 0.2794)
							(mid 0.239121 0.264521)
							(end 0.254 0.2286)
						)
						(arc
							(start 0.254 -0.2286)
							(mid 0.239121 -0.264521)
							(end 0.2032 -0.2794)
						)
					)
					(width 0)
					(fill yes)
				)
			)
		)
	)
	(footprint ""
		(layer "F.Cu")
		(at 12.9286 -62.8396 -90)
		(property "Reference" "PR39"
			(at 0 0 270)
			(layer "F.SilkS")
			(hide yes)
			(effects
				(font
					(size 1.27 1.27)
				)
			)
		)
		(property "Value" "100R2F-L1-GP-U"
			(at 1.7907 -1.1176 270)
			(unlocked yes)
			(layer "F.Fab")
			(hide yes)
			(effects
				(font
					(size 1.016 1.016)
					(thickness 0.1524)
				)
			)
		)
		(property "Device Type" "R402H14"
			(at 1.7907 -2.6416 270)
			(unlocked yes)
			(layer "F.Fab")
			(hide yes)
			(effects
				(font
					(size 1.016 1.016)
					(thickness 0.1524)
				)
			)
		)
		(duplicate_pad_numbers_are_jumpers no)
		(fp_rect
			(start -0.381 0.8382)
			(end 0.381 -0.8382)
			(stroke
				(width 0)
				(type default)
			)
			(fill no)
			(layer "F.CrtYd")
		)
		(fp_rect
			(start -0.381 0.8382)
			(end 0.381 -0.8382)
			(stroke
				(width 0)
				(type default)
			)
			(fill no)
			(layer "F.Fab")
		)
		(pad "1" smd custom
			(at 0 -0.4318 270)
			(size 0.127 0.127)
			(layers "F.Cu" "F.Mask" "F.Paste")
			(net "SVID_CPU_DATA")
			(options
				(clearance outline)
				(anchor circle)
			)
			(primitives
				(gr_poly
					(pts
						(arc
							(start -0.2032 -0.2794)
							(mid -0.239121 -0.264521)
							(end -0.254 -0.2286)
						)
						(arc
							(start -0.254 0.2286)
							(mid -0.239121 0.264521)
							(end -0.2032 0.2794)
						)
						(arc
							(start 0.2032 0.2794)
							(mid 0.239121 0.264521)
							(end 0.254 0.2286)
						)
						(arc
							(start 0.254 -0.2286)
							(mid 0.239121 -0.264521)
							(end 0.2032 -0.2794)
						)
					)
					(width 0)
					(fill yes)
				)
			)
		)
		(pad "2" smd custom
			(at 0 0.4318 270)
			(size 0.127 0.127)
			(layers "F.Cu" "F.Mask" "F.Paste")
			(net "P1V0")
			(options
				(clearance outline)
				(anchor circle)
			)
			(primitives
				(gr_poly
					(pts
						(arc
							(start -0.2032 -0.2794)
							(mid -0.239121 -0.264521)
							(end -0.254 -0.2286)
						)
						(arc
							(start -0.254 0.2286)
							(mid -0.239121 0.264521)
							(end -0.2032 0.2794)
						)
						(arc
							(start 0.2032 0.2794)
							(mid 0.239121 0.264521)
							(end 0.254 0.2286)
						)
						(arc
							(start 0.254 -0.2286)
							(mid 0.239121 -0.264521)
							(end 0.2032 -0.2794)
						)
					)
					(width 0)
					(fill yes)
				)
			)
		)
	)
	(footprint ""
		(layer "F.Cu")
		(at 12.9286 -61.3156 90)
		(property "Reference" "PR45"
			(at 0 0 90)
			(layer "F.SilkS")
			(hide yes)
			(effects
				(font
					(size 1.27 1.27)
				)
			)
		)
		(property "Value" "0R2J-2-GP"
			(at 1.7907 -1.1176 90)
			(unlocked yes)
			(layer "F.Fab")
			(hide yes)
			(effects
				(font
					(size 1.016 1.016)
					(thickness 0.1524)
				)
			)
		)
		(property "Device Type" "R402H16"
			(at 1.7907 -2.6416 90)
			(unlocked yes)
			(layer "F.Fab")
			(hide yes)
			(effects
				(font
					(size 1.016 1.016)
					(thickness 0.1524)
				)
			)
		)
		(duplicate_pad_numbers_are_jumpers no)
		(fp_rect
			(start -0.381 0.8382)
			(end 0.381 -0.8382)
			(stroke
				(width 0)
				(type default)
			)
			(fill no)
			(layer "F.CrtYd")
		)
		(fp_rect
			(start -0.381 0.8382)
			(end 0.381 -0.8382)
			(stroke
				(width 0)
				(type default)
			)
			(fill no)
			(layer "F.Fab")
		)
		(pad "1" smd custom
			(at 0 -0.4318 90)
			(size 0.127 0.127)
			(layers "F.Cu" "F.Mask" "F.Paste")
			(net "TP_PVCCP_ALERT")
			(options
				(clearance outline)
				(anchor circle)
			)
			(primitives
				(gr_poly
					(pts
						(arc
							(start -0.2032 -0.2794)
							(mid -0.239121 -0.264521)
							(end -0.254 -0.2286)
						)
						(arc
							(start -0.254 0.2286)
							(mid -0.239121 0.264521)
							(end -0.2032 0.2794)
						)
						(arc
							(start 0.2032 0.2794)
							(mid 0.239121 0.264521)
							(end 0.254 0.2286)
						)
						(arc
							(start 0.254 -0.2286)
							(mid 0.239121 -0.264521)
							(end 0.2032 -0.2794)
						)
					)
					(width 0)
					(fill yes)
				)
			)
		)
		(pad "2" smd custom
			(at 0 0.4318 90)
			(size 0.127 0.127)
			(layers "F.Cu" "F.Mask" "F.Paste")
			(net "SVID_CPU_ALERT#")
			(options
				(clearance outline)
				(anchor circle)
			)
			(primitives
				(gr_poly
					(pts
						(arc
							(start -0.2032 -0.2794)
							(mid -0.239121 -0.264521)
							(end -0.254 -0.2286)
						)
						(arc
							(start -0.254 0.2286)
							(mid -0.239121 0.264521)
							(end -0.2032 0.2794)
						)
						(arc
							(start 0.2032 0.2794)
							(mid 0.239121 0.264521)
							(end 0.254 0.2286)
						)
						(arc
							(start 0.254 -0.2286)
							(mid 0.239121 -0.264521)
							(end 0.2032 -0.2794)
						)
					)
					(width 0)
					(fill yes)
				)
			)
		)
	)
	(footprint ""
		(layer "F.Cu")
		(at 55.626 -68.072 180)
		(property "Reference" "C9"
			(at 0 0 180)
			(layer "F.SilkS")
			(hide yes)
			(effects
				(font
					(size 1.27 1.27)
				)
			)
		)
		(property "Value" "SC22U6D3V5MX-2GP"
			(at 0 -4.9022 180)
			(unlocked yes)
			(layer "F.Fab")
			(hide yes)
			(effects
				(font
					(size 1.016 1.016)
					(thickness 0.1524)
				)
			)
		)
		(property "Device Type" "C805H58"
			(at 0 -6.8072 180)
			(unlocked yes)
			(layer "F.Fab")
			(hide yes)
			(effects
				(font
					(size 1.016 1.016)
					(thickness 0.1524)
				)
			)
		)
		(duplicate_pad_numbers_are_jumpers no)
		(fp_line
			(start 0.6096 0)
			(end -0.6096 0)
			(stroke
				(width 0.3048)
				(type default)
			)
			(layer "F.SilkS")
		)
		(fp_poly
			(pts
				(xy -0.9017 1.4351) (xy 0.9017 1.4351) (xy 0.9017 -1.4351) (xy -0.9017 -1.4351)
			)
			(stroke
				(width 0)
				(type default)
			)
			(fill no)
			(layer "F.CrtYd")
		)
		(fp_poly
			(pts
				(xy 0.9017 1.4351) (xy 0.9017 -1.4351) (xy -0.9017 -1.4351) (xy -0.9017 1.4351)
			)
			(stroke
				(width 0)
				(type default)
			)
			(fill no)
			(layer "F.Fab")
		)
		(pad "1" smd rect
			(at 0 -0.8382 180)
			(size 1.5494 0.9398)
			(layers "F.Cu" "F.Mask" "F.Paste")
			(net "PVNN")
		)
		(pad "2" smd rect
			(at 0 0.8382 180)
			(size 1.5494 0.9398)
			(layers "F.Cu" "F.Mask" "F.Paste")
			(net "GND")
		)
	)
	(footprint ""
		(layer "F.Cu")
		(at 11.3792 -52.7812 90)
		(property "Reference" "C58"
			(at 0 0 90)
			(layer "F.SilkS")
			(hide yes)
			(effects
				(font
					(size 1.27 1.27)
				)
			)
		)
		(property "Value" "SCD01U16V2KX-3GP"
			(at 1.1811 -2.7051 90)
			(unlocked yes)
			(layer "F.Fab")
			(hide yes)
			(effects
				(font
					(size 1.016 1.016)
					(thickness 0.1524)
				)
			)
		)
		(property "Device Type" "C402H22"
			(at 1.1811 -4.2291 90)
			(unlocked yes)
			(layer "F.Fab")
			(hide yes)
			(effects
				(font
					(size 1.016 1.016)
					(thickness 0.1524)
				)
			)
		)
		(duplicate_pad_numbers_are_jumpers no)
		(fp_rect
			(start -0.381 0.7366)
			(end 0.381 -0.7366)
			(stroke
				(width 0)
				(type default)
			)
			(fill no)
			(layer "F.CrtYd")
		)
		(fp_rect
			(start -0.381 0.7366)
			(end 0.381 -0.7366)
			(stroke
				(width 0)
				(type default)
			)
			(fill no)
			(layer "F.Fab")
		)
		(pad "1" smd custom
			(at 0 -0.4572 90)
			(size 0.1143 0.1143)
			(layers "F.Cu" "F.Mask" "F.Paste")
			(net "SATA3_RX_DN1")
			(options
				(clearance outline)
				(anchor circle)
			)
			(primitives
				(gr_poly
					(pts
						(arc
							(start -0.254 -0.1778)
							(mid -0.239121 -0.213721)
							(end -0.2032 -0.2286)
						)
						(arc
							(start 0.2032 -0.2286)
							(mid 0.239121 -0.213721)
							(end 0.254 -0.1778)
						)
						(arc
							(start 0.254 0.1778)
							(mid 0.239121 0.213721)
							(end 0.2032 0.2286)
						)
						(arc
							(start -0.2032 0.2286)
							(mid -0.239121 0.213721)
							(end -0.254 0.1778)
						)
					)
					(width 0)
					(fill yes)
				)
			)
		)
		(pad "2" smd custom
			(at 0 0.4572 90)
			(size 0.1143 0.1143)
			(layers "F.Cu" "F.Mask" "F.Paste")
			(net "P2E_CPU_NGFF_C_RX_DP12")
			(options
				(clearance outline)
				(anchor circle)
			)
			(primitives
				(gr_poly
					(pts
						(arc
							(start -0.254 -0.1778)
							(mid -0.239121 -0.213721)
							(end -0.2032 -0.2286)
						)
						(arc
							(start 0.2032 -0.2286)
							(mid 0.239121 -0.213721)
							(end 0.254 -0.1778)
						)
						(arc
							(start 0.254 0.1778)
							(mid 0.239121 0.213721)
							(end 0.2032 0.2286)
						)
						(arc
							(start -0.2032 0.2286)
							(mid -0.239121 0.213721)
							(end -0.254 0.1778)
						)
					)
					(width 0)
					(fill yes)
				)
			)
		)
	)
	(footprint ""
		(layer "F.Cu")
		(at 164.211 -45.847 180)
		(property "Reference" "R210"
			(at 0 0 180)
			(layer "F.SilkS")
			(hide yes)
			(effects
				(font
					(size 1.27 1.27)
				)
			)
		)
		(property "Value" "0R2J-2-GP"
			(at 1.7907 -1.1176 180)
			(unlocked yes)
			(layer "F.Fab")
			(hide yes)
			(effects
				(font
					(size 1.016 1.016)
					(thickness 0.1524)
				)
			)
		)
		(property "Device Type" "R402H16"
			(at 1.7907 -2.6416 180)
			(unlocked yes)
			(layer "F.Fab")
			(hide yes)
			(effects
				(font
					(size 1.016 1.016)
					(thickness 0.1524)
				)
			)
		)
		(duplicate_pad_numbers_are_jumpers no)
		(fp_rect
			(start -0.381 0.8382)
			(end 0.381 -0.8382)
			(stroke
				(width 0)
				(type default)
			)
			(fill no)
			(layer "F.CrtYd")
		)
		(fp_rect
			(start -0.381 0.8382)
			(end 0.381 -0.8382)
			(stroke
				(width 0)
				(type default)
			)
			(fill no)
			(layer "F.Fab")
		)
		(pad "1" smd custom
			(at 0 -0.4318 180)
			(size 0.127 0.127)
			(layers "F.Cu" "F.Mask" "F.Paste")
			(net "JTAG_PLD_TMS")
			(options
				(clearance outline)
				(anchor circle)
			)
			(primitives
				(gr_poly
					(pts
						(arc
							(start -0.2032 -0.2794)
							(mid -0.239121 -0.264521)
							(end -0.254 -0.2286)
						)
						(arc
							(start -0.254 0.2286)
							(mid -0.239121 0.264521)
							(end -0.2032 0.2794)
						)
						(arc
							(start 0.2032 0.2794)
							(mid 0.239121 0.264521)
							(end 0.254 0.2286)
						)
						(arc
							(start 0.254 -0.2286)
							(mid 0.239121 -0.264521)
							(end 0.2032 -0.2794)
						)
					)
					(width 0)
					(fill yes)
				)
			)
		)
		(pad "2" smd custom
			(at 0 0.4318 180)
			(size 0.127 0.127)
			(layers "F.Cu" "F.Mask" "F.Paste")
			(net "JTAG_PLD_TMS_D")
			(options
				(clearance outline)
				(anchor circle)
			)
			(primitives
				(gr_poly
					(pts
						(arc
							(start -0.2032 -0.2794)
							(mid -0.239121 -0.264521)
							(end -0.254 -0.2286)
						)
						(arc
							(start -0.254 0.2286)
							(mid -0.239121 0.264521)
							(end -0.2032 0.2794)
						)
						(arc
							(start 0.2032 0.2794)
							(mid 0.239121 0.264521)
							(end 0.254 0.2286)
						)
						(arc
							(start 0.254 -0.2286)
							(mid 0.239121 -0.264521)
							(end 0.2032 -0.2794)
						)
					)
					(width 0)
					(fill yes)
				)
			)
		)
	)
	(footprint ""
		(layer "F.Cu")
		(at 55.753 -44.577)
		(property "Reference" "R53"
			(at 0 0 0)
			(layer "F.SilkS")
			(hide yes)
			(effects
				(font
					(size 1.27 1.27)
				)
			)
		)
		(property "Value" "10KR2F-2-GP"
			(at 0.064008 -3.993896 0)
			(unlocked yes)
			(layer "F.Fab")
			(hide yes)
			(effects
				(font
					(size 1.016 1.016)
					(thickness 0.1524)
				)
			)
		)
		(property "Device Type" "R402H16"
			(at 0.064008 -5.517896 0)
			(unlocked yes)
			(layer "F.Fab")
			(hide yes)
			(effects
				(font
					(size 1.016 1.016)
					(thickness 0.1524)
				)
			)
		)
		(duplicate_pad_numbers_are_jumpers no)
		(fp_rect
			(start -0.381 0.8382)
			(end 0.381 -0.8382)
			(stroke
				(width 0)
				(type default)
			)
			(fill no)
			(layer "F.CrtYd")
		)
		(fp_rect
			(start -0.381 0.8382)
			(end 0.381 -0.8382)
			(stroke
				(width 0)
				(type default)
			)
			(fill no)
			(layer "F.Fab")
		)
		(pad "1" smd custom
			(at 0 -0.4318)
			(size 0.127 0.127)
			(layers "F.Cu" "F.Mask" "F.Paste")
			(net "P12V")
			(options
				(clearance outline)
				(anchor circle)
			)
			(primitives
				(gr_poly
					(pts
						(arc
							(start -0.2032 -0.2794)
							(mid -0.239121 -0.264521)
							(end -0.254 -0.2286)
						)
						(arc
							(start -0.254 0.2286)
							(mid -0.239121 0.264521)
							(end -0.2032 0.2794)
						)
						(arc
							(start 0.2032 0.2794)
							(mid 0.239121 0.264521)
							(end 0.254 0.2286)
						)
						(arc
							(start 0.254 -0.2286)
							(mid 0.239121 -0.264521)
							(end 0.2032 -0.2794)
						)
					)
					(width 0)
					(fill yes)
				)
			)
		)
		(pad "2" smd custom
			(at 0 0.4318)
			(size 0.127 0.127)
			(layers "F.Cu" "F.Mask" "F.Paste")
			(net "SW_P3V3_EN_LV_D")
			(options
				(clearance outline)
				(anchor circle)
			)
			(primitives
				(gr_poly
					(pts
						(arc
							(start -0.2032 -0.2794)
							(mid -0.239121 -0.264521)
							(end -0.254 -0.2286)
						)
						(arc
							(start -0.254 0.2286)
							(mid -0.239121 0.264521)
							(end -0.2032 0.2794)
						)
						(arc
							(start 0.2032 0.2794)
							(mid 0.239121 0.264521)
							(end 0.254 0.2286)
						)
						(arc
							(start 0.254 -0.2286)
							(mid 0.239121 -0.264521)
							(end 0.2032 -0.2794)
						)
					)
					(width 0)
					(fill yes)
				)
			)
		)
	)
	(footprint ""
		(layer "F.Cu")
		(at 31.877 -34.2392 90)
		(property "Reference" "R270"
			(at 0 0 90)
			(layer "F.SilkS")
			(hide yes)
			(effects
				(font
					(size 1.27 1.27)
				)
			)
		)
		(property "Value" "51R2F-2-GP"
			(at 0.064008 -3.993896 90)
			(unlocked yes)
			(layer "F.Fab")
			(hide yes)
			(effects
				(font
					(size 1.016 1.016)
					(thickness 0.1524)
				)
			)
		)
		(property "Device Type" "R402H16"
			(at 0.064008 -5.517896 90)
			(unlocked yes)
			(layer "F.Fab")
			(hide yes)
			(effects
				(font
					(size 1.016 1.016)
					(thickness 0.1524)
				)
			)
		)
		(duplicate_pad_numbers_are_jumpers no)
		(fp_rect
			(start -0.381 0.8382)
			(end 0.381 -0.8382)
			(stroke
				(width 0)
				(type default)
			)
			(fill no)
			(layer "F.CrtYd")
		)
		(fp_rect
			(start -0.381 0.8382)
			(end 0.381 -0.8382)
			(stroke
				(width 0)
				(type default)
			)
			(fill no)
			(layer "F.Fab")
		)
		(pad "1" smd custom
			(at 0 -0.4318 90)
			(size 0.127 0.127)
			(layers "F.Cu" "F.Mask" "F.Paste")
			(net "P1V0_STBY")
			(options
				(clearance outline)
				(anchor circle)
			)
			(primitives
				(gr_poly
					(pts
						(arc
							(start -0.2032 -0.2794)
							(mid -0.239121 -0.264521)
							(end -0.254 -0.2286)
						)
						(arc
							(start -0.254 0.2286)
							(mid -0.239121 0.264521)
							(end -0.2032 0.2794)
						)
						(arc
							(start 0.2032 0.2794)
							(mid 0.239121 0.264521)
							(end 0.254 0.2286)
						)
						(arc
							(start 0.254 -0.2286)
							(mid 0.239121 -0.264521)
							(end 0.2032 -0.2794)
						)
					)
					(width 0)
					(fill yes)
				)
			)
		)
		(pad "2" smd custom
			(at 0 0.4318 90)
			(size 0.127 0.127)
			(layers "F.Cu" "F.Mask" "F.Paste")
			(net "XDP_SOC_CPU_TDO")
			(options
				(clearance outline)
				(anchor circle)
			)
			(primitives
				(gr_poly
					(pts
						(arc
							(start -0.2032 -0.2794)
							(mid -0.239121 -0.264521)
							(end -0.254 -0.2286)
						)
						(arc
							(start -0.254 0.2286)
							(mid -0.239121 0.264521)
							(end -0.2032 0.2794)
						)
						(arc
							(start 0.2032 0.2794)
							(mid 0.239121 0.264521)
							(end 0.254 0.2286)
						)
						(arc
							(start 0.254 -0.2286)
							(mid 0.239121 -0.264521)
							(end 0.2032 -0.2794)
						)
					)
					(width 0)
					(fill yes)
				)
			)
		)
	)
	(footprint ""
		(layer "F.Cu")
		(at 167.132 -41.656)
		(property "Reference" "OSC1"
			(at 0 0 0)
			(layer "F.SilkS")
			(hide yes)
			(effects
				(font
					(size 1.27 1.27)
				)
			)
		)
		(property "Value" "OSC-5MHZ-GP"
			(at 0 -4.182618 0)
			(unlocked yes)
			(layer "F.Fab")
			(hide yes)
			(effects
				(font
					(size 1.016 1.016)
					(thickness 0.1524)
				)
			)
		)
		(property "Device Type" "OSC-3225-4P-3H48"
			(at 0 -5.706618 0)
			(unlocked yes)
			(layer "F.Fab")
			(hide yes)
			(effects
				(font
					(size 1.016 1.016)
					(thickness 0.1524)
				)
			)
		)
		(duplicate_pad_numbers_are_jumpers no)
		(fp_poly
			(pts
				(xy -2.2987 1.2192) (xy -2.2987 0.3556) (xy -1.8669 0.7874)
			)
			(stroke
				(width 0)
				(type default)
			)
			(fill yes)
			(layer "F.SilkS")
		)
		(fp_rect
			(start -1.8669 1.4986)
			(end 1.8669 -1.4986)
			(stroke
				(width 0)
				(type default)
			)
			(fill no)
			(layer "F.CrtYd")
		)
		(fp_rect
			(start -1.8669 1.4986)
			(end 1.8669 -1.4986)
			(stroke
				(width 0)
				(type default)
			)
			(fill no)
			(layer "F.Fab")
		)
		(pad "1" smd rect
			(at -1.107948 0.824992)
			(size 1.27 0.9144)
			(layers "F.Cu" "F.Mask" "F.Paste")
			(net "OSC_5M_EN")
		)
		(pad "2" smd rect
			(at 1.107948 0.824992)
			(size 1.27 0.9144)
			(layers "F.Cu" "F.Mask" "F.Paste")
			(net "GND")
		)
		(pad "3" smd rect
			(at 1.107948 -0.824992)
			(size 1.27 0.9144)
			(layers "F.Cu" "F.Mask" "F.Paste")
			(net "OSC_5M_CLK_R")
		)
		(pad "4" smd rect
			(at -1.107948 -0.824992)
			(size 1.27 0.9144)
			(layers "F.Cu" "F.Mask" "F.Paste")
			(net "P3V3_STBY")
		)
		(zone
			(layer "F.Cu")
			(hatch none 0.5)
			(connect_pads
				(clearance 0)
			)
			(min_thickness 0.25)
			(keepout
				(tracks not_allowed)
				(vias allowed)
				(pads allowed)
				(copperpour not_allowed)
				(footprints allowed)
			)
			(placement
				(enabled no)
				(sheetname "")
			)
			(fill
				(thermal_gap 0.5)
				(thermal_bridge_width 0.5)
				(island_removal_mode 0)
			)
			(polygon
				(pts
					(xy 166.984172 -41.613328) (xy 167.279828 -41.613328) (xy 167.279828 -41.698672) (xy 166.984172 -41.698672)
				)
			)
		)
		(zone
			(layer "F.Cu")
			(hatch none 0.5)
			(connect_pads
				(clearance 0)
			)
			(min_thickness 0.25)
			(keepout
				(tracks allowed)
				(vias not_allowed)
				(pads allowed)
				(copperpour not_allowed)
				(footprints allowed)
			)
			(placement
				(enabled no)
				(sheetname "")
			)
			(fill
				(thermal_gap 0.5)
				(thermal_bridge_width 0.5)
				(island_removal_mode 0)
			)
			(polygon
				(pts
					(xy 166.659052 -40.373808) (xy 166.659052 -41.288208) (xy 165.389052 -41.288208) (xy 165.389052 -42.023792)
					(xy 166.659052 -42.023792) (xy 166.659052 -42.938192) (xy 167.604948 -42.938192) (xy 167.604948 -42.023792)
					(xy 168.874948 -42.023792) (xy 168.874948 -41.288208) (xy 167.604948 -41.288208) (xy 167.604948 -40.373808)
				)
			)
		)
	)
	(footprint ""
		(layer "F.Cu")
		(at 63.119 -56.769)
		(property "Reference" "PC144"
			(at 0 0 0)
			(layer "F.SilkS")
			(hide yes)
			(effects
				(font
					(size 1.27 1.27)
				)
			)
		)
		(property "Value" "SC47U6D3V5MX-1-GP"
			(at -0.0762 -6.1214 0)
			(unlocked yes)
			(layer "F.Fab")
			(hide yes)
			(effects
				(font
					(size 1.016 1.016)
					(thickness 0.1524)
				)
			)
		)
		(property "Device Type" "C805H54"
			(at -0.0762 -8.1534 0)
			(unlocked yes)
			(layer "F.Fab")
			(hide yes)
			(effects
				(font
					(size 1.016 1.016)
					(thickness 0.1524)
				)
			)
		)
		(duplicate_pad_numbers_are_jumpers no)
		(fp_line
			(start 0.6096 0)
			(end -0.6096 0)
			(stroke
				(width 0.3048)
				(type default)
			)
			(layer "F.SilkS")
		)
		(fp_poly
			(pts
				(xy -0.9017 1.4351) (xy 0.9017 1.4351) (xy 0.9017 -1.4351) (xy -0.9017 -1.4351)
			)
			(stroke
				(width 0)
				(type default)
			)
			(fill no)
			(layer "F.CrtYd")
		)
		(fp_poly
			(pts
				(xy 0.9017 1.4351) (xy 0.9017 -1.4351) (xy -0.9017 -1.4351) (xy -0.9017 1.4351)
			)
			(stroke
				(width 0)
				(type default)
			)
			(fill no)
			(layer "F.Fab")
		)
		(pad "1" smd rect
			(at 0 -0.8382)
			(size 1.5494 0.9398)
			(layers "F.Cu" "F.Mask" "F.Paste")
			(net "PVCCP")
		)
		(pad "2" smd rect
			(at 0 0.8382)
			(size 1.5494 0.9398)
			(layers "F.Cu" "F.Mask" "F.Paste")
			(net "GND")
		)
	)
	(footprint ""
		(layer "F.Cu")
		(at 12.9286 -62.0776 90)
		(property "Reference" "PR41"
			(at 0 0 90)
			(layer "F.SilkS")
			(hide yes)
			(effects
				(font
					(size 1.27 1.27)
				)
			)
		)
		(property "Value" "0R2J-2-GP"
			(at 1.7907 -1.1176 90)
			(unlocked yes)
			(layer "F.Fab")
			(hide yes)
			(effects
				(font
					(size 1.016 1.016)
					(thickness 0.1524)
				)
			)
		)
		(property "Device Type" "R402H16"
			(at 1.7907 -2.6416 90)
			(unlocked yes)
			(layer "F.Fab")
			(hide yes)
			(effects
				(font
					(size 1.016 1.016)
					(thickness 0.1524)
				)
			)
		)
		(duplicate_pad_numbers_are_jumpers no)
		(fp_rect
			(start -0.381 0.8382)
			(end 0.381 -0.8382)
			(stroke
				(width 0)
				(type default)
			)
			(fill no)
			(layer "F.CrtYd")
		)
		(fp_rect
			(start -0.381 0.8382)
			(end 0.381 -0.8382)
			(stroke
				(width 0)
				(type default)
			)
			(fill no)
			(layer "F.Fab")
		)
		(pad "1" smd custom
			(at 0 -0.4318 90)
			(size 0.127 0.127)
			(layers "F.Cu" "F.Mask" "F.Paste")
			(net "TP_PVCCP_VDIO")
			(options
				(clearance outline)
				(anchor circle)
			)
			(primitives
				(gr_poly
					(pts
						(arc
							(start -0.2032 -0.2794)
							(mid -0.239121 -0.264521)
							(end -0.254 -0.2286)
						)
						(arc
							(start -0.254 0.2286)
							(mid -0.239121 0.264521)
							(end -0.2032 0.2794)
						)
						(arc
							(start 0.2032 0.2794)
							(mid 0.239121 0.264521)
							(end 0.254 0.2286)
						)
						(arc
							(start 0.254 -0.2286)
							(mid 0.239121 -0.264521)
							(end 0.2032 -0.2794)
						)
					)
					(width 0)
					(fill yes)
				)
			)
		)
		(pad "2" smd custom
			(at 0 0.4318 90)
			(size 0.127 0.127)
			(layers "F.Cu" "F.Mask" "F.Paste")
			(net "SVID_CPU_DATA")
			(options
				(clearance outline)
				(anchor circle)
			)
			(primitives
				(gr_poly
					(pts
						(arc
							(start -0.2032 -0.2794)
							(mid -0.239121 -0.264521)
							(end -0.254 -0.2286)
						)
						(arc
							(start -0.254 0.2286)
							(mid -0.239121 0.264521)
							(end -0.2032 0.2794)
						)
						(arc
							(start 0.2032 0.2794)
							(mid 0.239121 0.264521)
							(end 0.254 0.2286)
						)
						(arc
							(start 0.254 -0.2286)
							(mid 0.239121 -0.264521)
							(end 0.2032 -0.2794)
						)
					)
					(width 0)
					(fill yes)
				)
			)
		)
	)
	(footprint ""
		(layer "F.Cu")
		(at 10.668 -51.7398 90)
		(property "Reference" "C60"
			(at 0 0 90)
			(layer "F.SilkS")
			(hide yes)
			(effects
				(font
					(size 1.27 1.27)
				)
			)
		)
		(property "Value" "SCD01U16V2KX-3GP"
			(at 1.1811 -2.7051 90)
			(unlocked yes)
			(layer "F.Fab")
			(hide yes)
			(effects
				(font
					(size 1.016 1.016)
					(thickness 0.1524)
				)
			)
		)
		(property "Device Type" "C402H22"
			(at 1.1811 -4.2291 90)
			(unlocked yes)
			(layer "F.Fab")
			(hide yes)
			(effects
				(font
					(size 1.016 1.016)
					(thickness 0.1524)
				)
			)
		)
		(duplicate_pad_numbers_are_jumpers no)
		(fp_rect
			(start -0.381 0.7366)
			(end 0.381 -0.7366)
			(stroke
				(width 0)
				(type default)
			)
			(fill no)
			(layer "F.CrtYd")
		)
		(fp_rect
			(start -0.381 0.7366)
			(end 0.381 -0.7366)
			(stroke
				(width 0)
				(type default)
			)
			(fill no)
			(layer "F.Fab")
		)
		(pad "1" smd custom
			(at 0 -0.4572 90)
			(size 0.1143 0.1143)
			(layers "F.Cu" "F.Mask" "F.Paste")
			(net "SATA3_TX_DN1")
			(options
				(clearance outline)
				(anchor circle)
			)
			(primitives
				(gr_poly
					(pts
						(arc
							(start -0.254 -0.1778)
							(mid -0.239121 -0.213721)
							(end -0.2032 -0.2286)
						)
						(arc
							(start 0.2032 -0.2286)
							(mid 0.239121 -0.213721)
							(end 0.254 -0.1778)
						)
						(arc
							(start 0.254 0.1778)
							(mid 0.239121 0.213721)
							(end 0.2032 0.2286)
						)
						(arc
							(start -0.2032 0.2286)
							(mid -0.239121 0.213721)
							(end -0.254 0.1778)
						)
					)
					(width 0)
					(fill yes)
				)
			)
		)
		(pad "2" smd custom
			(at 0 0.4572 90)
			(size 0.1143 0.1143)
			(layers "F.Cu" "F.Mask" "F.Paste")
			(net "P2E_CPU_NGFF_TX_DN12")
			(options
				(clearance outline)
				(anchor circle)
			)
			(primitives
				(gr_poly
					(pts
						(arc
							(start -0.254 -0.1778)
							(mid -0.239121 -0.213721)
							(end -0.2032 -0.2286)
						)
						(arc
							(start 0.2032 -0.2286)
							(mid 0.239121 -0.213721)
							(end 0.254 -0.1778)
						)
						(arc
							(start 0.254 0.1778)
							(mid 0.239121 0.213721)
							(end 0.2032 0.2286)
						)
						(arc
							(start -0.2032 0.2286)
							(mid -0.239121 0.213721)
							(end -0.254 0.1778)
						)
					)
					(width 0)
					(fill yes)
				)
			)
		)
	)
	(footprint ""
		(layer "F.Cu")
		(at 194.691 -31.623)
		(property "Reference" "PR139"
			(at 0 0 0)
			(layer "F.SilkS")
			(hide yes)
			(effects
				(font
					(size 1.27 1.27)
				)
			)
		)
		(property "Value" "4K12R2F-GP"
			(at 1.7907 -1.1176 0)
			(unlocked yes)
			(layer "F.Fab")
			(hide yes)
			(effects
				(font
					(size 1.016 1.016)
					(thickness 0.1524)
				)
			)
		)
		(property "Device Type" "R402H16"
			(at 1.7907 -2.6416 0)
			(unlocked yes)
			(layer "F.Fab")
			(hide yes)
			(effects
				(font
					(size 1.016 1.016)
					(thickness 0.1524)
				)
			)
		)
		(duplicate_pad_numbers_are_jumpers no)
		(fp_rect
			(start -0.381 0.8382)
			(end 0.381 -0.8382)
			(stroke
				(width 0)
				(type default)
			)
			(fill no)
			(layer "F.CrtYd")
		)
		(fp_rect
			(start -0.381 0.8382)
			(end 0.381 -0.8382)
			(stroke
				(width 0)
				(type default)
			)
			(fill no)
			(layer "F.Fab")
		)
		(pad "1" smd custom
			(at 0 -0.4318)
			(size 0.127 0.127)
			(layers "F.Cu" "F.Mask" "F.Paste")
			(net "VR_PVDDR_A_PROG1")
			(options
				(clearance outline)
				(anchor circle)
			)
			(primitives
				(gr_poly
					(pts
						(arc
							(start -0.2032 -0.2794)
							(mid -0.239121 -0.264521)
							(end -0.254 -0.2286)
						)
						(arc
							(start -0.254 0.2286)
							(mid -0.239121 0.264521)
							(end -0.2032 0.2794)
						)
						(arc
							(start 0.2032 0.2794)
							(mid 0.239121 0.264521)
							(end 0.254 0.2286)
						)
						(arc
							(start 0.254 -0.2286)
							(mid 0.239121 -0.264521)
							(end 0.2032 -0.2794)
						)
					)
					(width 0)
					(fill yes)
				)
			)
		)
		(pad "2" smd custom
			(at 0 0.4318)
			(size 0.127 0.127)
			(layers "F.Cu" "F.Mask" "F.Paste")
			(net "GND")
			(options
				(clearance outline)
				(anchor circle)
			)
			(primitives
				(gr_poly
					(pts
						(arc
							(start -0.2032 -0.2794)
							(mid -0.239121 -0.264521)
							(end -0.254 -0.2286)
						)
						(arc
							(start -0.254 0.2286)
							(mid -0.239121 0.264521)
							(end -0.2032 0.2794)
						)
						(arc
							(start 0.2032 0.2794)
							(mid 0.239121 0.264521)
							(end 0.254 0.2286)
						)
						(arc
							(start 0.254 -0.2286)
							(mid 0.239121 -0.264521)
							(end 0.2032 -0.2794)
						)
					)
					(width 0)
					(fill yes)
				)
			)
		)
	)
	(footprint ""
		(layer "F.Cu")
		(at 49.3522 -34.925 180)
		(property "Reference" "R109"
			(at 0 0 180)
			(layer "F.SilkS")
			(hide yes)
			(effects
				(font
					(size 1.27 1.27)
				)
			)
		)
		(property "Value" "33R2F-3-GP"
			(at 0.064008 -3.993896 180)
			(unlocked yes)
			(layer "F.Fab")
			(hide yes)
			(effects
				(font
					(size 1.016 1.016)
					(thickness 0.1524)
				)
			)
		)
		(property "Device Type" "R402H16"
			(at 0.064008 -5.517896 180)
			(unlocked yes)
			(layer "F.Fab")
			(hide yes)
			(effects
				(font
					(size 1.016 1.016)
					(thickness 0.1524)
				)
			)
		)
		(duplicate_pad_numbers_are_jumpers no)
		(fp_rect
			(start -0.381 0.8382)
			(end 0.381 -0.8382)
			(stroke
				(width 0)
				(type default)
			)
			(fill no)
			(layer "F.CrtYd")
		)
		(fp_rect
			(start -0.381 0.8382)
			(end 0.381 -0.8382)
			(stroke
				(width 0)
				(type default)
			)
			(fill no)
			(layer "F.Fab")
		)
		(pad "1" smd custom
			(at 0 -0.4318 180)
			(size 0.127 0.127)
			(layers "F.Cu" "F.Mask" "F.Paste")
			(net "SPI_SCLK_R_1")
			(options
				(clearance outline)
				(anchor circle)
			)
			(primitives
				(gr_poly
					(pts
						(arc
							(start -0.2032 -0.2794)
							(mid -0.239121 -0.264521)
							(end -0.254 -0.2286)
						)
						(arc
							(start -0.254 0.2286)
							(mid -0.239121 0.264521)
							(end -0.2032 0.2794)
						)
						(arc
							(start 0.2032 0.2794)
							(mid 0.239121 0.264521)
							(end 0.254 0.2286)
						)
						(arc
							(start 0.254 -0.2286)
							(mid 0.239121 -0.264521)
							(end 0.2032 -0.2794)
						)
					)
					(width 0)
					(fill yes)
				)
			)
		)
		(pad "2" smd custom
			(at 0 0.4318 180)
			(size 0.127 0.127)
			(layers "F.Cu" "F.Mask" "F.Paste")
			(net "SPI_CPU_SCLK")
			(options
				(clearance outline)
				(anchor circle)
			)
			(primitives
				(gr_poly
					(pts
						(arc
							(start -0.2032 -0.2794)
							(mid -0.239121 -0.264521)
							(end -0.254 -0.2286)
						)
						(arc
							(start -0.254 0.2286)
							(mid -0.239121 0.264521)
							(end -0.2032 0.2794)
						)
						(arc
							(start 0.2032 0.2794)
							(mid 0.239121 0.264521)
							(end 0.254 0.2286)
						)
						(arc
							(start 0.254 -0.2286)
							(mid 0.239121 -0.264521)
							(end 0.2032 -0.2794)
						)
					)
					(width 0)
					(fill yes)
				)
			)
		)
	)
	(footprint ""
		(layer "F.Cu")
		(at 20.066 -63.4492 90)
		(property "Reference" "PC15"
			(at 0 0 90)
			(layer "F.SilkS")
			(hide yes)
			(effects
				(font
					(size 1.27 1.27)
				)
			)
		)
		(property "Value" "SCD068U16V2KX-GP"
			(at 1.8923 -1.2065 90)
			(unlocked yes)
			(layer "F.Fab")
			(hide yes)
			(effects
				(font
					(size 1.016 1.016)
					(thickness 0.1524)
				)
			)
		)
		(property "Device Type" "C402H22"
			(at 1.8923 -2.7305 90)
			(unlocked yes)
			(layer "F.Fab")
			(hide yes)
			(effects
				(font
					(size 1.016 1.016)
					(thickness 0.1524)
				)
			)
		)
		(duplicate_pad_numbers_are_jumpers no)
		(fp_rect
			(start -0.381 0.7366)
			(end 0.381 -0.7366)
			(stroke
				(width 0)
				(type default)
			)
			(fill no)
			(layer "F.CrtYd")
		)
		(fp_rect
			(start -0.381 0.7366)
			(end 0.381 -0.7366)
			(stroke
				(width 0)
				(type default)
			)
			(fill no)
			(layer "F.Fab")
		)
		(pad "1" smd custom
			(at 0 -0.4572 90)
			(size 0.1143 0.1143)
			(layers "F.Cu" "F.Mask" "F.Paste")
			(net "VR_PVNN_VSEN")
			(options
				(clearance outline)
				(anchor circle)
			)
			(primitives
				(gr_poly
					(pts
						(arc
							(start -0.254 -0.1778)
							(mid -0.239121 -0.213721)
							(end -0.2032 -0.2286)
						)
						(arc
							(start 0.2032 -0.2286)
							(mid 0.239121 -0.213721)
							(end 0.254 -0.1778)
						)
						(arc
							(start 0.254 0.1778)
							(mid 0.239121 0.213721)
							(end 0.2032 0.2286)
						)
						(arc
							(start -0.2032 0.2286)
							(mid -0.239121 0.213721)
							(end -0.254 0.1778)
						)
					)
					(width 0)
					(fill yes)
				)
			)
		)
		(pad "2" smd custom
			(at 0 0.4572 90)
			(size 0.1143 0.1143)
			(layers "F.Cu" "F.Mask" "F.Paste")
			(net "VR_PVNN_RTN")
			(options
				(clearance outline)
				(anchor circle)
			)
			(primitives
				(gr_poly
					(pts
						(arc
							(start -0.254 -0.1778)
							(mid -0.239121 -0.213721)
							(end -0.2032 -0.2286)
						)
						(arc
							(start 0.2032 -0.2286)
							(mid 0.239121 -0.213721)
							(end 0.254 -0.1778)
						)
						(arc
							(start 0.254 0.1778)
							(mid 0.239121 0.213721)
							(end 0.2032 0.2286)
						)
						(arc
							(start -0.2032 0.2286)
							(mid -0.239121 0.213721)
							(end -0.254 0.1778)
						)
					)
					(width 0)
					(fill yes)
				)
			)
		)
	)
	(footprint ""
		(layer "F.Cu")
		(at 36.7538 -54.9656)
		(property "Reference" "PC18"
			(at 0 0 0)
			(layer "F.SilkS")
			(hide yes)
			(effects
				(font
					(size 1.27 1.27)
				)
			)
		)
		(property "Value" "SC10U25V5KX-GP"
			(at 0 -4.9022 0)
			(unlocked yes)
			(layer "F.Fab")
			(hide yes)
			(effects
				(font
					(size 1.016 1.016)
					(thickness 0.1524)
				)
			)
		)
		(property "Device Type" "C805H56"
			(at 0 -6.8072 0)
			(unlocked yes)
			(layer "F.Fab")
			(hide yes)
			(effects
				(font
					(size 1.016 1.016)
					(thickness 0.1524)
				)
			)
		)
		(duplicate_pad_numbers_are_jumpers no)
		(fp_line
			(start 0.6096 0)
			(end -0.6096 0)
			(stroke
				(width 0.3048)
				(type default)
			)
			(layer "F.SilkS")
		)
		(fp_poly
			(pts
				(xy -0.9017 1.4351) (xy 0.9017 1.4351) (xy 0.9017 -1.4351) (xy -0.9017 -1.4351)
			)
			(stroke
				(width 0)
				(type default)
			)
			(fill no)
			(layer "F.CrtYd")
		)
		(fp_poly
			(pts
				(xy 0.9017 1.4351) (xy 0.9017 -1.4351) (xy -0.9017 -1.4351) (xy -0.9017 1.4351)
			)
			(stroke
				(width 0)
				(type default)
			)
			(fill no)
			(layer "F.Fab")
		)
		(pad "1" smd rect
			(at 0 -0.8382)
			(size 1.5494 0.9398)
			(layers "F.Cu" "F.Mask" "F.Paste")
			(net "VR_FET_SW_P12V_PVCCP_PVNN")
		)
		(pad "2" smd rect
			(at 0 0.8382)
			(size 1.5494 0.9398)
			(layers "F.Cu" "F.Mask" "F.Paste")
			(net "GND")
		)
	)
	(footprint ""
		(layer "F.Cu")
		(at 167.894 -33.782 -90)
		(property "Reference" "PC83"
			(at 0 0 270)
			(layer "F.SilkS")
			(hide yes)
			(effects
				(font
					(size 1.27 1.27)
				)
			)
		)
		(property "Value" "SC22U6D3V5MX-2GP"
			(at -0.0762 -6.1214 270)
			(unlocked yes)
			(layer "F.Fab")
			(hide yes)
			(effects
				(font
					(size 1.016 1.016)
					(thickness 0.1524)
				)
			)
		)
		(property "Device Type" "C805H58"
			(at -0.0762 -8.1534 270)
			(unlocked yes)
			(layer "F.Fab")
			(hide yes)
			(effects
				(font
					(size 1.016 1.016)
					(thickness 0.1524)
				)
			)
		)
		(duplicate_pad_numbers_are_jumpers no)
		(fp_line
			(start 0.6096 0)
			(end -0.6096 0)
			(stroke
				(width 0.3048)
				(type default)
			)
			(layer "F.SilkS")
		)
		(fp_poly
			(pts
				(xy -0.9017 1.4351) (xy 0.9017 1.4351) (xy 0.9017 -1.4351) (xy -0.9017 -1.4351)
			)
			(stroke
				(width 0)
				(type default)
			)
			(fill no)
			(layer "F.CrtYd")
		)
		(fp_poly
			(pts
				(xy 0.9017 1.4351) (xy 0.9017 -1.4351) (xy -0.9017 -1.4351) (xy -0.9017 1.4351)
			)
			(stroke
				(width 0)
				(type default)
			)
			(fill no)
			(layer "F.Fab")
		)
		(pad "1" smd rect
			(at 0 -0.8382 270)
			(size 1.5494 0.9398)
			(layers "F.Cu" "F.Mask" "F.Paste")
			(net "P1V2_STBY_LDO_OUT1")
		)
		(pad "2" smd rect
			(at 0 0.8382 270)
			(size 1.5494 0.9398)
			(layers "F.Cu" "F.Mask" "F.Paste")
			(net "GND")
		)
	)
	(footprint ""
		(layer "F.Cu")
		(at 183.642 -46.101 180)
		(property "Reference" "R217"
			(at 0 0 180)
			(layer "F.SilkS")
			(hide yes)
			(effects
				(font
					(size 1.27 1.27)
				)
			)
		)
		(property "Value" "0R2J-2-GP"
			(at 0.064008 -3.993896 180)
			(unlocked yes)
			(layer "F.Fab")
			(hide yes)
			(effects
				(font
					(size 1.016 1.016)
					(thickness 0.1524)
				)
			)
		)
		(property "Device Type" "R402H16"
			(at 0.064008 -5.517896 180)
			(unlocked yes)
			(layer "F.Fab")
			(hide yes)
			(effects
				(font
					(size 1.016 1.016)
					(thickness 0.1524)
				)
			)
		)
		(duplicate_pad_numbers_are_jumpers no)
		(fp_rect
			(start -0.381 0.8382)
			(end 0.381 -0.8382)
			(stroke
				(width 0)
				(type default)
			)
			(fill no)
			(layer "F.CrtYd")
		)
		(fp_rect
			(start -0.381 0.8382)
			(end 0.381 -0.8382)
			(stroke
				(width 0)
				(type default)
			)
			(fill no)
			(layer "F.Fab")
		)
		(pad "1" smd custom
			(at 0 -0.4318 180)
			(size 0.127 0.127)
			(layers "F.Cu" "F.Mask" "F.Paste")
			(net "SMB_HOST_LV_CLK")
			(options
				(clearance outline)
				(anchor circle)
			)
			(primitives
				(gr_poly
					(pts
						(arc
							(start -0.2032 -0.2794)
							(mid -0.239121 -0.264521)
							(end -0.254 -0.2286)
						)
						(arc
							(start -0.254 0.2286)
							(mid -0.239121 0.264521)
							(end -0.2032 0.2794)
						)
						(arc
							(start 0.2032 0.2794)
							(mid 0.239121 0.264521)
							(end 0.254 0.2286)
						)
						(arc
							(start 0.254 -0.2286)
							(mid 0.239121 -0.264521)
							(end 0.2032 -0.2794)
						)
					)
					(width 0)
					(fill yes)
				)
			)
		)
		(pad "2" smd custom
			(at 0 0.4318 180)
			(size 0.127 0.127)
			(layers "F.Cu" "F.Mask" "F.Paste")
			(net "SMB_DPOT_CLK")
			(options
				(clearance outline)
				(anchor circle)
			)
			(primitives
				(gr_poly
					(pts
						(arc
							(start -0.2032 -0.2794)
							(mid -0.239121 -0.264521)
							(end -0.254 -0.2286)
						)
						(arc
							(start -0.254 0.2286)
							(mid -0.239121 0.264521)
							(end -0.2032 0.2794)
						)
						(arc
							(start 0.2032 0.2794)
							(mid 0.239121 0.264521)
							(end 0.254 0.2286)
						)
						(arc
							(start 0.254 -0.2286)
							(mid 0.239121 -0.264521)
							(end 0.2032 -0.2794)
						)
					)
					(width 0)
					(fill yes)
				)
			)
		)
	)
	(footprint ""
		(layer "F.Cu")
		(at 167.64 -30.2514 -90)
		(property "Reference" "PR132"
			(at 0 0 270)
			(layer "F.SilkS")
			(hide yes)
			(effects
				(font
					(size 1.27 1.27)
				)
			)
		)
		(property "Value" "0R3J-6-GP"
			(at -0.0254 -2.5146 270)
			(unlocked yes)
			(layer "F.Fab")
			(hide yes)
			(effects
				(font
					(size 1.016 1.016)
					(thickness 0.1524)
				)
			)
		)
		(property "Device Type" "R603H22"
			(at -0.0254 -4.0386 270)
			(unlocked yes)
			(layer "F.Fab")
			(hide yes)
			(effects
				(font
					(size 1.016 1.016)
					(thickness 0.1524)
				)
			)
		)
		(duplicate_pad_numbers_are_jumpers no)
		(fp_line
			(start -0.2032 0)
			(end -0.4191 0)
			(stroke
				(width 0.2032)
				(type default)
			)
			(layer "F.SilkS")
		)
		(fp_line
			(start 0.4318 0)
			(end 0.2032 0)
			(stroke
				(width 0.2032)
				(type default)
			)
			(layer "F.SilkS")
		)
		(fp_rect
			(start -0.635 1.1811)
			(end 0.635 -1.1811)
			(stroke
				(width 0)
				(type default)
			)
			(fill no)
			(layer "F.CrtYd")
		)
		(fp_rect
			(start -0.635 1.1811)
			(end 0.635 -1.1811)
			(stroke
				(width 0)
				(type default)
			)
			(fill no)
			(layer "F.Fab")
		)
		(pad "1" smd custom
			(at 0 -0.6604 270)
			(size 0.19685 0.19685)
			(layers "F.Cu" "F.Mask" "F.Paste")
			(net "P1V8_STBY_LDO_IN1")
			(options
				(clearance outline)
				(anchor circle)
			)
			(primitives
				(gr_poly
					(pts
						(arc
							(start 0.508 -0.2921)
							(mid 0.478242 -0.363942)
							(end 0.4064 -0.3937)
						)
						(arc
							(start -0.4064 -0.3937)
							(mid -0.478242 -0.363942)
							(end -0.508 -0.2921)
						)
						(arc
							(start -0.508 0.2921)
							(mid -0.478242 0.363942)
							(end -0.4064 0.3937)
						)
						(arc
							(start 0.4064 0.3937)
							(mid 0.478242 0.363942)
							(end 0.508 0.2921)
						)
					)
					(width 0)
					(fill yes)
				)
			)
		)
		(pad "2" smd custom
			(at 0 0.6604 270)
			(size 0.19685 0.19685)
			(layers "F.Cu" "F.Mask" "F.Paste")
			(net "P3V3_STBY")
			(options
				(clearance outline)
				(anchor circle)
			)
			(primitives
				(gr_poly
					(pts
						(arc
							(start 0.508 -0.2921)
							(mid 0.478242 -0.363942)
							(end 0.4064 -0.3937)
						)
						(arc
							(start -0.4064 -0.3937)
							(mid -0.478242 -0.363942)
							(end -0.508 -0.2921)
						)
						(arc
							(start -0.508 0.2921)
							(mid -0.478242 0.363942)
							(end -0.4064 0.3937)
						)
						(arc
							(start 0.4064 0.3937)
							(mid 0.478242 0.363942)
							(end 0.508 0.2921)
						)
					)
					(width 0)
					(fill yes)
				)
			)
		)
	)
	(footprint ""
		(layer "F.Cu")
		(at 130.302 -45.466 -90)
		(property "Reference" "C11"
			(at 0 0 270)
			(layer "F.SilkS")
			(hide yes)
			(effects
				(font
					(size 1.27 1.27)
				)
			)
		)
		(property "Value" "SCD1U10V2KX-5GP"
			(at 1.1811 -2.7051 270)
			(unlocked yes)
			(layer "F.Fab")
			(hide yes)
			(effects
				(font
					(size 1.016 1.016)
					(thickness 0.1524)
				)
			)
		)
		(property "Device Type" "C402H22"
			(at 1.1811 -4.2291 270)
			(unlocked yes)
			(layer "F.Fab")
			(hide yes)
			(effects
				(font
					(size 1.016 1.016)
					(thickness 0.1524)
				)
			)
		)
		(duplicate_pad_numbers_are_jumpers no)
		(fp_rect
			(start -0.381 0.7366)
			(end 0.381 -0.7366)
			(stroke
				(width 0)
				(type default)
			)
			(fill no)
			(layer "F.CrtYd")
		)
		(fp_rect
			(start -0.381 0.7366)
			(end 0.381 -0.7366)
			(stroke
				(width 0)
				(type default)
			)
			(fill no)
			(layer "F.Fab")
		)
		(pad "1" smd custom
			(at 0 -0.4572 270)
			(size 0.1143 0.1143)
			(layers "F.Cu" "F.Mask" "F.Paste")
			(net "P1V2_FPGA_A")
			(options
				(clearance outline)
				(anchor circle)
			)
			(primitives
				(gr_poly
					(pts
						(arc
							(start -0.254 -0.1778)
							(mid -0.239121 -0.213721)
							(end -0.2032 -0.2286)
						)
						(arc
							(start 0.2032 -0.2286)
							(mid 0.239121 -0.213721)
							(end 0.254 -0.1778)
						)
						(arc
							(start 0.254 0.1778)
							(mid 0.239121 0.213721)
							(end 0.2032 0.2286)
						)
						(arc
							(start -0.2032 0.2286)
							(mid -0.239121 0.213721)
							(end -0.254 0.1778)
						)
					)
					(width 0)
					(fill yes)
				)
			)
		)
		(pad "2" smd custom
			(at 0 0.4572 270)
			(size 0.1143 0.1143)
			(layers "F.Cu" "F.Mask" "F.Paste")
			(net "GND")
			(options
				(clearance outline)
				(anchor circle)
			)
			(primitives
				(gr_poly
					(pts
						(arc
							(start -0.254 -0.1778)
							(mid -0.239121 -0.213721)
							(end -0.2032 -0.2286)
						)
						(arc
							(start 0.2032 -0.2286)
							(mid 0.239121 -0.213721)
							(end 0.254 -0.1778)
						)
						(arc
							(start 0.254 0.1778)
							(mid 0.239121 0.213721)
							(end 0.2032 0.2286)
						)
						(arc
							(start -0.2032 0.2286)
							(mid -0.239121 0.213721)
							(end -0.254 0.1778)
						)
					)
					(width 0)
					(fill yes)
				)
			)
		)
	)
	(footprint ""
		(layer "F.Cu")
		(at 153.7462 -59.182)
		(property "Reference" "C97"
			(at 0 0 0)
			(layer "F.SilkS")
			(hide yes)
			(effects
				(font
					(size 1.27 1.27)
				)
			)
		)
		(property "Value" "SC10U6D3V3MX-GP"
			(at 0 -2.8194 0)
			(unlocked yes)
			(layer "F.Fab")
			(hide yes)
			(effects
				(font
					(size 1.016 1.016)
					(thickness 0.1524)
				)
			)
		)
		(property "Device Type" "C603H38"
			(at 0 -4.3434 0)
			(unlocked yes)
			(layer "F.Fab")
			(hide yes)
			(effects
				(font
					(size 1.016 1.016)
					(thickness 0.1524)
				)
			)
		)
		(duplicate_pad_numbers_are_jumpers no)
		(fp_line
			(start -0.4064 0)
			(end 0.4064 0)
			(stroke
				(width 0.2286)
				(type default)
			)
			(layer "F.SilkS")
		)
		(fp_rect
			(start -0.635 1.1811)
			(end 0.635 -1.1811)
			(stroke
				(width 0)
				(type default)
			)
			(fill no)
			(layer "F.CrtYd")
		)
		(fp_rect
			(start -0.635 1.1811)
			(end 0.635 -1.1811)
			(stroke
				(width 0)
				(type default)
			)
			(fill no)
			(layer "F.Fab")
		)
		(pad "1" smd custom
			(at 0 -0.6604)
			(size 0.19685 0.19685)
			(layers "F.Cu" "F.Mask" "F.Paste")
			(net "PV_VDDR")
			(options
				(clearance outline)
				(anchor circle)
			)
			(primitives
				(gr_poly
					(pts
						(arc
							(start 0.508 -0.2921)
							(mid 0.478242 -0.363942)
							(end 0.4064 -0.3937)
						)
						(arc
							(start -0.4064 -0.3937)
							(mid -0.478242 -0.363942)
							(end -0.508 -0.2921)
						)
						(arc
							(start -0.508 0.2921)
							(mid -0.478242 0.363942)
							(end -0.4064 0.3937)
						)
						(arc
							(start 0.4064 0.3937)
							(mid 0.478242 0.363942)
							(end 0.508 0.2921)
						)
					)
					(width 0)
					(fill yes)
				)
			)
		)
		(pad "2" smd custom
			(at 0 0.6604)
			(size 0.19685 0.19685)
			(layers "F.Cu" "F.Mask" "F.Paste")
			(net "GND")
			(options
				(clearance outline)
				(anchor circle)
			)
			(primitives
				(gr_poly
					(pts
						(arc
							(start 0.508 -0.2921)
							(mid 0.478242 -0.363942)
							(end 0.4064 -0.3937)
						)
						(arc
							(start -0.4064 -0.3937)
							(mid -0.478242 -0.363942)
							(end -0.508 -0.2921)
						)
						(arc
							(start -0.508 0.2921)
							(mid -0.478242 0.363942)
							(end -0.4064 0.3937)
						)
						(arc
							(start 0.4064 0.3937)
							(mid 0.478242 0.363942)
							(end 0.508 0.2921)
						)
					)
					(width 0)
					(fill yes)
				)
			)
		)
	)
	(footprint ""
		(layer "F.Cu")
		(at 74.422 -49.276 180)
		(property "Reference" "R45"
			(at 0 0 180)
			(layer "F.SilkS")
			(hide yes)
			(effects
				(font
					(size 1.27 1.27)
				)
			)
		)
		(property "Value" "1KR2F-3-GP"
			(at 0.064008 -3.993896 180)
			(unlocked yes)
			(layer "F.Fab")
			(hide yes)
			(effects
				(font
					(size 1.016 1.016)
					(thickness 0.1524)
				)
			)
		)
		(property "Device Type" "R402H16"
			(at 0.064008 -5.517896 180)
			(unlocked yes)
			(layer "F.Fab")
			(hide yes)
			(effects
				(font
					(size 1.016 1.016)
					(thickness 0.1524)
				)
			)
		)
		(duplicate_pad_numbers_are_jumpers no)
		(fp_rect
			(start -0.381 0.8382)
			(end 0.381 -0.8382)
			(stroke
				(width 0)
				(type default)
			)
			(fill no)
			(layer "F.CrtYd")
		)
		(fp_rect
			(start -0.381 0.8382)
			(end 0.381 -0.8382)
			(stroke
				(width 0)
				(type default)
			)
			(fill no)
			(layer "F.Fab")
		)
		(pad "1" smd custom
			(at 0 -0.4318 180)
			(size 0.127 0.127)
			(layers "F.Cu" "F.Mask" "F.Paste")
			(net "BD_ID_0")
			(options
				(clearance outline)
				(anchor circle)
			)
			(primitives
				(gr_poly
					(pts
						(arc
							(start -0.2032 -0.2794)
							(mid -0.239121 -0.264521)
							(end -0.254 -0.2286)
						)
						(arc
							(start -0.254 0.2286)
							(mid -0.239121 0.264521)
							(end -0.2032 0.2794)
						)
						(arc
							(start 0.2032 0.2794)
							(mid 0.239121 0.264521)
							(end 0.254 0.2286)
						)
						(arc
							(start 0.254 -0.2286)
							(mid 0.239121 -0.264521)
							(end 0.2032 -0.2794)
						)
					)
					(width 0)
					(fill yes)
				)
			)
		)
		(pad "2" smd custom
			(at 0 0.4318 180)
			(size 0.127 0.127)
			(layers "F.Cu" "F.Mask" "F.Paste")
			(net "GND")
			(options
				(clearance outline)
				(anchor circle)
			)
			(primitives
				(gr_poly
					(pts
						(arc
							(start -0.2032 -0.2794)
							(mid -0.239121 -0.264521)
							(end -0.254 -0.2286)
						)
						(arc
							(start -0.254 0.2286)
							(mid -0.239121 0.264521)
							(end -0.2032 0.2794)
						)
						(arc
							(start 0.2032 0.2794)
							(mid 0.239121 0.264521)
							(end 0.254 0.2286)
						)
						(arc
							(start 0.254 -0.2286)
							(mid 0.239121 -0.264521)
							(end 0.2032 -0.2794)
						)
					)
					(width 0)
					(fill yes)
				)
			)
		)
	)
	(footprint ""
		(layer "F.Cu")
		(at 5.5626 -50.546)
		(property "Reference" "R5"
			(at 0 0 0)
			(layer "F.SilkS")
			(hide yes)
			(effects
				(font
					(size 1.27 1.27)
				)
			)
		)
		(property "Value" "4K7R2F-GP"
			(at 0.064008 -3.993896 0)
			(unlocked yes)
			(layer "F.Fab")
			(hide yes)
			(effects
				(font
					(size 1.016 1.016)
					(thickness 0.1524)
				)
			)
		)
		(property "Device Type" "R402H16"
			(at 0.064008 -5.517896 0)
			(unlocked yes)
			(layer "F.Fab")
			(hide yes)
			(effects
				(font
					(size 1.016 1.016)
					(thickness 0.1524)
				)
			)
		)
		(duplicate_pad_numbers_are_jumpers no)
		(fp_rect
			(start -0.381 0.8382)
			(end 0.381 -0.8382)
			(stroke
				(width 0)
				(type default)
			)
			(fill no)
			(layer "F.CrtYd")
		)
		(fp_rect
			(start -0.381 0.8382)
			(end 0.381 -0.8382)
			(stroke
				(width 0)
				(type default)
			)
			(fill no)
			(layer "F.Fab")
		)
		(pad "1" smd custom
			(at 0 -0.4318)
			(size 0.127 0.127)
			(layers "F.Cu" "F.Mask" "F.Paste")
			(net "P3V3_STBY")
			(options
				(clearance outline)
				(anchor circle)
			)
			(primitives
				(gr_poly
					(pts
						(arc
							(start -0.2032 -0.2794)
							(mid -0.239121 -0.264521)
							(end -0.254 -0.2286)
						)
						(arc
							(start -0.254 0.2286)
							(mid -0.239121 0.264521)
							(end -0.2032 0.2794)
						)
						(arc
							(start 0.2032 0.2794)
							(mid 0.239121 0.264521)
							(end 0.254 0.2286)
						)
						(arc
							(start 0.254 -0.2286)
							(mid 0.239121 -0.264521)
							(end 0.2032 -0.2794)
						)
					)
					(width 0)
					(fill yes)
				)
			)
		)
		(pad "2" smd custom
			(at 0 0.4318)
			(size 0.127 0.127)
			(layers "F.Cu" "F.Mask" "F.Paste")
			(net "TEMP_1_A0")
			(options
				(clearance outline)
				(anchor circle)
			)
			(primitives
				(gr_poly
					(pts
						(arc
							(start -0.2032 -0.2794)
							(mid -0.239121 -0.264521)
							(end -0.254 -0.2286)
						)
						(arc
							(start -0.254 0.2286)
							(mid -0.239121 0.264521)
							(end -0.2032 0.2794)
						)
						(arc
							(start 0.2032 0.2794)
							(mid 0.239121 0.264521)
							(end 0.254 0.2286)
						)
						(arc
							(start 0.254 -0.2286)
							(mid 0.239121 -0.264521)
							(end 0.2032 -0.2794)
						)
					)
					(width 0)
					(fill yes)
				)
			)
		)
	)
	(footprint ""
		(layer "F.Cu")
		(at 140.589 -51.3588 -90)
		(property "Reference" "R87"
			(at 0 0 270)
			(layer "F.SilkS")
			(hide yes)
			(effects
				(font
					(size 1.27 1.27)
				)
			)
		)
		(property "Value" "4K7R2F-GP"
			(at 1.7907 -1.1176 270)
			(unlocked yes)
			(layer "F.Fab")
			(hide yes)
			(effects
				(font
					(size 1.016 1.016)
					(thickness 0.1524)
				)
			)
		)
		(property "Device Type" "R402H16"
			(at 1.7907 -2.6416 270)
			(unlocked yes)
			(layer "F.Fab")
			(hide yes)
			(effects
				(font
					(size 1.016 1.016)
					(thickness 0.1524)
				)
			)
		)
		(duplicate_pad_numbers_are_jumpers no)
		(fp_rect
			(start -0.381 0.8382)
			(end 0.381 -0.8382)
			(stroke
				(width 0)
				(type default)
			)
			(fill no)
			(layer "F.CrtYd")
		)
		(fp_rect
			(start -0.381 0.8382)
			(end 0.381 -0.8382)
			(stroke
				(width 0)
				(type default)
			)
			(fill no)
			(layer "F.Fab")
		)
		(pad "1" smd custom
			(at 0 -0.4318 270)
			(size 0.127 0.127)
			(layers "F.Cu" "F.Mask" "F.Paste")
			(net "SPI_SW_ADDR1")
			(options
				(clearance outline)
				(anchor circle)
			)
			(primitives
				(gr_poly
					(pts
						(arc
							(start -0.2032 -0.2794)
							(mid -0.239121 -0.264521)
							(end -0.254 -0.2286)
						)
						(arc
							(start -0.254 0.2286)
							(mid -0.239121 0.264521)
							(end -0.2032 0.2794)
						)
						(arc
							(start 0.2032 0.2794)
							(mid 0.239121 0.264521)
							(end 0.254 0.2286)
						)
						(arc
							(start 0.254 -0.2286)
							(mid 0.239121 -0.264521)
							(end 0.2032 -0.2794)
						)
					)
					(width 0)
					(fill yes)
				)
			)
		)
		(pad "2" smd custom
			(at 0 0.4318 270)
			(size 0.127 0.127)
			(layers "F.Cu" "F.Mask" "F.Paste")
			(net "GND")
			(options
				(clearance outline)
				(anchor circle)
			)
			(primitives
				(gr_poly
					(pts
						(arc
							(start -0.2032 -0.2794)
							(mid -0.239121 -0.264521)
							(end -0.254 -0.2286)
						)
						(arc
							(start -0.254 0.2286)
							(mid -0.239121 0.264521)
							(end -0.2032 0.2794)
						)
						(arc
							(start 0.2032 0.2794)
							(mid 0.239121 0.264521)
							(end 0.254 0.2286)
						)
						(arc
							(start 0.254 -0.2286)
							(mid 0.239121 -0.264521)
							(end 0.2032 -0.2794)
						)
					)
					(width 0)
					(fill yes)
				)
			)
		)
	)
	(footprint ""
		(layer "F.Cu")
		(at 66.802 -57.658)
		(property "Reference" "R473"
			(at 0 0 0)
			(layer "F.SilkS")
			(hide yes)
			(effects
				(font
					(size 1.27 1.27)
				)
			)
		)
		(property "Value" "0R2J-2-GP"
			(at 1.7907 -1.1176 0)
			(unlocked yes)
			(layer "F.Fab")
			(hide yes)
			(effects
				(font
					(size 1.016 1.016)
					(thickness 0.1524)
				)
			)
		)
		(property "Device Type" "R402H16"
			(at 1.7907 -2.6416 0)
			(unlocked yes)
			(layer "F.Fab")
			(hide yes)
			(effects
				(font
					(size 1.016 1.016)
					(thickness 0.1524)
				)
			)
		)
		(duplicate_pad_numbers_are_jumpers no)
		(fp_rect
			(start -0.381 0.8382)
			(end 0.381 -0.8382)
			(stroke
				(width 0)
				(type default)
			)
			(fill no)
			(layer "F.CrtYd")
		)
		(fp_rect
			(start -0.381 0.8382)
			(end 0.381 -0.8382)
			(stroke
				(width 0)
				(type default)
			)
			(fill no)
			(layer "F.Fab")
		)
		(pad "1" smd custom
			(at 0 -0.4318)
			(size 0.127 0.127)
			(layers "F.Cu" "F.Mask" "F.Paste")
			(net "FPGA_SMB_HOST_CLK")
			(options
				(clearance outline)
				(anchor circle)
			)
			(primitives
				(gr_poly
					(pts
						(arc
							(start -0.2032 -0.2794)
							(mid -0.239121 -0.264521)
							(end -0.254 -0.2286)
						)
						(arc
							(start -0.254 0.2286)
							(mid -0.239121 0.264521)
							(end -0.2032 0.2794)
						)
						(arc
							(start 0.2032 0.2794)
							(mid 0.239121 0.264521)
							(end 0.254 0.2286)
						)
						(arc
							(start 0.254 -0.2286)
							(mid 0.239121 -0.264521)
							(end 0.2032 -0.2794)
						)
					)
					(width 0)
					(fill yes)
				)
			)
		)
		(pad "2" smd custom
			(at 0 0.4318)
			(size 0.127 0.127)
			(layers "F.Cu" "F.Mask" "F.Paste")
			(net "FPGA_SMB_HOST_R_CLK")
			(options
				(clearance outline)
				(anchor circle)
			)
			(primitives
				(gr_poly
					(pts
						(arc
							(start -0.2032 -0.2794)
							(mid -0.239121 -0.264521)
							(end -0.254 -0.2286)
						)
						(arc
							(start -0.254 0.2286)
							(mid -0.239121 0.264521)
							(end -0.2032 0.2794)
						)
						(arc
							(start 0.2032 0.2794)
							(mid 0.239121 0.264521)
							(end 0.254 0.2286)
						)
						(arc
							(start 0.254 -0.2286)
							(mid 0.239121 -0.264521)
							(end 0.2032 -0.2794)
						)
					)
					(width 0)
					(fill yes)
				)
			)
		)
	)
	(footprint ""
		(layer "F.Cu")
		(at 49.4538 -12.7)
		(property "Reference" "C312"
			(at 0 0 0)
			(layer "F.SilkS")
			(hide yes)
			(effects
				(font
					(size 1.27 1.27)
				)
			)
		)
		(property "Value" "SCD047U25V2KX-GP"
			(at 1.8923 -1.2065 0)
			(unlocked yes)
			(layer "F.Fab")
			(hide yes)
			(effects
				(font
					(size 1.016 1.016)
					(thickness 0.1524)
				)
			)
		)
		(property "Device Type" "C402H22"
			(at 1.8923 -2.7305 0)
			(unlocked yes)
			(layer "F.Fab")
			(hide yes)
			(effects
				(font
					(size 1.016 1.016)
					(thickness 0.1524)
				)
			)
		)
		(duplicate_pad_numbers_are_jumpers no)
		(fp_rect
			(start -0.381 0.7366)
			(end 0.381 -0.7366)
			(stroke
				(width 0)
				(type default)
			)
			(fill no)
			(layer "F.CrtYd")
		)
		(fp_rect
			(start -0.381 0.7366)
			(end 0.381 -0.7366)
			(stroke
				(width 0)
				(type default)
			)
			(fill no)
			(layer "F.Fab")
		)
		(pad "1" smd custom
			(at 0 -0.4572)
			(size 0.1143 0.1143)
			(layers "F.Cu" "F.Mask" "F.Paste")
			(net "CPU_GBE_TX_DN0")
			(options
				(clearance outline)
				(anchor circle)
			)
			(primitives
				(gr_poly
					(pts
						(arc
							(start -0.254 -0.1778)
							(mid -0.239121 -0.213721)
							(end -0.2032 -0.2286)
						)
						(arc
							(start 0.2032 -0.2286)
							(mid 0.239121 -0.213721)
							(end 0.254 -0.1778)
						)
						(arc
							(start 0.254 0.1778)
							(mid 0.239121 0.213721)
							(end 0.2032 0.2286)
						)
						(arc
							(start -0.2032 0.2286)
							(mid -0.239121 0.213721)
							(end -0.254 0.1778)
						)
					)
					(width 0)
					(fill yes)
				)
			)
		)
		(pad "2" smd custom
			(at 0 0.4572)
			(size 0.1143 0.1143)
			(layers "F.Cu" "F.Mask" "F.Paste")
			(net "CPU_GBE_TX_C_DN0")
			(options
				(clearance outline)
				(anchor circle)
			)
			(primitives
				(gr_poly
					(pts
						(arc
							(start -0.254 -0.1778)
							(mid -0.239121 -0.213721)
							(end -0.2032 -0.2286)
						)
						(arc
							(start 0.2032 -0.2286)
							(mid 0.239121 -0.213721)
							(end 0.254 -0.1778)
						)
						(arc
							(start 0.254 0.1778)
							(mid 0.239121 0.213721)
							(end 0.2032 0.2286)
						)
						(arc
							(start -0.2032 0.2286)
							(mid -0.239121 0.213721)
							(end -0.254 0.1778)
						)
					)
					(width 0)
					(fill yes)
				)
			)
		)
	)
	(footprint ""
		(layer "F.Cu")
		(at 48.387 -16.0782 180)
		(property "Reference" "R348"
			(at 0 0 180)
			(layer "F.SilkS")
			(hide yes)
			(effects
				(font
					(size 1.27 1.27)
				)
			)
		)
		(property "Value" "4K7R2F-GP"
			(at 0.064008 -3.993896 180)
			(unlocked yes)
			(layer "F.Fab")
			(hide yes)
			(effects
				(font
					(size 1.016 1.016)
					(thickness 0.1524)
				)
			)
		)
		(property "Device Type" "R402H16"
			(at 0.064008 -5.517896 180)
			(unlocked yes)
			(layer "F.Fab")
			(hide yes)
			(effects
				(font
					(size 1.016 1.016)
					(thickness 0.1524)
				)
			)
		)
		(duplicate_pad_numbers_are_jumpers no)
		(fp_rect
			(start -0.381 0.8382)
			(end 0.381 -0.8382)
			(stroke
				(width 0)
				(type default)
			)
			(fill no)
			(layer "F.CrtYd")
		)
		(fp_rect
			(start -0.381 0.8382)
			(end 0.381 -0.8382)
			(stroke
				(width 0)
				(type default)
			)
			(fill no)
			(layer "F.Fab")
		)
		(pad "1" smd custom
			(at 0 -0.4318 180)
			(size 0.127 0.127)
			(layers "F.Cu" "F.Mask" "F.Paste")
			(net "P3V3")
			(options
				(clearance outline)
				(anchor circle)
			)
			(primitives
				(gr_poly
					(pts
						(arc
							(start -0.2032 -0.2794)
							(mid -0.239121 -0.264521)
							(end -0.254 -0.2286)
						)
						(arc
							(start -0.254 0.2286)
							(mid -0.239121 0.264521)
							(end -0.2032 0.2794)
						)
						(arc
							(start 0.2032 0.2794)
							(mid 0.239121 0.264521)
							(end 0.254 0.2286)
						)
						(arc
							(start 0.254 -0.2286)
							(mid 0.239121 -0.264521)
							(end 0.2032 -0.2794)
						)
					)
					(width 0)
					(fill yes)
				)
			)
		)
		(pad "2" smd custom
			(at 0 0.4318 180)
			(size 0.127 0.127)
			(layers "F.Cu" "F.Mask" "F.Paste")
			(net "CLKBUFF_OE3#")
			(options
				(clearance outline)
				(anchor circle)
			)
			(primitives
				(gr_poly
					(pts
						(arc
							(start -0.2032 -0.2794)
							(mid -0.239121 -0.264521)
							(end -0.254 -0.2286)
						)
						(arc
							(start -0.254 0.2286)
							(mid -0.239121 0.264521)
							(end -0.2032 0.2794)
						)
						(arc
							(start 0.2032 0.2794)
							(mid 0.239121 0.264521)
							(end 0.254 0.2286)
						)
						(arc
							(start 0.254 -0.2286)
							(mid 0.239121 -0.264521)
							(end 0.2032 -0.2794)
						)
					)
					(width 0)
					(fill yes)
				)
			)
		)
	)
	(footprint ""
		(layer "F.Cu")
		(at 44.704 -21.463 -90)
		(property "Reference" "R246"
			(at 0 0 270)
			(layer "F.SilkS")
			(hide yes)
			(effects
				(font
					(size 1.27 1.27)
				)
			)
		)
		(property "Value" "1KR2F-3-GP"
			(at 0.064008 -3.993896 270)
			(unlocked yes)
			(layer "F.Fab")
			(hide yes)
			(effects
				(font
					(size 1.016 1.016)
					(thickness 0.1524)
				)
			)
		)
		(property "Device Type" "R402H16"
			(at 0.064008 -5.517896 270)
			(unlocked yes)
			(layer "F.Fab")
			(hide yes)
			(effects
				(font
					(size 1.016 1.016)
					(thickness 0.1524)
				)
			)
		)
		(duplicate_pad_numbers_are_jumpers no)
		(fp_rect
			(start -0.381 0.8382)
			(end 0.381 -0.8382)
			(stroke
				(width 0)
				(type default)
			)
			(fill no)
			(layer "F.CrtYd")
		)
		(fp_rect
			(start -0.381 0.8382)
			(end 0.381 -0.8382)
			(stroke
				(width 0)
				(type default)
			)
			(fill no)
			(layer "F.Fab")
		)
		(pad "1" smd custom
			(at 0 -0.4318 270)
			(size 0.127 0.127)
			(layers "F.Cu" "F.Mask" "F.Paste")
			(net "P1V0")
			(options
				(clearance outline)
				(anchor circle)
			)
			(primitives
				(gr_poly
					(pts
						(arc
							(start -0.2032 -0.2794)
							(mid -0.239121 -0.264521)
							(end -0.254 -0.2286)
						)
						(arc
							(start -0.254 0.2286)
							(mid -0.239121 0.264521)
							(end -0.2032 0.2794)
						)
						(arc
							(start 0.2032 0.2794)
							(mid 0.239121 0.264521)
							(end 0.254 0.2286)
						)
						(arc
							(start 0.254 -0.2286)
							(mid 0.239121 -0.264521)
							(end 0.2032 -0.2794)
						)
					)
					(width 0)
					(fill yes)
				)
			)
		)
		(pad "2" smd custom
			(at 0 0.4318 270)
			(size 0.127 0.127)
			(layers "F.Cu" "F.Mask" "F.Paste")
			(net "XDP_CPU_PRDY#")
			(options
				(clearance outline)
				(anchor circle)
			)
			(primitives
				(gr_poly
					(pts
						(arc
							(start -0.2032 -0.2794)
							(mid -0.239121 -0.264521)
							(end -0.254 -0.2286)
						)
						(arc
							(start -0.254 0.2286)
							(mid -0.239121 0.264521)
							(end -0.2032 0.2794)
						)
						(arc
							(start 0.2032 0.2794)
							(mid 0.239121 0.264521)
							(end 0.254 0.2286)
						)
						(arc
							(start 0.254 -0.2286)
							(mid 0.239121 -0.264521)
							(end 0.2032 -0.2794)
						)
					)
					(width 0)
					(fill yes)
				)
			)
		)
	)
	(footprint ""
		(layer "F.Cu")
		(at 5.715 -37.211 -90)
		(property "Reference" "PC187"
			(at 0 0 270)
			(layer "F.SilkS")
			(hide yes)
			(effects
				(font
					(size 1.27 1.27)
				)
			)
		)
		(property "Value" "SC22U25V5MX-GP"
			(at 0 -4.9022 270)
			(unlocked yes)
			(layer "F.Fab")
			(hide yes)
			(effects
				(font
					(size 1.016 1.016)
					(thickness 0.1524)
				)
			)
		)
		(property "Device Type" "C805H58"
			(at 0 -6.8072 270)
			(unlocked yes)
			(layer "F.Fab")
			(hide yes)
			(effects
				(font
					(size 1.016 1.016)
					(thickness 0.1524)
				)
			)
		)
		(duplicate_pad_numbers_are_jumpers no)
		(fp_line
			(start 0.6096 0)
			(end -0.6096 0)
			(stroke
				(width 0.3048)
				(type default)
			)
			(layer "F.SilkS")
		)
		(fp_poly
			(pts
				(xy -0.9017 1.4351) (xy 0.9017 1.4351) (xy 0.9017 -1.4351) (xy -0.9017 -1.4351)
			)
			(stroke
				(width 0)
				(type default)
			)
			(fill no)
			(layer "F.CrtYd")
		)
		(fp_poly
			(pts
				(xy 0.9017 1.4351) (xy 0.9017 -1.4351) (xy -0.9017 -1.4351) (xy -0.9017 1.4351)
			)
			(stroke
				(width 0)
				(type default)
			)
			(fill no)
			(layer "F.Fab")
		)
		(pad "1" smd rect
			(at 0 -0.8382 270)
			(size 1.5494 0.9398)
			(layers "F.Cu" "F.Mask" "F.Paste")
			(net "P3V3_STBY_VIN")
		)
		(pad "2" smd rect
			(at 0 0.8382 270)
			(size 1.5494 0.9398)
			(layers "F.Cu" "F.Mask" "F.Paste")
			(net "GND")
		)
	)
	(footprint ""
		(layer "F.Cu")
		(at 187.071 -27.0002)
		(property "Reference" "PR160"
			(at 0 0 0)
			(layer "F.SilkS")
			(hide yes)
			(effects
				(font
					(size 1.27 1.27)
				)
			)
		)
		(property "Value" "0R2J-2-GP"
			(at 1.7907 -1.1176 0)
			(unlocked yes)
			(layer "F.Fab")
			(hide yes)
			(effects
				(font
					(size 1.016 1.016)
					(thickness 0.1524)
				)
			)
		)
		(property "Device Type" "R402H16"
			(at 1.7907 -2.6416 0)
			(unlocked yes)
			(layer "F.Fab")
			(hide yes)
			(effects
				(font
					(size 1.016 1.016)
					(thickness 0.1524)
				)
			)
		)
		(duplicate_pad_numbers_are_jumpers no)
		(fp_rect
			(start -0.381 0.8382)
			(end 0.381 -0.8382)
			(stroke
				(width 0)
				(type default)
			)
			(fill no)
			(layer "F.CrtYd")
		)
		(fp_rect
			(start -0.381 0.8382)
			(end 0.381 -0.8382)
			(stroke
				(width 0)
				(type default)
			)
			(fill no)
			(layer "F.Fab")
		)
		(pad "1" smd custom
			(at 0 -0.4318)
			(size 0.127 0.127)
			(layers "F.Cu" "F.Mask" "F.Paste")
			(net "VR_PVDDR_A_VSEN")
			(options
				(clearance outline)
				(anchor circle)
			)
			(primitives
				(gr_poly
					(pts
						(arc
							(start -0.2032 -0.2794)
							(mid -0.239121 -0.264521)
							(end -0.254 -0.2286)
						)
						(arc
							(start -0.254 0.2286)
							(mid -0.239121 0.264521)
							(end -0.2032 0.2794)
						)
						(arc
							(start 0.2032 0.2794)
							(mid 0.239121 0.264521)
							(end 0.254 0.2286)
						)
						(arc
							(start 0.254 -0.2286)
							(mid 0.239121 -0.264521)
							(end 0.2032 -0.2794)
						)
					)
					(width 0)
					(fill yes)
				)
			)
		)
		(pad "2" smd custom
			(at 0 0.4318)
			(size 0.127 0.127)
			(layers "F.Cu" "F.Mask" "F.Paste")
			(net "VSENSE_PVDDR_A_VSEN")
			(options
				(clearance outline)
				(anchor circle)
			)
			(primitives
				(gr_poly
					(pts
						(arc
							(start -0.2032 -0.2794)
							(mid -0.239121 -0.264521)
							(end -0.254 -0.2286)
						)
						(arc
							(start -0.254 0.2286)
							(mid -0.239121 0.264521)
							(end -0.2032 0.2794)
						)
						(arc
							(start 0.2032 0.2794)
							(mid 0.239121 0.264521)
							(end 0.254 0.2286)
						)
						(arc
							(start 0.254 -0.2286)
							(mid 0.239121 -0.264521)
							(end 0.2032 -0.2794)
						)
					)
					(width 0)
					(fill yes)
				)
			)
		)
	)
	(footprint ""
		(layer "F.Cu")
		(at 38.9128 -54.483)
		(property "Reference" "PC32"
			(at 0 0 0)
			(layer "F.SilkS")
			(hide yes)
			(effects
				(font
					(size 1.27 1.27)
				)
			)
		)
		(property "Value" "SCD1U25V2KX-2-GP"
			(at 1.8923 -1.2065 0)
			(unlocked yes)
			(layer "F.Fab")
			(hide yes)
			(effects
				(font
					(size 1.016 1.016)
					(thickness 0.1524)
				)
			)
		)
		(property "Device Type" "C402H22"
			(at 1.8923 -2.7305 0)
			(unlocked yes)
			(layer "F.Fab")
			(hide yes)
			(effects
				(font
					(size 1.016 1.016)
					(thickness 0.1524)
				)
			)
		)
		(duplicate_pad_numbers_are_jumpers no)
		(fp_rect
			(start -0.381 0.7366)
			(end 0.381 -0.7366)
			(stroke
				(width 0)
				(type default)
			)
			(fill no)
			(layer "F.CrtYd")
		)
		(fp_rect
			(start -0.381 0.7366)
			(end 0.381 -0.7366)
			(stroke
				(width 0)
				(type default)
			)
			(fill no)
			(layer "F.Fab")
		)
		(pad "1" smd custom
			(at 0 -0.4572)
			(size 0.1143 0.1143)
			(layers "F.Cu" "F.Mask" "F.Paste")
			(net "VR_FET_SW_P12V_PVCCP_PVNN")
			(options
				(clearance outline)
				(anchor circle)
			)
			(primitives
				(gr_poly
					(pts
						(arc
							(start -0.254 -0.1778)
							(mid -0.239121 -0.213721)
							(end -0.2032 -0.2286)
						)
						(arc
							(start 0.2032 -0.2286)
							(mid 0.239121 -0.213721)
							(end 0.254 -0.1778)
						)
						(arc
							(start 0.254 0.1778)
							(mid 0.239121 0.213721)
							(end 0.2032 0.2286)
						)
						(arc
							(start -0.2032 0.2286)
							(mid -0.239121 0.213721)
							(end -0.254 0.1778)
						)
					)
					(width 0)
					(fill yes)
				)
			)
		)
		(pad "2" smd custom
			(at 0 0.4572)
			(size 0.1143 0.1143)
			(layers "F.Cu" "F.Mask" "F.Paste")
			(net "GND")
			(options
				(clearance outline)
				(anchor circle)
			)
			(primitives
				(gr_poly
					(pts
						(arc
							(start -0.254 -0.1778)
							(mid -0.239121 -0.213721)
							(end -0.2032 -0.2286)
						)
						(arc
							(start 0.2032 -0.2286)
							(mid 0.239121 -0.213721)
							(end 0.254 -0.1778)
						)
						(arc
							(start 0.254 0.1778)
							(mid 0.239121 0.213721)
							(end 0.2032 0.2286)
						)
						(arc
							(start -0.2032 0.2286)
							(mid -0.239121 0.213721)
							(end -0.254 0.1778)
						)
					)
					(width 0)
					(fill yes)
				)
			)
		)
	)
	(footprint ""
		(layer "F.Cu")
		(at 112.522 -71.12)
		(property "Reference" "R235"
			(at 0 0 0)
			(layer "F.SilkS")
			(hide yes)
			(effects
				(font
					(size 1.27 1.27)
				)
			)
		)
		(property "Value" "4K7R2F-GP"
			(at 0.064008 -3.993896 0)
			(unlocked yes)
			(layer "F.Fab")
			(hide yes)
			(effects
				(font
					(size 1.016 1.016)
					(thickness 0.1524)
				)
			)
		)
		(property "Device Type" "R402H16"
			(at 0.064008 -5.517896 0)
			(unlocked yes)
			(layer "F.Fab")
			(hide yes)
			(effects
				(font
					(size 1.016 1.016)
					(thickness 0.1524)
				)
			)
		)
		(duplicate_pad_numbers_are_jumpers no)
		(fp_rect
			(start -0.381 0.8382)
			(end 0.381 -0.8382)
			(stroke
				(width 0)
				(type default)
			)
			(fill no)
			(layer "F.CrtYd")
		)
		(fp_rect
			(start -0.381 0.8382)
			(end 0.381 -0.8382)
			(stroke
				(width 0)
				(type default)
			)
			(fill no)
			(layer "F.Fab")
		)
		(pad "1" smd custom
			(at 0 -0.4318)
			(size 0.127 0.127)
			(layers "F.Cu" "F.Mask" "F.Paste")
			(net "CHA_1_SA0")
			(options
				(clearance outline)
				(anchor circle)
			)
			(primitives
				(gr_poly
					(pts
						(arc
							(start -0.2032 -0.2794)
							(mid -0.239121 -0.264521)
							(end -0.254 -0.2286)
						)
						(arc
							(start -0.254 0.2286)
							(mid -0.239121 0.264521)
							(end -0.2032 0.2794)
						)
						(arc
							(start 0.2032 0.2794)
							(mid 0.239121 0.264521)
							(end 0.254 0.2286)
						)
						(arc
							(start 0.254 -0.2286)
							(mid 0.239121 -0.264521)
							(end 0.2032 -0.2794)
						)
					)
					(width 0)
					(fill yes)
				)
			)
		)
		(pad "2" smd custom
			(at 0 0.4318)
			(size 0.127 0.127)
			(layers "F.Cu" "F.Mask" "F.Paste")
			(net "GND")
			(options
				(clearance outline)
				(anchor circle)
			)
			(primitives
				(gr_poly
					(pts
						(arc
							(start -0.2032 -0.2794)
							(mid -0.239121 -0.264521)
							(end -0.254 -0.2286)
						)
						(arc
							(start -0.254 0.2286)
							(mid -0.239121 0.264521)
							(end -0.2032 0.2794)
						)
						(arc
							(start 0.2032 0.2794)
							(mid 0.239121 0.264521)
							(end 0.254 0.2286)
						)
						(arc
							(start 0.254 -0.2286)
							(mid 0.239121 -0.264521)
							(end 0.2032 -0.2794)
						)
					)
					(width 0)
					(fill yes)
				)
			)
		)
	)
	(footprint ""
		(layer "F.Cu")
		(at 164.846 -43.942 -90)
		(property "Reference" "R86"
			(at 0 0 270)
			(layer "F.SilkS")
			(hide yes)
			(effects
				(font
					(size 1.27 1.27)
				)
			)
		)
		(property "Value" "33R2F-3-GP"
			(at 0.064008 -3.993896 270)
			(unlocked yes)
			(layer "F.Fab")
			(hide yes)
			(effects
				(font
					(size 1.016 1.016)
					(thickness 0.1524)
				)
			)
		)
		(property "Device Type" "R402H16"
			(at 0.064008 -5.517896 270)
			(unlocked yes)
			(layer "F.Fab")
			(hide yes)
			(effects
				(font
					(size 1.016 1.016)
					(thickness 0.1524)
				)
			)
		)
		(duplicate_pad_numbers_are_jumpers no)
		(fp_rect
			(start -0.381 0.8382)
			(end 0.381 -0.8382)
			(stroke
				(width 0)
				(type default)
			)
			(fill no)
			(layer "F.CrtYd")
		)
		(fp_rect
			(start -0.381 0.8382)
			(end 0.381 -0.8382)
			(stroke
				(width 0)
				(type default)
			)
			(fill no)
			(layer "F.Fab")
		)
		(pad "1" smd custom
			(at 0 -0.4318 270)
			(size 0.127 0.127)
			(layers "F.Cu" "F.Mask" "F.Paste")
			(net "OSC_5M_CLK_R")
			(options
				(clearance outline)
				(anchor circle)
			)
			(primitives
				(gr_poly
					(pts
						(arc
							(start -0.2032 -0.2794)
							(mid -0.239121 -0.264521)
							(end -0.254 -0.2286)
						)
						(arc
							(start -0.254 0.2286)
							(mid -0.239121 0.264521)
							(end -0.2032 0.2794)
						)
						(arc
							(start 0.2032 0.2794)
							(mid 0.239121 0.264521)
							(end 0.254 0.2286)
						)
						(arc
							(start 0.254 -0.2286)
							(mid 0.239121 -0.264521)
							(end 0.2032 -0.2794)
						)
					)
					(width 0)
					(fill yes)
				)
			)
		)
		(pad "2" smd custom
			(at 0 0.4318 270)
			(size 0.127 0.127)
			(layers "F.Cu" "F.Mask" "F.Paste")
			(net "FPGA_CLK_DP")
			(options
				(clearance outline)
				(anchor circle)
			)
			(primitives
				(gr_poly
					(pts
						(arc
							(start -0.2032 -0.2794)
							(mid -0.239121 -0.264521)
							(end -0.254 -0.2286)
						)
						(arc
							(start -0.254 0.2286)
							(mid -0.239121 0.264521)
							(end -0.2032 0.2794)
						)
						(arc
							(start 0.2032 0.2794)
							(mid 0.239121 0.264521)
							(end 0.254 0.2286)
						)
						(arc
							(start 0.254 -0.2286)
							(mid 0.239121 -0.264521)
							(end 0.2032 -0.2794)
						)
					)
					(width 0)
					(fill yes)
				)
			)
		)
	)
	(footprint ""
		(layer "F.Cu")
		(at 11.43 -50.4952 90)
		(property "Reference" "C63"
			(at 0 0 90)
			(layer "F.SilkS")
			(hide yes)
			(effects
				(font
					(size 1.27 1.27)
				)
			)
		)
		(property "Value" "SCD1U16V2KX-3GP"
			(at 1.1811 -2.7051 90)
			(unlocked yes)
			(layer "F.Fab")
			(hide yes)
			(effects
				(font
					(size 1.016 1.016)
					(thickness 0.1524)
				)
			)
		)
		(property "Device Type" "C402H22"
			(at 1.1811 -4.2291 90)
			(unlocked yes)
			(layer "F.Fab")
			(hide yes)
			(effects
				(font
					(size 1.016 1.016)
					(thickness 0.1524)
				)
			)
		)
		(duplicate_pad_numbers_are_jumpers no)
		(fp_rect
			(start -0.381 0.7366)
			(end 0.381 -0.7366)
			(stroke
				(width 0)
				(type default)
			)
			(fill no)
			(layer "F.CrtYd")
		)
		(fp_rect
			(start -0.381 0.7366)
			(end 0.381 -0.7366)
			(stroke
				(width 0)
				(type default)
			)
			(fill no)
			(layer "F.Fab")
		)
		(pad "1" smd custom
			(at 0 -0.4572 90)
			(size 0.1143 0.1143)
			(layers "F.Cu" "F.Mask" "F.Paste")
			(net "P2E_CPU_NGFF_TX_DP12")
			(options
				(clearance outline)
				(anchor circle)
			)
			(primitives
				(gr_poly
					(pts
						(arc
							(start -0.254 -0.1778)
							(mid -0.239121 -0.213721)
							(end -0.2032 -0.2286)
						)
						(arc
							(start 0.2032 -0.2286)
							(mid 0.239121 -0.213721)
							(end 0.254 -0.1778)
						)
						(arc
							(start 0.254 0.1778)
							(mid 0.239121 0.213721)
							(end 0.2032 0.2286)
						)
						(arc
							(start -0.2032 0.2286)
							(mid -0.239121 0.213721)
							(end -0.254 0.1778)
						)
					)
					(width 0)
					(fill yes)
				)
			)
		)
		(pad "2" smd custom
			(at 0 0.4572 90)
			(size 0.1143 0.1143)
			(layers "F.Cu" "F.Mask" "F.Paste")
			(net "P2E_CPU_NGFF_C_TX_DP12")
			(options
				(clearance outline)
				(anchor circle)
			)
			(primitives
				(gr_poly
					(pts
						(arc
							(start -0.254 -0.1778)
							(mid -0.239121 -0.213721)
							(end -0.2032 -0.2286)
						)
						(arc
							(start 0.2032 -0.2286)
							(mid 0.239121 -0.213721)
							(end 0.254 -0.1778)
						)
						(arc
							(start 0.254 0.1778)
							(mid 0.239121 0.213721)
							(end 0.2032 0.2286)
						)
						(arc
							(start -0.2032 0.2286)
							(mid -0.239121 0.213721)
							(end -0.254 0.1778)
						)
					)
					(width 0)
					(fill yes)
				)
			)
		)
	)
	(footprint ""
		(layer "F.Cu")
		(at 165.3032 -12.828778 180)
		(property "Reference" "C341"
			(at 0 0 180)
			(layer "F.SilkS")
			(hide yes)
			(effects
				(font
					(size 1.27 1.27)
				)
			)
		)
		(property "Value" "SCD1U16V2KX-3GP"
			(at 1.8923 -1.2065 180)
			(unlocked yes)
			(layer "F.Fab")
			(hide yes)
			(effects
				(font
					(size 1.016 1.016)
					(thickness 0.1524)
				)
			)
		)
		(property "Device Type" "C402H22"
			(at 1.8923 -2.7305 180)
			(unlocked yes)
			(layer "F.Fab")
			(hide yes)
			(effects
				(font
					(size 1.016 1.016)
					(thickness 0.1524)
				)
			)
		)
		(duplicate_pad_numbers_are_jumpers no)
		(fp_rect
			(start -0.381 0.7366)
			(end 0.381 -0.7366)
			(stroke
				(width 0)
				(type default)
			)
			(fill no)
			(layer "F.CrtYd")
		)
		(fp_rect
			(start -0.381 0.7366)
			(end 0.381 -0.7366)
			(stroke
				(width 0)
				(type default)
			)
			(fill no)
			(layer "F.Fab")
		)
		(pad "1" smd custom
			(at 0 -0.4572 180)
			(size 0.1143 0.1143)
			(layers "F.Cu" "F.Mask" "F.Paste")
			(net "PV_VDDR")
			(options
				(clearance outline)
				(anchor circle)
			)
			(primitives
				(gr_poly
					(pts
						(arc
							(start -0.254 -0.1778)
							(mid -0.239121 -0.213721)
							(end -0.2032 -0.2286)
						)
						(arc
							(start 0.2032 -0.2286)
							(mid 0.239121 -0.213721)
							(end 0.254 -0.1778)
						)
						(arc
							(start 0.254 0.1778)
							(mid 0.239121 0.213721)
							(end 0.2032 0.2286)
						)
						(arc
							(start -0.2032 0.2286)
							(mid -0.239121 0.213721)
							(end -0.254 0.1778)
						)
					)
					(width 0)
					(fill yes)
				)
			)
		)
		(pad "2" smd custom
			(at 0 0.4572 180)
			(size 0.1143 0.1143)
			(layers "F.Cu" "F.Mask" "F.Paste")
			(net "GND")
			(options
				(clearance outline)
				(anchor circle)
			)
			(primitives
				(gr_poly
					(pts
						(arc
							(start -0.254 -0.1778)
							(mid -0.239121 -0.213721)
							(end -0.2032 -0.2286)
						)
						(arc
							(start 0.2032 -0.2286)
							(mid 0.239121 -0.213721)
							(end 0.254 -0.1778)
						)
						(arc
							(start 0.254 0.1778)
							(mid 0.239121 0.213721)
							(end 0.2032 0.2286)
						)
						(arc
							(start -0.2032 0.2286)
							(mid -0.239121 0.213721)
							(end -0.254 0.1778)
						)
					)
					(width 0)
					(fill yes)
				)
			)
		)
	)
	(footprint ""
		(layer "F.Cu")
		(at 132.207 -48.514 180)
		(property "Reference" "Q1"
			(at 0 0 180)
			(layer "F.SilkS")
			(hide yes)
			(effects
				(font
					(size 1.27 1.27)
				)
			)
		)
		(property "Value" "MMBT3904TT1G-GP"
			(at -2.032 -3.674618 180)
			(unlocked yes)
			(layer "F.Fab")
			(hide yes)
			(effects
				(font
					(size 1.016 1.016)
					(thickness 0.1524)
				)
			)
		)
		(property "Device Type" "SC75CBE1D6H36"
			(at -2.032 -5.198618 180)
			(unlocked yes)
			(layer "F.Fab")
			(hide yes)
			(effects
				(font
					(size 1.016 1.016)
					(thickness 0.1524)
				)
			)
		)
		(duplicate_pad_numbers_are_jumpers no)
		(fp_poly
			(pts
				(xy 0.381 -1.1938) (xy -0.381 -1.1938) (xy -0.381 -0.6604) (xy -1.0541 -0.6604) (xy -1.0541 0.6604)
				(xy -0.889 0.6604) (xy -0.889 1.1938) (xy 0.889 1.1938) (xy 0.889 0.6604) (xy 1.0541 0.6604) (xy 1.0541 -0.6604)
				(xy 0.381 -0.6604)
			)
			(stroke
				(width 0)
				(type default)
			)
			(fill no)
			(layer "F.CrtYd")
		)
		(fp_poly
			(pts
				(xy 0.381 -1.1938) (xy -0.381 -1.1938) (xy -0.381 -0.6604) (xy -1.0541 -0.6604) (xy -1.0541 0.6604)
				(xy -0.889 0.6604) (xy -0.889 1.1938) (xy 0.889 1.1938) (xy 0.889 0.6604) (xy 1.0541 0.6604) (xy 1.0541 -0.6604)
				(xy 0.381 -0.6604)
			)
			(stroke
				(width 0)
				(type default)
			)
			(fill no)
			(layer "F.Fab")
		)
		(pad "B" smd custom
			(at -0.508 0.6604 180)
			(size 0.127 0.127)
			(layers "F.Cu" "F.Mask" "F.Paste")
			(net "MEMORY_HOT_N_LV_B2")
			(options
				(clearance outline)
				(anchor circle)
			)
			(primitives
				(gr_poly
					(pts
						(arc
							(start -0.0508 0.4064)
							(mid -0.194484 0.346884)
							(end -0.254 0.2032)
						)
						(arc
							(start -0.254 -0.2032)
							(mid -0.194484 -0.346884)
							(end -0.0508 -0.4064)
						)
						(arc
							(start 0.0508 -0.4064)
							(mid 0.194484 -0.346884)
							(end 0.254 -0.2032)
						)
						(arc
							(start 0.254 0.2032)
							(mid 0.194484 0.346884)
							(end 0.0508 0.4064)
						)
					)
					(width 0)
					(fill yes)
				)
			)
		)
		(pad "C" smd custom
			(at 0 -0.6604 180)
			(size 0.127 0.127)
			(layers "F.Cu" "F.Mask" "F.Paste")
			(net "MEMORY_FPGA_HOT#")
			(options
				(clearance outline)
				(anchor circle)
			)
			(primitives
				(gr_poly
					(pts
						(arc
							(start -0.0508 0.4064)
							(mid -0.194484 0.346884)
							(end -0.254 0.2032)
						)
						(arc
							(start -0.254 -0.2032)
							(mid -0.194484 -0.346884)
							(end -0.0508 -0.4064)
						)
						(arc
							(start 0.0508 -0.4064)
							(mid 0.194484 -0.346884)
							(end 0.254 -0.2032)
						)
						(arc
							(start 0.254 0.2032)
							(mid 0.194484 0.346884)
							(end 0.0508 0.4064)
						)
					)
					(width 0)
					(fill yes)
				)
			)
		)
		(pad "E" smd custom
			(at 0.508 0.6604 180)
			(size 0.127 0.127)
			(layers "F.Cu" "F.Mask" "F.Paste")
			(net "MEMORY_HOT_LV_E2#")
			(options
				(clearance outline)
				(anchor circle)
			)
			(primitives
				(gr_poly
					(pts
						(arc
							(start -0.0508 0.4064)
							(mid -0.194484 0.346884)
							(end -0.254 0.2032)
						)
						(arc
							(start -0.254 -0.2032)
							(mid -0.194484 -0.346884)
							(end -0.0508 -0.4064)
						)
						(arc
							(start 0.0508 -0.4064)
							(mid 0.194484 -0.346884)
							(end 0.254 -0.2032)
						)
						(arc
							(start 0.254 0.2032)
							(mid 0.194484 0.346884)
							(end 0.0508 0.4064)
						)
					)
					(width 0)
					(fill yes)
				)
			)
		)
	)
	(footprint ""
		(layer "F.Cu")
		(at 8.509 -61.849 90)
		(property "Reference" "C32"
			(at 0 0 90)
			(layer "F.SilkS")
			(hide yes)
			(effects
				(font
					(size 1.27 1.27)
				)
			)
		)
		(property "Value" "SCD1U16V2KX-3GP"
			(at 1.1811 -2.7051 90)
			(unlocked yes)
			(layer "F.Fab")
			(hide yes)
			(effects
				(font
					(size 1.016 1.016)
					(thickness 0.1524)
				)
			)
		)
		(property "Device Type" "C402H22"
			(at 1.1811 -4.2291 90)
			(unlocked yes)
			(layer "F.Fab")
			(hide yes)
			(effects
				(font
					(size 1.016 1.016)
					(thickness 0.1524)
				)
			)
		)
		(duplicate_pad_numbers_are_jumpers no)
		(fp_rect
			(start -0.381 0.7366)
			(end 0.381 -0.7366)
			(stroke
				(width 0)
				(type default)
			)
			(fill no)
			(layer "F.CrtYd")
		)
		(fp_rect
			(start -0.381 0.7366)
			(end 0.381 -0.7366)
			(stroke
				(width 0)
				(type default)
			)
			(fill no)
			(layer "F.Fab")
		)
		(pad "1" smd custom
			(at 0 -0.4572 90)
			(size 0.1143 0.1143)
			(layers "F.Cu" "F.Mask" "F.Paste")
			(net "P2E_CPU_NGFF_C_RX_DN14")
			(options
				(clearance outline)
				(anchor circle)
			)
			(primitives
				(gr_poly
					(pts
						(arc
							(start -0.254 -0.1778)
							(mid -0.239121 -0.213721)
							(end -0.2032 -0.2286)
						)
						(arc
							(start 0.2032 -0.2286)
							(mid 0.239121 -0.213721)
							(end 0.254 -0.1778)
						)
						(arc
							(start 0.254 0.1778)
							(mid 0.239121 0.213721)
							(end 0.2032 0.2286)
						)
						(arc
							(start -0.2032 0.2286)
							(mid -0.239121 0.213721)
							(end -0.254 0.1778)
						)
					)
					(width 0)
					(fill yes)
				)
			)
		)
		(pad "2" smd custom
			(at 0 0.4572 90)
			(size 0.1143 0.1143)
			(layers "F.Cu" "F.Mask" "F.Paste")
			(net "P2E_CPU_NGFF_RX_DN14")
			(options
				(clearance outline)
				(anchor circle)
			)
			(primitives
				(gr_poly
					(pts
						(arc
							(start -0.254 -0.1778)
							(mid -0.239121 -0.213721)
							(end -0.2032 -0.2286)
						)
						(arc
							(start 0.2032 -0.2286)
							(mid 0.239121 -0.213721)
							(end 0.254 -0.1778)
						)
						(arc
							(start 0.254 0.1778)
							(mid 0.239121 0.213721)
							(end 0.2032 0.2286)
						)
						(arc
							(start -0.2032 0.2286)
							(mid -0.239121 0.213721)
							(end -0.254 0.1778)
						)
					)
					(width 0)
					(fill yes)
				)
			)
		)
	)
	(footprint ""
		(layer "F.Cu")
		(at 34.29 -13.081)
		(property "Reference" "R463"
			(at 0 0 0)
			(layer "F.SilkS")
			(hide yes)
			(effects
				(font
					(size 1.27 1.27)
				)
			)
		)
		(property "Value" "4K7R2F-GP"
			(at 1.7907 -1.1176 0)
			(unlocked yes)
			(layer "F.Fab")
			(hide yes)
			(effects
				(font
					(size 1.016 1.016)
					(thickness 0.1524)
				)
			)
		)
		(property "Device Type" "R402H16"
			(at 1.7907 -2.6416 0)
			(unlocked yes)
			(layer "F.Fab")
			(hide yes)
			(effects
				(font
					(size 1.016 1.016)
					(thickness 0.1524)
				)
			)
		)
		(duplicate_pad_numbers_are_jumpers no)
		(fp_rect
			(start -0.381 0.8382)
			(end 0.381 -0.8382)
			(stroke
				(width 0)
				(type default)
			)
			(fill no)
			(layer "F.CrtYd")
		)
		(fp_rect
			(start -0.381 0.8382)
			(end 0.381 -0.8382)
			(stroke
				(width 0)
				(type default)
			)
			(fill no)
			(layer "F.Fab")
		)
		(pad "1" smd custom
			(at 0 -0.4318)
			(size 0.127 0.127)
			(layers "F.Cu" "F.Mask" "F.Paste")
			(net "P3V3_STBY")
			(options
				(clearance outline)
				(anchor circle)
			)
			(primitives
				(gr_poly
					(pts
						(arc
							(start -0.2032 -0.2794)
							(mid -0.239121 -0.264521)
							(end -0.254 -0.2286)
						)
						(arc
							(start -0.254 0.2286)
							(mid -0.239121 0.264521)
							(end -0.2032 0.2794)
						)
						(arc
							(start 0.2032 0.2794)
							(mid 0.239121 0.264521)
							(end 0.254 0.2286)
						)
						(arc
							(start 0.254 -0.2286)
							(mid 0.239121 -0.264521)
							(end 0.2032 -0.2794)
						)
					)
					(width 0)
					(fill yes)
				)
			)
		)
		(pad "2" smd custom
			(at 0 0.4318)
			(size 0.127 0.127)
			(layers "F.Cu" "F.Mask" "F.Paste")
			(net "PCIE_GF_I2C_DATA")
			(options
				(clearance outline)
				(anchor circle)
			)
			(primitives
				(gr_poly
					(pts
						(arc
							(start -0.2032 -0.2794)
							(mid -0.239121 -0.264521)
							(end -0.254 -0.2286)
						)
						(arc
							(start -0.254 0.2286)
							(mid -0.239121 0.264521)
							(end -0.2032 0.2794)
						)
						(arc
							(start 0.2032 0.2794)
							(mid 0.239121 0.264521)
							(end 0.254 0.2286)
						)
						(arc
							(start 0.254 -0.2286)
							(mid 0.239121 -0.264521)
							(end 0.2032 -0.2794)
						)
					)
					(width 0)
					(fill yes)
				)
			)
		)
	)
	(footprint ""
		(layer "F.Cu")
		(at 200.787 -61.722 90)
		(property "Reference" "PTC3"
			(at 0 0 90)
			(layer "F.SilkS")
			(hide yes)
			(effects
				(font
					(size 1.27 1.27)
				)
			)
		)
		(property "Value" "SE470UF2VDM-GP"
			(at -3.220466 1.242822 90)
			(unlocked yes)
			(layer "F.Fab")
			(hide yes)
			(effects
				(font
					(size 1.016 1.016)
					(thickness 0.1524)
				)
			)
		)
		(property "Device Type" "CT7343H83"
			(at -3.220466 -0.281178 90)
			(unlocked yes)
			(layer "F.Fab")
			(hide yes)
			(effects
				(font
					(size 1.016 1.016)
					(thickness 0.1524)
				)
			)
		)
		(duplicate_pad_numbers_are_jumpers no)
		(fp_line
			(start -2.206752 -4.2926)
			(end 2.155698 -4.2926)
			(stroke
				(width 0.508)
				(type default)
			)
			(layer "F.SilkS")
		)
		(fp_rect
			(start -2.1463 3.6449)
			(end 2.1463 -3.6449)
			(stroke
				(width 0)
				(type default)
			)
			(fill no)
			(layer "F.CrtYd")
		)
		(fp_poly
			(pts
				(xy -3.81 3.9116) (xy -3.81 -3.9116) (xy -2.54 -3.9116) (xy -2.4003 -3.9116) (xy -2.4003 -4.0386)
				(xy 2.4003 -4.0386) (xy 2.4003 -3.9116) (xy 2.54 -3.9116) (xy 2.5654 -3.9116) (xy 3.81 -3.9116)
				(xy 3.81 -1.6256) (xy 2.1463 -1.6256) (xy 2.1463 -3.6449) (xy -2.1463 -3.6449) (xy -2.1463 3.6449)
				(xy 2.1463 3.6449) (xy 2.1463 -1.6129) (xy 3.81 -1.6129) (xy 3.81 3.9116) (xy 2.4003 3.9116) (xy 2.4003 3.9243)
				(xy 2.4003 4.0386) (xy -2.4003 4.0386) (xy -2.4003 3.9116)
			)
			(stroke
				(width 0)
				(type default)
			)
			(fill no)
			(layer "F.CrtYd")
		)
		(fp_rect
			(start 2.4003 3.9116)
			(end 3.81 -3.9116)
			(stroke
				(width 0)
				(type default)
			)
			(fill no)
			(layer "F.Fab")
		)
		(fp_rect
			(start -3.81 3.9116)
			(end -2.4003 -3.9116)
			(stroke
				(width 0)
				(type default)
			)
			(fill no)
			(layer "F.Fab")
		)
		(fp_rect
			(start -2.4003 4.0386)
			(end 2.4003 -4.0386)
			(stroke
				(width 0)
				(type default)
			)
			(fill no)
			(layer "F.Fab")
		)
		(pad "1" smd rect
			(at 0 -2.9591 90)
			(size 2.413 1.905)
			(layers "F.Cu" "F.Mask" "F.Paste")
			(net "PV_VDDR")
		)
		(pad "2" smd rect
			(at 0 2.9591 90)
			(size 2.413 1.905)
			(layers "F.Cu" "F.Mask" "F.Paste")
			(net "GND")
		)
	)
	(footprint ""
		(layer "F.Cu")
		(at 69.088 -45.3136 90)
		(property "Reference" "R61"
			(at 0 0 90)
			(layer "F.SilkS")
			(hide yes)
			(effects
				(font
					(size 1.27 1.27)
				)
			)
		)
		(property "Value" "0R2J-2-GP"
			(at 0.064008 -3.993896 90)
			(unlocked yes)
			(layer "F.Fab")
			(hide yes)
			(effects
				(font
					(size 1.016 1.016)
					(thickness 0.1524)
				)
			)
		)
		(property "Device Type" "R402H16"
			(at 0.064008 -5.517896 90)
			(unlocked yes)
			(layer "F.Fab")
			(hide yes)
			(effects
				(font
					(size 1.016 1.016)
					(thickness 0.1524)
				)
			)
		)
		(duplicate_pad_numbers_are_jumpers no)
		(fp_rect
			(start -0.381 0.8382)
			(end 0.381 -0.8382)
			(stroke
				(width 0)
				(type default)
			)
			(fill no)
			(layer "F.CrtYd")
		)
		(fp_rect
			(start -0.381 0.8382)
			(end 0.381 -0.8382)
			(stroke
				(width 0)
				(type default)
			)
			(fill no)
			(layer "F.Fab")
		)
		(pad "1" smd custom
			(at 0 -0.4318 90)
			(size 0.127 0.127)
			(layers "F.Cu" "F.Mask" "F.Paste")
			(net "SMBUS_PECI_R_CLK")
			(options
				(clearance outline)
				(anchor circle)
			)
			(primitives
				(gr_poly
					(pts
						(arc
							(start -0.2032 -0.2794)
							(mid -0.239121 -0.264521)
							(end -0.254 -0.2286)
						)
						(arc
							(start -0.254 0.2286)
							(mid -0.239121 0.264521)
							(end -0.2032 0.2794)
						)
						(arc
							(start 0.2032 0.2794)
							(mid 0.239121 0.264521)
							(end 0.254 0.2286)
						)
						(arc
							(start 0.254 -0.2286)
							(mid 0.239121 -0.264521)
							(end 0.2032 -0.2794)
						)
					)
					(width 0)
					(fill yes)
				)
			)
		)
		(pad "2" smd custom
			(at 0 0.4318 90)
			(size 0.127 0.127)
			(layers "F.Cu" "F.Mask" "F.Paste")
			(net "SMBUS_PECI_CLK")
			(options
				(clearance outline)
				(anchor circle)
			)
			(primitives
				(gr_poly
					(pts
						(arc
							(start -0.2032 -0.2794)
							(mid -0.239121 -0.264521)
							(end -0.254 -0.2286)
						)
						(arc
							(start -0.254 0.2286)
							(mid -0.239121 0.264521)
							(end -0.2032 0.2794)
						)
						(arc
							(start 0.2032 0.2794)
							(mid 0.239121 0.264521)
							(end 0.254 0.2286)
						)
						(arc
							(start 0.254 -0.2286)
							(mid 0.239121 -0.264521)
							(end 0.2032 -0.2794)
						)
					)
					(width 0)
					(fill yes)
				)
			)
		)
	)
	(footprint ""
		(layer "F.Cu")
		(at 11.43 -51.7398 90)
		(property "Reference" "C59"
			(at 0 0 90)
			(layer "F.SilkS")
			(hide yes)
			(effects
				(font
					(size 1.27 1.27)
				)
			)
		)
		(property "Value" "SCD1U16V2KX-3GP"
			(at 1.1811 -2.7051 90)
			(unlocked yes)
			(layer "F.Fab")
			(hide yes)
			(effects
				(font
					(size 1.016 1.016)
					(thickness 0.1524)
				)
			)
		)
		(property "Device Type" "C402H22"
			(at 1.1811 -4.2291 90)
			(unlocked yes)
			(layer "F.Fab")
			(hide yes)
			(effects
				(font
					(size 1.016 1.016)
					(thickness 0.1524)
				)
			)
		)
		(duplicate_pad_numbers_are_jumpers no)
		(fp_rect
			(start -0.381 0.7366)
			(end 0.381 -0.7366)
			(stroke
				(width 0)
				(type default)
			)
			(fill no)
			(layer "F.CrtYd")
		)
		(fp_rect
			(start -0.381 0.7366)
			(end 0.381 -0.7366)
			(stroke
				(width 0)
				(type default)
			)
			(fill no)
			(layer "F.Fab")
		)
		(pad "1" smd custom
			(at 0 -0.4572 90)
			(size 0.1143 0.1143)
			(layers "F.Cu" "F.Mask" "F.Paste")
			(net "P2E_CPU_NGFF_TX_DN12")
			(options
				(clearance outline)
				(anchor circle)
			)
			(primitives
				(gr_poly
					(pts
						(arc
							(start -0.254 -0.1778)
							(mid -0.239121 -0.213721)
							(end -0.2032 -0.2286)
						)
						(arc
							(start 0.2032 -0.2286)
							(mid 0.239121 -0.213721)
							(end 0.254 -0.1778)
						)
						(arc
							(start 0.254 0.1778)
							(mid 0.239121 0.213721)
							(end 0.2032 0.2286)
						)
						(arc
							(start -0.2032 0.2286)
							(mid -0.239121 0.213721)
							(end -0.254 0.1778)
						)
					)
					(width 0)
					(fill yes)
				)
			)
		)
		(pad "2" smd custom
			(at 0 0.4572 90)
			(size 0.1143 0.1143)
			(layers "F.Cu" "F.Mask" "F.Paste")
			(net "P2E_CPU_NGFF_C_TX_DN12")
			(options
				(clearance outline)
				(anchor circle)
			)
			(primitives
				(gr_poly
					(pts
						(arc
							(start -0.254 -0.1778)
							(mid -0.239121 -0.213721)
							(end -0.2032 -0.2286)
						)
						(arc
							(start 0.2032 -0.2286)
							(mid 0.239121 -0.213721)
							(end 0.254 -0.1778)
						)
						(arc
							(start 0.254 0.1778)
							(mid 0.239121 0.213721)
							(end 0.2032 0.2286)
						)
						(arc
							(start -0.2032 0.2286)
							(mid -0.239121 0.213721)
							(end -0.254 0.1778)
						)
					)
					(width 0)
					(fill yes)
				)
			)
		)
	)
	(footprint ""
		(layer "F.Cu")
		(at 4.699 -44.45)
		(property "Reference" "R4"
			(at 0 0 0)
			(layer "F.SilkS")
			(hide yes)
			(effects
				(font
					(size 1.27 1.27)
				)
			)
		)
		(property "Value" "0R2J-2-GP"
			(at 0.064008 -3.993896 0)
			(unlocked yes)
			(layer "F.Fab")
			(hide yes)
			(effects
				(font
					(size 1.016 1.016)
					(thickness 0.1524)
				)
			)
		)
		(property "Device Type" "R402H16"
			(at 0.064008 -5.517896 0)
			(unlocked yes)
			(layer "F.Fab")
			(hide yes)
			(effects
				(font
					(size 1.016 1.016)
					(thickness 0.1524)
				)
			)
		)
		(duplicate_pad_numbers_are_jumpers no)
		(fp_rect
			(start -0.381 0.8382)
			(end 0.381 -0.8382)
			(stroke
				(width 0)
				(type default)
			)
			(fill no)
			(layer "F.CrtYd")
		)
		(fp_rect
			(start -0.381 0.8382)
			(end 0.381 -0.8382)
			(stroke
				(width 0)
				(type default)
			)
			(fill no)
			(layer "F.Fab")
		)
		(pad "1" smd custom
			(at 0 -0.4318)
			(size 0.127 0.127)
			(layers "F.Cu" "F.Mask" "F.Paste")
			(net "SMB_HOST_LV_DATA")
			(options
				(clearance outline)
				(anchor circle)
			)
			(primitives
				(gr_poly
					(pts
						(arc
							(start -0.2032 -0.2794)
							(mid -0.239121 -0.264521)
							(end -0.254 -0.2286)
						)
						(arc
							(start -0.254 0.2286)
							(mid -0.239121 0.264521)
							(end -0.2032 0.2794)
						)
						(arc
							(start 0.2032 0.2794)
							(mid 0.239121 0.264521)
							(end 0.254 0.2286)
						)
						(arc
							(start 0.254 -0.2286)
							(mid 0.239121 -0.264521)
							(end 0.2032 -0.2794)
						)
					)
					(width 0)
					(fill yes)
				)
			)
		)
		(pad "2" smd custom
			(at 0 0.4318)
			(size 0.127 0.127)
			(layers "F.Cu" "F.Mask" "F.Paste")
			(net "TEMP_1_DATA")
			(options
				(clearance outline)
				(anchor circle)
			)
			(primitives
				(gr_poly
					(pts
						(arc
							(start -0.2032 -0.2794)
							(mid -0.239121 -0.264521)
							(end -0.254 -0.2286)
						)
						(arc
							(start -0.254 0.2286)
							(mid -0.239121 0.264521)
							(end -0.2032 0.2794)
						)
						(arc
							(start 0.2032 0.2794)
							(mid 0.239121 0.264521)
							(end 0.254 0.2286)
						)
						(arc
							(start 0.254 -0.2286)
							(mid 0.239121 -0.264521)
							(end 0.2032 -0.2794)
						)
					)
					(width 0)
					(fill yes)
				)
			)
		)
	)
	(footprint ""
		(layer "F.Cu")
		(at 65.4558 -63.754 180)
		(property "Reference" "PC136"
			(at 0 0 180)
			(layer "F.SilkS")
			(hide yes)
			(effects
				(font
					(size 1.27 1.27)
				)
			)
		)
		(property "Value" "SC47U6D3V5MX-1-GP"
			(at -0.0762 -6.1214 180)
			(unlocked yes)
			(layer "F.Fab")
			(hide yes)
			(effects
				(font
					(size 1.016 1.016)
					(thickness 0.1524)
				)
			)
		)
		(property "Device Type" "C805H54"
			(at -0.0762 -8.1534 180)
			(unlocked yes)
			(layer "F.Fab")
			(hide yes)
			(effects
				(font
					(size 1.016 1.016)
					(thickness 0.1524)
				)
			)
		)
		(duplicate_pad_numbers_are_jumpers no)
		(fp_line
			(start 0.6096 0)
			(end -0.6096 0)
			(stroke
				(width 0.3048)
				(type default)
			)
			(layer "F.SilkS")
		)
		(fp_poly
			(pts
				(xy -0.9017 1.4351) (xy 0.9017 1.4351) (xy 0.9017 -1.4351) (xy -0.9017 -1.4351)
			)
			(stroke
				(width 0)
				(type default)
			)
			(fill no)
			(layer "F.CrtYd")
		)
		(fp_poly
			(pts
				(xy 0.9017 1.4351) (xy 0.9017 -1.4351) (xy -0.9017 -1.4351) (xy -0.9017 1.4351)
			)
			(stroke
				(width 0)
				(type default)
			)
			(fill no)
			(layer "F.Fab")
		)
		(pad "1" smd rect
			(at 0 -0.8382 180)
			(size 1.5494 0.9398)
			(layers "F.Cu" "F.Mask" "F.Paste")
			(net "PVCCP")
		)
		(pad "2" smd rect
			(at 0 0.8382 180)
			(size 1.5494 0.9398)
			(layers "F.Cu" "F.Mask" "F.Paste")
			(net "GND")
		)
	)
	(footprint ""
		(layer "F.Cu")
		(at 21.9964 -63.373 90)
		(property "Reference" "TP1"
			(at 0 0 90)
			(layer "F.SilkS")
			(hide yes)
			(effects
				(font
					(size 1.27 1.27)
				)
			)
		)
		(property "Value" "TPAD28-1-GP-U"
			(at 0.0508 -1.9304 90)
			(unlocked yes)
			(layer "F.Fab")
			(hide yes)
			(effects
				(font
					(size 1.016 1.016)
					(thickness 0.1524)
				)
			)
		)
		(property "Device Type" "TPAD28-1-U"
			(at 0.0508 -3.4544 90)
			(unlocked yes)
			(layer "F.Fab")
			(hide yes)
			(effects
				(font
					(size 1.016 1.016)
					(thickness 0.1524)
				)
			)
		)
		(duplicate_pad_numbers_are_jumpers no)
		(fp_poly
			(pts
				(arc
					(start 0 0.3556)
					(mid 0 -0.3556)
					(end 0 0.3556)
				)
			)
			(stroke
				(width 0)
				(type default)
			)
			(fill no)
			(layer "F.CrtYd")
		)
		(fp_poly
			(pts
				(arc
					(start 0 0.9525)
					(mid 0 -0.9525)
					(end 0 0.9525)
				)
			)
			(stroke
				(width 0)
				(type default)
			)
			(fill no)
			(layer "F.Fab")
		)
		(pad "1" smd circle
			(at 0 0 90)
			(size 0.7112 0.7112)
			(layers "F.Cu" "F.Mask" "F.Paste")
			(net "VR_PVNN_NTC")
		)
	)
	(footprint ""
		(layer "F.Cu")
		(at 47.117 -22.733 180)
		(property "Reference" "R480"
			(at 0 0 180)
			(layer "F.SilkS")
			(hide yes)
			(effects
				(font
					(size 1.27 1.27)
				)
			)
		)
		(property "Value" "4K7R2F-GP"
			(at 1.7907 -1.1176 180)
			(unlocked yes)
			(layer "F.Fab")
			(hide yes)
			(effects
				(font
					(size 1.016 1.016)
					(thickness 0.1524)
				)
			)
		)
		(property "Device Type" "R402H16"
			(at 1.7907 -2.6416 180)
			(unlocked yes)
			(layer "F.Fab")
			(hide yes)
			(effects
				(font
					(size 1.016 1.016)
					(thickness 0.1524)
				)
			)
		)
		(duplicate_pad_numbers_are_jumpers no)
		(fp_rect
			(start -0.381 0.8382)
			(end 0.381 -0.8382)
			(stroke
				(width 0)
				(type default)
			)
			(fill no)
			(layer "F.CrtYd")
		)
		(fp_rect
			(start -0.381 0.8382)
			(end 0.381 -0.8382)
			(stroke
				(width 0)
				(type default)
			)
			(fill no)
			(layer "F.Fab")
		)
		(pad "1" smd custom
			(at 0 -0.4318 180)
			(size 0.127 0.127)
			(layers "F.Cu" "F.Mask" "F.Paste")
			(net "P3V3_STBY")
			(options
				(clearance outline)
				(anchor circle)
			)
			(primitives
				(gr_poly
					(pts
						(arc
							(start -0.2032 -0.2794)
							(mid -0.239121 -0.264521)
							(end -0.254 -0.2286)
						)
						(arc
							(start -0.254 0.2286)
							(mid -0.239121 0.264521)
							(end -0.2032 0.2794)
						)
						(arc
							(start 0.2032 0.2794)
							(mid 0.239121 0.264521)
							(end 0.254 0.2286)
						)
						(arc
							(start 0.254 -0.2286)
							(mid 0.239121 -0.264521)
							(end 0.2032 -0.2794)
						)
					)
					(width 0)
					(fill yes)
				)
			)
		)
		(pad "2" smd custom
			(at 0 0.4318 180)
			(size 0.127 0.127)
			(layers "F.Cu" "F.Mask" "F.Paste")
			(net "BMC_PWRBTN#")
			(options
				(clearance outline)
				(anchor circle)
			)
			(primitives
				(gr_poly
					(pts
						(arc
							(start -0.2032 -0.2794)
							(mid -0.239121 -0.264521)
							(end -0.254 -0.2286)
						)
						(arc
							(start -0.254 0.2286)
							(mid -0.239121 0.264521)
							(end -0.2032 0.2794)
						)
						(arc
							(start 0.2032 0.2794)
							(mid 0.239121 0.264521)
							(end 0.254 0.2286)
						)
						(arc
							(start 0.254 -0.2286)
							(mid 0.239121 -0.264521)
							(end 0.2032 -0.2794)
						)
					)
					(width 0)
					(fill yes)
				)
			)
		)
	)
	(footprint ""
		(layer "F.Cu")
		(at 189.256416 -33.975802 90)
		(property "Reference" "PU10"
			(at 0 0 90)
			(layer "F.SilkS")
			(hide yes)
			(effects
				(font
					(size 1.27 1.27)
				)
			)
		)
		(property "Value" "ISL6353CRTZ-GP-U"
			(at -4.1783 -7.4422 90)
			(unlocked yes)
			(layer "F.Fab")
			(hide yes)
			(effects
				(font
					(size 1.016 1.016)
					(thickness 0.1524)
				)
			)
		)
		(property "Device Type" "QFN40-G3D5H32"
			(at -4.1783 -8.9662 90)
			(unlocked yes)
			(layer "F.Fab")
			(hide yes)
			(effects
				(font
					(size 1.016 1.016)
					(thickness 0.1524)
				)
			)
		)
		(duplicate_pad_numbers_are_jumpers no)
		(fp_poly
			(pts
				(xy 2.0574 -2.8829) (xy 2.8829 -2.8829) (xy 2.8829 -2.0574)
			)
			(stroke
				(width 0)
				(type default)
			)
			(fill yes)
			(layer "F.SilkS")
		)
		(fp_rect
			(start -2.8829 2.8829)
			(end 2.8829 -2.8829)
			(stroke
				(width 0)
				(type default)
			)
			(fill no)
			(layer "F.CrtYd")
		)
		(fp_rect
			(start -2.8829 2.8829)
			(end 2.8829 -2.8829)
			(stroke
				(width 0)
				(type default)
			)
			(fill no)
			(layer "F.Fab")
		)
		(pad "1" smd rect
			(at 1.800098 -2.4003 90)
			(size 0.2032 0.6604)
			(drill
				(offset 0 -0.0254)
			)
			(layers "F.Cu" "F.Mask" "F.Paste")
			(net "SVID_DIO_A")
		)
		(pad "2" smd rect
			(at 1.400048 -2.4003 90)
			(size 0.2032 0.7112)
			(layers "F.Cu" "F.Mask" "F.Paste")
			(net "SVID_A_ALERT#")
		)
		(pad "3" smd rect
			(at 0.999998 -2.4003 90)
			(size 0.2032 0.7112)
			(layers "F.Cu" "F.Mask" "F.Paste")
			(net "SVID_CLK_A")
		)
		(pad "4" smd rect
			(at 0.599948 -2.4003 90)
			(size 0.2032 0.7112)
			(layers "F.Cu" "F.Mask" "F.Paste")
			(net "VR_PWREN_PVDDR_A")
		)
		(pad "5" smd rect
			(at 0.199898 -2.4003 90)
			(size 0.2032 0.7112)
			(layers "F.Cu" "F.Mask" "F.Paste")
			(net "PWRGD_PVDDR_PG")
		)
		(pad "6" smd rect
			(at -0.199898 -2.4003 90)
			(size 0.2032 0.7112)
			(layers "F.Cu" "F.Mask" "F.Paste")
			(net "VR_PVDDR_A_IMON")
		)
		(pad "7" smd rect
			(at -0.599948 -2.4003 90)
			(size 0.2032 0.7112)
			(layers "F.Cu" "F.Mask" "F.Paste")
			(net "VR_PVDDR_PNN_VRHOT#")
		)
		(pad "8" smd rect
			(at -0.999998 -2.4003 90)
			(size 0.2032 0.7112)
			(layers "F.Cu" "F.Mask" "F.Paste")
			(net "VR_PVDDR_A_NTC")
		)
		(pad "9" smd rect
			(at -1.400048 -2.4003 90)
			(size 0.2032 0.7112)
			(layers "F.Cu" "F.Mask" "F.Paste")
			(net "VR_PVDDR_A_VW")
		)
		(pad "10" smd rect
			(at -1.800098 -2.4003 90)
			(size 0.2032 0.6604)
			(drill
				(offset 0 -0.0254)
			)
			(layers "F.Cu" "F.Mask" "F.Paste")
			(net "VR_PVDDR_A_COMP")
		)
		(pad "11" smd rect
			(at -2.4003 -1.800098 90)
			(size 0.6604 0.2032)
			(drill
				(offset -0.0254 0)
			)
			(layers "F.Cu" "F.Mask" "F.Paste")
			(net "VR_PVDDR_A_FB")
		)
		(pad "12" smd rect
			(at -2.4003 -1.400048 90)
			(size 0.7112 0.2032)
			(layers "F.Cu" "F.Mask" "F.Paste")
			(net "Net_320")
		)
		(pad "13" smd rect
			(at -2.4003 -0.999998 90)
			(size 0.7112 0.2032)
			(layers "F.Cu" "F.Mask" "F.Paste")
			(net "Net_321")
		)
		(pad "14" smd rect
			(at -2.4003 -0.599948 90)
			(size 0.7112 0.2032)
			(layers "F.Cu" "F.Mask" "F.Paste")
			(net "VR_PVDDR_A_ISEN2")
		)
		(pad "15" smd rect
			(at -2.4003 -0.199898 90)
			(size 0.7112 0.2032)
			(layers "F.Cu" "F.Mask" "F.Paste")
			(net "ISENSE_PVDDR_A_ISEN1")
		)
		(pad "16" smd rect
			(at -2.4003 0.199898 90)
			(size 0.7112 0.2032)
			(layers "F.Cu" "F.Mask" "F.Paste")
			(net "VR_PVDDR_A_VSEN")
		)
		(pad "17" smd rect
			(at -2.4003 0.599948 90)
			(size 0.7112 0.2032)
			(layers "F.Cu" "F.Mask" "F.Paste")
			(net "VSENSE_PVDDR_A_VRTN")
		)
		(pad "18" smd rect
			(at -2.4003 0.999998 90)
			(size 0.7112 0.2032)
			(layers "F.Cu" "F.Mask" "F.Paste")
			(net "VR_PVDDR_A_SUMN")
		)
		(pad "19" smd rect
			(at -2.4003 1.400048 90)
			(size 0.7112 0.2032)
			(layers "F.Cu" "F.Mask" "F.Paste")
			(net "VR_PVDDRA_ISUMP1")
		)
		(pad "20" smd rect
			(at -2.4003 1.800098 90)
			(size 0.6604 0.2032)
			(drill
				(offset -0.0254 0)
			)
			(layers "F.Cu" "F.Mask" "F.Paste")
			(net "VR_PVDDR_A_VDD")
		)
		(pad "21" smd rect
			(at -1.800098 2.4003 90)
			(size 0.2032 0.6604)
			(drill
				(offset 0 0.0254)
			)
			(layers "F.Cu" "F.Mask" "F.Paste")
			(net "VR_PVDDR_A_VIN")
		)
		(pad "22" smd rect
			(at -1.400048 2.4003 90)
			(size 0.2032 0.7112)
			(layers "F.Cu" "F.Mask" "F.Paste")
			(net "VR_PVDDR_A_PROG1")
		)
		(pad "23" smd rect
			(at -0.999998 2.4003 90)
			(size 0.2032 0.7112)
			(layers "F.Cu" "F.Mask" "F.Paste")
			(net "VR_PVDDR_A_BOOT1")
		)
		(pad "24" smd rect
			(at -0.599948 2.4003 90)
			(size 0.2032 0.7112)
			(layers "F.Cu" "F.Mask" "F.Paste")
			(net "VR_PVDDR_A_GH1")
		)
		(pad "25" smd rect
			(at -0.199898 2.4003 90)
			(size 0.2032 0.7112)
			(layers "F.Cu" "F.Mask" "F.Paste")
			(net "VR_PVDDR_A_PHASE1")
		)
		(pad "26" smd rect
			(at 0.199898 2.4003 90)
			(size 0.2032 0.7112)
			(layers "F.Cu" "F.Mask" "F.Paste")
			(net "GND")
		)
		(pad "27" smd rect
			(at 0.599948 2.4003 90)
			(size 0.2032 0.7112)
			(layers "F.Cu" "F.Mask" "F.Paste")
			(net "VR_PVDDR_A_GL1")
		)
		(pad "28" smd rect
			(at 0.999998 2.4003 90)
			(size 0.2032 0.7112)
			(layers "F.Cu" "F.Mask" "F.Paste")
			(net "VR_PVDDR_A_PWM3")
		)
		(pad "29" smd rect
			(at 1.400048 2.4003 90)
			(size 0.2032 0.7112)
			(layers "F.Cu" "F.Mask" "F.Paste")
			(net "VR_PVDDR_A_VDDP")
		)
		(pad "30" smd rect
			(at 1.800098 2.4003 90)
			(size 0.2032 0.6604)
			(drill
				(offset 0 0.0254)
			)
			(layers "F.Cu" "F.Mask" "F.Paste")
			(net "Net_316")
		)
		(pad "31" smd rect
			(at 2.4003 1.800098 90)
			(size 0.6604 0.2032)
			(drill
				(offset 0.0254 0)
			)
			(layers "F.Cu" "F.Mask" "F.Paste")
			(net "GND")
		)
		(pad "32" smd rect
			(at 2.4003 1.400048 90)
			(size 0.7112 0.2032)
			(layers "F.Cu" "F.Mask" "F.Paste")
			(net "Net_318")
		)
		(pad "33" smd rect
			(at 2.4003 0.999998 90)
			(size 0.7112 0.2032)
			(layers "F.Cu" "F.Mask" "F.Paste")
			(net "Net_319")
		)
		(pad "34" smd rect
			(at 2.4003 0.599948 90)
			(size 0.7112 0.2032)
			(layers "F.Cu" "F.Mask" "F.Paste")
			(net "Net_317")
		)
		(pad "35" smd rect
			(at 2.4003 0.199898 90)
			(size 0.7112 0.2032)
			(layers "F.Cu" "F.Mask" "F.Paste")
			(net "VR_PVDDR_A_PROG2")
		)
		(pad "36" smd rect
			(at 2.4003 -0.199898 90)
			(size 0.7112 0.2032)
			(layers "F.Cu" "F.Mask" "F.Paste")
			(net "VR_PVDDR_A_PSI")
		)
		(pad "37" smd rect
			(at 2.4003 -0.599948 90)
			(size 0.7112 0.2032)
			(layers "F.Cu" "F.Mask" "F.Paste")
			(net "VR_PVDDR_A_VAUTO")
		)
		(pad "38" smd rect
			(at 2.4003 -0.999998 90)
			(size 0.7112 0.2032)
			(layers "F.Cu" "F.Mask" "F.Paste")
			(net "VR_PVDDR_A_IAUTO")
		)
		(pad "39" smd rect
			(at 2.4003 -1.400048 90)
			(size 0.7112 0.2032)
			(layers "F.Cu" "F.Mask" "F.Paste")
			(net "VR_PVDDR_A_OCP")
		)
		(pad "40" smd rect
			(at 2.4003 -1.800098 90)
			(size 0.6604 0.2032)
			(drill
				(offset 0.0254 0)
			)
			(layers "F.Cu" "F.Mask" "F.Paste")
			(net "VR_PVDDR_A_SVID_ADDR")
		)
		(pad "41" smd rect
			(at 0 0 90)
			(size 3.5052 3.5052)
			(layers "F.Cu" "F.Mask" "F.Paste")
			(net "GND")
		)
	)
	(footprint ""
		(layer "F.Cu")
		(at 28.321 -25.781)
		(property "Reference" "PTC1"
			(at 0 0 0)
			(layer "F.SilkS")
			(hide yes)
			(effects
				(font
					(size 1.27 1.27)
				)
			)
		)
		(property "Value" "SE470UF2VDM-GP"
			(at -3.220466 1.242822 0)
			(unlocked yes)
			(layer "F.Fab")
			(hide yes)
			(effects
				(font
					(size 1.016 1.016)
					(thickness 0.1524)
				)
			)
		)
		(property "Device Type" "CT7343H83"
			(at -3.220466 -0.281178 0)
			(unlocked yes)
			(layer "F.Fab")
			(hide yes)
			(effects
				(font
					(size 1.016 1.016)
					(thickness 0.1524)
				)
			)
		)
		(duplicate_pad_numbers_are_jumpers no)
		(fp_line
			(start -2.206752 -4.2926)
			(end 2.155698 -4.2926)
			(stroke
				(width 0.508)
				(type default)
			)
			(layer "F.SilkS")
		)
		(fp_rect
			(start -2.1463 3.6449)
			(end 2.1463 -3.6449)
			(stroke
				(width 0)
				(type default)
			)
			(fill no)
			(layer "F.CrtYd")
		)
		(fp_poly
			(pts
				(xy -3.81 3.9116) (xy -3.81 -3.9116) (xy -2.54 -3.9116) (xy -2.4003 -3.9116) (xy -2.4003 -4.0386)
				(xy 2.4003 -4.0386) (xy 2.4003 -3.9116) (xy 2.54 -3.9116) (xy 2.5654 -3.9116) (xy 3.81 -3.9116)
				(xy 3.81 -1.6256) (xy 2.1463 -1.6256) (xy 2.1463 -3.6449) (xy -2.1463 -3.6449) (xy -2.1463 3.6449)
				(xy 2.1463 3.6449) (xy 2.1463 -1.6129) (xy 3.81 -1.6129) (xy 3.81 3.9116) (xy 2.4003 3.9116) (xy 2.4003 3.9243)
				(xy 2.4003 4.0386) (xy -2.4003 4.0386) (xy -2.4003 3.9116)
			)
			(stroke
				(width 0)
				(type default)
			)
			(fill no)
			(layer "F.CrtYd")
		)
		(fp_rect
			(start -3.81 3.9116)
			(end -2.4003 -3.9116)
			(stroke
				(width 0)
				(type default)
			)
			(fill no)
			(layer "F.Fab")
		)
		(fp_rect
			(start -2.4003 4.0386)
			(end 2.4003 -4.0386)
			(stroke
				(width 0)
				(type default)
			)
			(fill no)
			(layer "F.Fab")
		)
		(fp_rect
			(start 2.4003 3.9116)
			(end 3.81 -3.9116)
			(stroke
				(width 0)
				(type default)
			)
			(fill no)
			(layer "F.Fab")
		)
		(pad "1" smd rect
			(at 0 -2.9591)
			(size 2.413 1.905)
			(layers "F.Cu" "F.Mask" "F.Paste")
			(net "P1V0")
		)
		(pad "2" smd rect
			(at 0 2.9591)
			(size 2.413 1.905)
			(layers "F.Cu" "F.Mask" "F.Paste")
			(net "GND")
		)
	)
	(footprint ""
		(layer "F.Cu")
		(at 49.7078 -54.6481 -90)
		(property "Reference" "L1"
			(at 0 0 270)
			(layer "F.SilkS")
			(hide yes)
			(effects
				(font
					(size 1.27 1.27)
				)
			)
		)
		(property "Value" "BLM18PG330SN1D-GP"
			(at -0.0254 -2.0193 270)
			(unlocked yes)
			(layer "F.Fab")
			(hide yes)
			(effects
				(font
					(size 1.016 1.016)
					(thickness 0.1524)
				)
			)
		)
		(property "Device Type" "L1608-UH38"
			(at -0.0254 -3.5433 270)
			(unlocked yes)
			(layer "F.Fab")
			(hide yes)
			(effects
				(font
					(size 1.016 1.016)
					(thickness 0.1524)
				)
			)
		)
		(duplicate_pad_numbers_are_jumpers no)
		(fp_line
			(start -0.4064 0)
			(end 0.4064 0)
			(stroke
				(width 0.2032)
				(type default)
			)
			(layer "F.SilkS")
		)
		(fp_rect
			(start -0.635 1.1811)
			(end 0.635 -1.1811)
			(stroke
				(width 0)
				(type default)
			)
			(fill no)
			(layer "F.CrtYd")
		)
		(fp_rect
			(start -0.635 1.1811)
			(end 0.635 -1.1811)
			(stroke
				(width 0)
				(type default)
			)
			(fill no)
			(layer "F.Fab")
		)
		(pad "1" smd custom
			(at 0 -0.6604 270)
			(size 0.19685 0.19685)
			(layers "F.Cu" "F.Mask" "F.Paste")
			(net "P3V3_STBY")
			(options
				(clearance outline)
				(anchor circle)
			)
			(primitives
				(gr_poly
					(pts
						(arc
							(start 0.508 -0.2921)
							(mid 0.478242 -0.363942)
							(end 0.4064 -0.3937)
						)
						(arc
							(start -0.4064 -0.3937)
							(mid -0.478242 -0.363942)
							(end -0.508 -0.2921)
						)
						(arc
							(start -0.508 0.2921)
							(mid -0.478242 0.363942)
							(end -0.4064 0.3937)
						)
						(arc
							(start 0.4064 0.3937)
							(mid 0.478242 0.363942)
							(end 0.508 0.2921)
						)
					)
					(width 0)
					(fill yes)
				)
			)
		)
		(pad "2" smd custom
			(at 0 0.6604 270)
			(size 0.19685 0.19685)
			(layers "F.Cu" "F.Mask" "F.Paste")
			(net "P3V3_CLK_R_VDD25")
			(options
				(clearance outline)
				(anchor circle)
			)
			(primitives
				(gr_poly
					(pts
						(arc
							(start 0.508 -0.2921)
							(mid 0.478242 -0.363942)
							(end 0.4064 -0.3937)
						)
						(arc
							(start -0.4064 -0.3937)
							(mid -0.478242 -0.363942)
							(end -0.508 -0.2921)
						)
						(arc
							(start -0.508 0.2921)
							(mid -0.478242 0.363942)
							(end -0.4064 0.3937)
						)
						(arc
							(start 0.4064 0.3937)
							(mid 0.478242 0.363942)
							(end 0.508 0.2921)
						)
					)
					(width 0)
					(fill yes)
				)
			)
		)
	)
	(footprint ""
		(layer "F.Cu")
		(at 31.877 -35.0012 -90)
		(property "Reference" "R269"
			(at 0 0 270)
			(layer "F.SilkS")
			(hide yes)
			(effects
				(font
					(size 1.27 1.27)
				)
			)
		)
		(property "Value" "51R2F-2-GP"
			(at 0.064008 -3.993896 270)
			(unlocked yes)
			(layer "F.Fab")
			(hide yes)
			(effects
				(font
					(size 1.016 1.016)
					(thickness 0.1524)
				)
			)
		)
		(property "Device Type" "R402H16"
			(at 0.064008 -5.517896 270)
			(unlocked yes)
			(layer "F.Fab")
			(hide yes)
			(effects
				(font
					(size 1.016 1.016)
					(thickness 0.1524)
				)
			)
		)
		(duplicate_pad_numbers_are_jumpers no)
		(fp_rect
			(start -0.381 0.8382)
			(end 0.381 -0.8382)
			(stroke
				(width 0)
				(type default)
			)
			(fill no)
			(layer "F.CrtYd")
		)
		(fp_rect
			(start -0.381 0.8382)
			(end 0.381 -0.8382)
			(stroke
				(width 0)
				(type default)
			)
			(fill no)
			(layer "F.Fab")
		)
		(pad "1" smd custom
			(at 0 -0.4318 270)
			(size 0.127 0.127)
			(layers "F.Cu" "F.Mask" "F.Paste")
			(net "XDP_SOC_CPU_TRST#")
			(options
				(clearance outline)
				(anchor circle)
			)
			(primitives
				(gr_poly
					(pts
						(arc
							(start -0.2032 -0.2794)
							(mid -0.239121 -0.264521)
							(end -0.254 -0.2286)
						)
						(arc
							(start -0.254 0.2286)
							(mid -0.239121 0.264521)
							(end -0.2032 0.2794)
						)
						(arc
							(start 0.2032 0.2794)
							(mid 0.239121 0.264521)
							(end 0.254 0.2286)
						)
						(arc
							(start 0.254 -0.2286)
							(mid 0.239121 -0.264521)
							(end 0.2032 -0.2794)
						)
					)
					(width 0)
					(fill yes)
				)
			)
		)
		(pad "2" smd custom
			(at 0 0.4318 270)
			(size 0.127 0.127)
			(layers "F.Cu" "F.Mask" "F.Paste")
			(net "GND")
			(options
				(clearance outline)
				(anchor circle)
			)
			(primitives
				(gr_poly
					(pts
						(arc
							(start -0.2032 -0.2794)
							(mid -0.239121 -0.264521)
							(end -0.254 -0.2286)
						)
						(arc
							(start -0.254 0.2286)
							(mid -0.239121 0.264521)
							(end -0.2032 0.2794)
						)
						(arc
							(start 0.2032 0.2794)
							(mid 0.239121 0.264521)
							(end 0.254 0.2286)
						)
						(arc
							(start 0.254 -0.2286)
							(mid 0.239121 -0.264521)
							(end 0.2032 -0.2794)
						)
					)
					(width 0)
					(fill yes)
				)
			)
		)
	)
	(footprint ""
		(layer "F.Cu")
		(at 47.625 -16.0782 180)
		(property "Reference" "R346"
			(at 0 0 180)
			(layer "F.SilkS")
			(hide yes)
			(effects
				(font
					(size 1.27 1.27)
				)
			)
		)
		(property "Value" "4K7R2F-GP"
			(at 0.064008 -3.993896 180)
			(unlocked yes)
			(layer "F.Fab")
			(hide yes)
			(effects
				(font
					(size 1.016 1.016)
					(thickness 0.1524)
				)
			)
		)
		(property "Device Type" "R402H16"
			(at 0.064008 -5.517896 180)
			(unlocked yes)
			(layer "F.Fab")
			(hide yes)
			(effects
				(font
					(size 1.016 1.016)
					(thickness 0.1524)
				)
			)
		)
		(duplicate_pad_numbers_are_jumpers no)
		(fp_rect
			(start -0.381 0.8382)
			(end 0.381 -0.8382)
			(stroke
				(width 0)
				(type default)
			)
			(fill no)
			(layer "F.CrtYd")
		)
		(fp_rect
			(start -0.381 0.8382)
			(end 0.381 -0.8382)
			(stroke
				(width 0)
				(type default)
			)
			(fill no)
			(layer "F.Fab")
		)
		(pad "1" smd custom
			(at 0 -0.4318 180)
			(size 0.127 0.127)
			(layers "F.Cu" "F.Mask" "F.Paste")
			(net "P3V3")
			(options
				(clearance outline)
				(anchor circle)
			)
			(primitives
				(gr_poly
					(pts
						(arc
							(start -0.2032 -0.2794)
							(mid -0.239121 -0.264521)
							(end -0.254 -0.2286)
						)
						(arc
							(start -0.254 0.2286)
							(mid -0.239121 0.264521)
							(end -0.2032 0.2794)
						)
						(arc
							(start 0.2032 0.2794)
							(mid 0.239121 0.264521)
							(end 0.254 0.2286)
						)
						(arc
							(start 0.254 -0.2286)
							(mid 0.239121 -0.264521)
							(end 0.2032 -0.2794)
						)
					)
					(width 0)
					(fill yes)
				)
			)
		)
		(pad "2" smd custom
			(at 0 0.4318 180)
			(size 0.127 0.127)
			(layers "F.Cu" "F.Mask" "F.Paste")
			(net "CLKBUFF_OE1#")
			(options
				(clearance outline)
				(anchor circle)
			)
			(primitives
				(gr_poly
					(pts
						(arc
							(start -0.2032 -0.2794)
							(mid -0.239121 -0.264521)
							(end -0.254 -0.2286)
						)
						(arc
							(start -0.254 0.2286)
							(mid -0.239121 0.264521)
							(end -0.2032 0.2794)
						)
						(arc
							(start 0.2032 0.2794)
							(mid 0.239121 0.264521)
							(end 0.254 0.2286)
						)
						(arc
							(start 0.254 -0.2286)
							(mid 0.239121 -0.264521)
							(end 0.2032 -0.2794)
						)
					)
					(width 0)
					(fill yes)
				)
			)
		)
	)
	(footprint ""
		(layer "F.Cu")
		(at 185.76036 -18.69821 180)
		(property "Reference" "PU12"
			(at 0 0 180)
			(layer "F.SilkS")
			(hide yes)
			(effects
				(font
					(size 1.27 1.27)
				)
			)
		)
		(property "Value" "TPS51200-GP-U1"
			(at 2.9083 1.397 180)
			(unlocked yes)
			(layer "F.Fab")
			(hide yes)
			(effects
				(font
					(size 1.016 1.016)
					(thickness 0.1524)
				)
			)
		)
		(property "Device Type" "QFN10-G4H40"
			(at 2.9083 -0.127 180)
			(unlocked yes)
			(layer "F.Fab")
			(hide yes)
			(effects
				(font
					(size 1.016 1.016)
					(thickness 0.1524)
				)
			)
		)
		(duplicate_pad_numbers_are_jumpers no)
		(fp_poly
			(pts
				(xy 1.0287 -2.0066) (xy 1.27 -2.2479) (xy 0.7874 -2.2479)
			)
			(stroke
				(width 0)
				(type default)
			)
			(fill yes)
			(layer "F.SilkS")
		)
		(fp_rect
			(start -1.7526 2.0066)
			(end 1.7526 -2.0066)
			(stroke
				(width 0)
				(type default)
			)
			(fill no)
			(layer "F.CrtYd")
		)
		(fp_rect
			(start -1.7526 2.0066)
			(end 1.7526 -2.0066)
			(stroke
				(width 0)
				(type default)
			)
			(fill no)
			(layer "F.Fab")
		)
		(pad "1" smd rect
			(at 0.999998 -1.4605 180)
			(size 0.3048 0.8382)
			(layers "F.Cu" "F.Mask" "F.Paste")
			(net "PV_VTT_DDR_B_REFIN")
		)
		(pad "2" smd rect
			(at 0.500126 -1.4605 180)
			(size 0.3048 0.8382)
			(layers "F.Cu" "F.Mask" "F.Paste")
			(net "PV_VDDR")
		)
		(pad "3" smd rect
			(at 0 -1.4605 180)
			(size 0.3048 0.8382)
			(layers "F.Cu" "F.Mask" "F.Paste")
			(net "PV_VTT_DDR_B")
		)
		(pad "4" smd rect
			(at -0.500126 -1.4605 180)
			(size 0.3048 0.8382)
			(layers "F.Cu" "F.Mask" "F.Paste")
			(net "GND")
		)
		(pad "5" smd rect
			(at -0.999998 -1.4605 180)
			(size 0.3048 0.8382)
			(layers "F.Cu" "F.Mask" "F.Paste")
			(net "PV_VTT_DDR_B_SNS")
		)
		(pad "6" smd rect
			(at -0.999998 1.4605 180)
			(size 0.3048 0.8382)
			(layers "F.Cu" "F.Mask" "F.Paste")
			(net "PV_VTT_DDR_B_REFO")
		)
		(pad "7" smd rect
			(at -0.500126 1.4605 180)
			(size 0.3048 0.8382)
			(layers "F.Cu" "F.Mask" "F.Paste")
			(net "PV_VTT_DDR_B_EN")
		)
		(pad "8" smd rect
			(at 0 1.4605 180)
			(size 0.3048 0.8382)
			(layers "F.Cu" "F.Mask" "F.Paste")
			(net "GND")
		)
		(pad "9" smd rect
			(at 0.500126 1.4605 180)
			(size 0.3048 0.8382)
			(layers "F.Cu" "F.Mask" "F.Paste")
			(net "PV_VTT_DDR_B_R_PG")
		)
		(pad "10" smd rect
			(at 0.999998 1.4605 180)
			(size 0.3048 0.8382)
			(layers "F.Cu" "F.Mask" "F.Paste")
			(net "PV_VTT_DDR_B_VIN")
		)
		(pad "11" smd rect
			(at 0 0 180)
			(size 2.9972 1.6764)
			(layers "F.Cu" "F.Mask" "F.Paste")
			(net "GND")
		)
	)
	(footprint ""
		(layer "F.Cu")
		(at 100.6094 -67.5894 -90)
		(property "Reference" "PR9"
			(at 0 0 270)
			(layer "F.SilkS")
			(hide yes)
			(effects
				(font
					(size 1.27 1.27)
				)
			)
		)
		(property "Value" "10KR2F-2-GP"
			(at 0.064008 -3.993896 270)
			(unlocked yes)
			(layer "F.Fab")
			(hide yes)
			(effects
				(font
					(size 1.016 1.016)
					(thickness 0.1524)
				)
			)
		)
		(property "Device Type" "R402H16"
			(at 0.064008 -5.517896 270)
			(unlocked yes)
			(layer "F.Fab")
			(hide yes)
			(effects
				(font
					(size 1.016 1.016)
					(thickness 0.1524)
				)
			)
		)
		(duplicate_pad_numbers_are_jumpers no)
		(fp_rect
			(start -0.381 0.8382)
			(end 0.381 -0.8382)
			(stroke
				(width 0)
				(type default)
			)
			(fill no)
			(layer "F.CrtYd")
		)
		(fp_rect
			(start -0.381 0.8382)
			(end 0.381 -0.8382)
			(stroke
				(width 0)
				(type default)
			)
			(fill no)
			(layer "F.Fab")
		)
		(pad "1" smd custom
			(at 0 -0.4318 270)
			(size 0.127 0.127)
			(layers "F.Cu" "F.Mask" "F.Paste")
			(net "P3V3_STBY")
			(options
				(clearance outline)
				(anchor circle)
			)
			(primitives
				(gr_poly
					(pts
						(arc
							(start -0.2032 -0.2794)
							(mid -0.239121 -0.264521)
							(end -0.254 -0.2286)
						)
						(arc
							(start -0.254 0.2286)
							(mid -0.239121 0.264521)
							(end -0.2032 0.2794)
						)
						(arc
							(start 0.2032 0.2794)
							(mid 0.239121 0.264521)
							(end 0.254 0.2286)
						)
						(arc
							(start 0.254 -0.2286)
							(mid 0.239121 -0.264521)
							(end 0.2032 -0.2794)
						)
					)
					(width 0)
					(fill yes)
				)
			)
		)
		(pad "2" smd custom
			(at 0 0.4318 270)
			(size 0.127 0.127)
			(layers "F.Cu" "F.Mask" "F.Paste")
			(net "VR_P1V1_EN")
			(options
				(clearance outline)
				(anchor circle)
			)
			(primitives
				(gr_poly
					(pts
						(arc
							(start -0.2032 -0.2794)
							(mid -0.239121 -0.264521)
							(end -0.254 -0.2286)
						)
						(arc
							(start -0.254 0.2286)
							(mid -0.239121 0.264521)
							(end -0.2032 0.2794)
						)
						(arc
							(start 0.2032 0.2794)
							(mid 0.239121 0.264521)
							(end 0.254 0.2286)
						)
						(arc
							(start 0.254 -0.2286)
							(mid 0.239121 -0.264521)
							(end 0.2032 -0.2794)
						)
					)
					(width 0)
					(fill yes)
				)
			)
		)
	)
	(footprint ""
		(layer "F.Cu")
		(at 44.323 -54.229 -90)
		(property "Reference" "PC34"
			(at 0 0 270)
			(layer "F.SilkS")
			(hide yes)
			(effects
				(font
					(size 1.27 1.27)
				)
			)
		)
		(property "Value" "SC3300P50V3KX-1GP"
			(at -0.0254 -2.0193 270)
			(unlocked yes)
			(layer "F.Fab")
			(hide yes)
			(effects
				(font
					(size 1.016 1.016)
					(thickness 0.1524)
				)
			)
		)
		(property "Device Type" "C603H36"
			(at -0.0254 -3.5433 270)
			(unlocked yes)
			(layer "F.Fab")
			(hide yes)
			(effects
				(font
					(size 1.016 1.016)
					(thickness 0.1524)
				)
			)
		)
		(duplicate_pad_numbers_are_jumpers no)
		(fp_line
			(start -0.4064 0)
			(end 0.4064 0)
			(stroke
				(width 0.2286)
				(type default)
			)
			(layer "F.SilkS")
		)
		(fp_rect
			(start -0.635 1.1811)
			(end 0.635 -1.1811)
			(stroke
				(width 0)
				(type default)
			)
			(fill no)
			(layer "F.CrtYd")
		)
		(fp_rect
			(start -0.635 1.1811)
			(end 0.635 -1.1811)
			(stroke
				(width 0)
				(type default)
			)
			(fill no)
			(layer "F.Fab")
		)
		(pad "1" smd custom
			(at 0 -0.6604 270)
			(size 0.19685 0.19685)
			(layers "F.Cu" "F.Mask" "F.Paste")
			(net "VR_PVCCP_PWM_OUT")
			(options
				(clearance outline)
				(anchor circle)
			)
			(primitives
				(gr_poly
					(pts
						(arc
							(start 0.508 -0.2921)
							(mid 0.478242 -0.363942)
							(end 0.4064 -0.3937)
						)
						(arc
							(start -0.4064 -0.3937)
							(mid -0.478242 -0.363942)
							(end -0.508 -0.2921)
						)
						(arc
							(start -0.508 0.2921)
							(mid -0.478242 0.363942)
							(end -0.4064 0.3937)
						)
						(arc
							(start 0.4064 0.3937)
							(mid 0.478242 0.363942)
							(end 0.508 0.2921)
						)
					)
					(width 0)
					(fill yes)
				)
			)
		)
		(pad "2" smd custom
			(at 0 0.6604 270)
			(size 0.19685 0.19685)
			(layers "F.Cu" "F.Mask" "F.Paste")
			(net "VR_PVCCP_VSW_R")
			(options
				(clearance outline)
				(anchor circle)
			)
			(primitives
				(gr_poly
					(pts
						(arc
							(start 0.508 -0.2921)
							(mid 0.478242 -0.363942)
							(end 0.4064 -0.3937)
						)
						(arc
							(start -0.4064 -0.3937)
							(mid -0.478242 -0.363942)
							(end -0.508 -0.2921)
						)
						(arc
							(start -0.508 0.2921)
							(mid -0.478242 0.363942)
							(end -0.4064 0.3937)
						)
						(arc
							(start 0.4064 0.3937)
							(mid 0.478242 0.363942)
							(end 0.508 0.2921)
						)
					)
					(width 0)
					(fill yes)
				)
			)
		)
	)
	(footprint ""
		(layer "F.Cu")
		(at 45.8724 -32.4358 -90)
		(property "Reference" "C115"
			(at 0 0 270)
			(layer "F.SilkS")
			(hide yes)
			(effects
				(font
					(size 1.27 1.27)
				)
			)
		)
		(property "Value" "SCD1U16V2KX-3GP"
			(at 1.1811 -2.7051 270)
			(unlocked yes)
			(layer "F.Fab")
			(hide yes)
			(effects
				(font
					(size 1.016 1.016)
					(thickness 0.1524)
				)
			)
		)
		(property "Device Type" "C402H22"
			(at 1.1811 -4.2291 270)
			(unlocked yes)
			(layer "F.Fab")
			(hide yes)
			(effects
				(font
					(size 1.016 1.016)
					(thickness 0.1524)
				)
			)
		)
		(duplicate_pad_numbers_are_jumpers no)
		(fp_rect
			(start -0.381 0.7366)
			(end 0.381 -0.7366)
			(stroke
				(width 0)
				(type default)
			)
			(fill no)
			(layer "F.CrtYd")
		)
		(fp_rect
			(start -0.381 0.7366)
			(end 0.381 -0.7366)
			(stroke
				(width 0)
				(type default)
			)
			(fill no)
			(layer "F.Fab")
		)
		(pad "1" smd custom
			(at 0 -0.4572 270)
			(size 0.1143 0.1143)
			(layers "F.Cu" "F.Mask" "F.Paste")
			(net "XDP_PWRBTN#")
			(options
				(clearance outline)
				(anchor circle)
			)
			(primitives
				(gr_poly
					(pts
						(arc
							(start -0.254 -0.1778)
							(mid -0.239121 -0.213721)
							(end -0.2032 -0.2286)
						)
						(arc
							(start 0.2032 -0.2286)
							(mid 0.239121 -0.213721)
							(end 0.254 -0.1778)
						)
						(arc
							(start 0.254 0.1778)
							(mid 0.239121 0.213721)
							(end 0.2032 0.2286)
						)
						(arc
							(start -0.2032 0.2286)
							(mid -0.239121 0.213721)
							(end -0.254 0.1778)
						)
					)
					(width 0)
					(fill yes)
				)
			)
		)
		(pad "2" smd custom
			(at 0 0.4572 270)
			(size 0.1143 0.1143)
			(layers "F.Cu" "F.Mask" "F.Paste")
			(net "GND")
			(options
				(clearance outline)
				(anchor circle)
			)
			(primitives
				(gr_poly
					(pts
						(arc
							(start -0.254 -0.1778)
							(mid -0.239121 -0.213721)
							(end -0.2032 -0.2286)
						)
						(arc
							(start 0.2032 -0.2286)
							(mid 0.239121 -0.213721)
							(end 0.254 -0.1778)
						)
						(arc
							(start 0.254 0.1778)
							(mid 0.239121 0.213721)
							(end 0.2032 0.2286)
						)
						(arc
							(start -0.2032 0.2286)
							(mid -0.239121 0.213721)
							(end -0.254 0.1778)
						)
					)
					(width 0)
					(fill yes)
				)
			)
		)
	)
	(footprint ""
		(layer "F.Cu")
		(at 163.449 -45.847)
		(property "Reference" "R216"
			(at 0 0 0)
			(layer "F.SilkS")
			(hide yes)
			(effects
				(font
					(size 1.27 1.27)
				)
			)
		)
		(property "Value" "0R2J-2-GP"
			(at 1.7907 -1.1176 0)
			(unlocked yes)
			(layer "F.Fab")
			(hide yes)
			(effects
				(font
					(size 1.016 1.016)
					(thickness 0.1524)
				)
			)
		)
		(property "Device Type" "R402H16"
			(at 1.7907 -2.6416 0)
			(unlocked yes)
			(layer "F.Fab")
			(hide yes)
			(effects
				(font
					(size 1.016 1.016)
					(thickness 0.1524)
				)
			)
		)
		(duplicate_pad_numbers_are_jumpers no)
		(fp_rect
			(start -0.381 0.8382)
			(end 0.381 -0.8382)
			(stroke
				(width 0)
				(type default)
			)
			(fill no)
			(layer "F.CrtYd")
		)
		(fp_rect
			(start -0.381 0.8382)
			(end 0.381 -0.8382)
			(stroke
				(width 0)
				(type default)
			)
			(fill no)
			(layer "F.Fab")
		)
		(pad "1" smd custom
			(at 0 -0.4318)
			(size 0.127 0.127)
			(layers "F.Cu" "F.Mask" "F.Paste")
			(net "XDP_SOC_CPU_TCK")
			(options
				(clearance outline)
				(anchor circle)
			)
			(primitives
				(gr_poly
					(pts
						(arc
							(start -0.2032 -0.2794)
							(mid -0.239121 -0.264521)
							(end -0.254 -0.2286)
						)
						(arc
							(start -0.254 0.2286)
							(mid -0.239121 0.264521)
							(end -0.2032 0.2794)
						)
						(arc
							(start 0.2032 0.2794)
							(mid 0.239121 0.264521)
							(end 0.254 0.2286)
						)
						(arc
							(start 0.254 -0.2286)
							(mid 0.239121 -0.264521)
							(end 0.2032 -0.2794)
						)
					)
					(width 0)
					(fill yes)
				)
			)
		)
		(pad "2" smd custom
			(at 0 0.4318)
			(size 0.127 0.127)
			(layers "F.Cu" "F.Mask" "F.Paste")
			(net "XDP_SOC_CPU_TCK_S")
			(options
				(clearance outline)
				(anchor circle)
			)
			(primitives
				(gr_poly
					(pts
						(arc
							(start -0.2032 -0.2794)
							(mid -0.239121 -0.264521)
							(end -0.254 -0.2286)
						)
						(arc
							(start -0.254 0.2286)
							(mid -0.239121 0.264521)
							(end -0.2032 0.2794)
						)
						(arc
							(start 0.2032 0.2794)
							(mid 0.239121 0.264521)
							(end 0.254 0.2286)
						)
						(arc
							(start 0.254 -0.2286)
							(mid 0.239121 -0.264521)
							(end 0.2032 -0.2794)
						)
					)
					(width 0)
					(fill yes)
				)
			)
		)
	)
	(footprint ""
		(layer "F.Cu")
		(at 16.0528 -50.3682 90)
		(property "Reference" "PC148"
			(at 0 0 90)
			(layer "F.SilkS")
			(hide yes)
			(effects
				(font
					(size 1.27 1.27)
				)
			)
		)
		(property "Value" "SC4700P50V2KX-1GP"
			(at 1.8923 -1.2065 90)
			(unlocked yes)
			(layer "F.Fab")
			(hide yes)
			(effects
				(font
					(size 1.016 1.016)
					(thickness 0.1524)
				)
			)
		)
		(property "Device Type" "C402H22"
			(at 1.8923 -2.7305 90)
			(unlocked yes)
			(layer "F.Fab")
			(hide yes)
			(effects
				(font
					(size 1.016 1.016)
					(thickness 0.1524)
				)
			)
		)
		(duplicate_pad_numbers_are_jumpers no)
		(fp_rect
			(start -0.381 0.7366)
			(end 0.381 -0.7366)
			(stroke
				(width 0)
				(type default)
			)
			(fill no)
			(layer "F.CrtYd")
		)
		(fp_rect
			(start -0.381 0.7366)
			(end 0.381 -0.7366)
			(stroke
				(width 0)
				(type default)
			)
			(fill no)
			(layer "F.Fab")
		)
		(pad "1" smd custom
			(at 0 -0.4572 90)
			(size 0.1143 0.1143)
			(layers "F.Cu" "F.Mask" "F.Paste")
			(net "VR_PVCCP_COMP")
			(options
				(clearance outline)
				(anchor circle)
			)
			(primitives
				(gr_poly
					(pts
						(arc
							(start -0.254 -0.1778)
							(mid -0.239121 -0.213721)
							(end -0.2032 -0.2286)
						)
						(arc
							(start 0.2032 -0.2286)
							(mid 0.239121 -0.213721)
							(end 0.254 -0.1778)
						)
						(arc
							(start 0.254 0.1778)
							(mid 0.239121 0.213721)
							(end 0.2032 0.2286)
						)
						(arc
							(start -0.2032 0.2286)
							(mid -0.239121 0.213721)
							(end -0.254 0.1778)
						)
					)
					(width 0)
					(fill yes)
				)
			)
		)
		(pad "2" smd custom
			(at 0 0.4572 90)
			(size 0.1143 0.1143)
			(layers "F.Cu" "F.Mask" "F.Paste")
			(net "VR_PVCCP_COMP_RC")
			(options
				(clearance outline)
				(anchor circle)
			)
			(primitives
				(gr_poly
					(pts
						(arc
							(start -0.254 -0.1778)
							(mid -0.239121 -0.213721)
							(end -0.2032 -0.2286)
						)
						(arc
							(start 0.2032 -0.2286)
							(mid 0.239121 -0.213721)
							(end 0.254 -0.1778)
						)
						(arc
							(start 0.254 0.1778)
							(mid 0.239121 0.213721)
							(end 0.2032 0.2286)
						)
						(arc
							(start -0.2032 0.2286)
							(mid -0.239121 0.213721)
							(end -0.254 0.1778)
						)
					)
					(width 0)
					(fill yes)
				)
			)
		)
	)
	(footprint ""
		(layer "F.Cu")
		(at 24.511 -43.307 180)
		(property "Reference" "PC150"
			(at 0 0 180)
			(layer "F.SilkS")
			(hide yes)
			(effects
				(font
					(size 1.27 1.27)
				)
			)
		)
		(property "Value" "SCD1U25V2KX-2-GP"
			(at 1.8923 -1.2065 180)
			(unlocked yes)
			(layer "F.Fab")
			(hide yes)
			(effects
				(font
					(size 1.016 1.016)
					(thickness 0.1524)
				)
			)
		)
		(property "Device Type" "C402H22"
			(at 1.8923 -2.7305 180)
			(unlocked yes)
			(layer "F.Fab")
			(hide yes)
			(effects
				(font
					(size 1.016 1.016)
					(thickness 0.1524)
				)
			)
		)
		(duplicate_pad_numbers_are_jumpers no)
		(fp_rect
			(start -0.381 0.7366)
			(end 0.381 -0.7366)
			(stroke
				(width 0)
				(type default)
			)
			(fill no)
			(layer "F.CrtYd")
		)
		(fp_rect
			(start -0.381 0.7366)
			(end 0.381 -0.7366)
			(stroke
				(width 0)
				(type default)
			)
			(fill no)
			(layer "F.Fab")
		)
		(pad "1" smd custom
			(at 0 -0.4572 180)
			(size 0.1143 0.1143)
			(layers "F.Cu" "F.Mask" "F.Paste")
			(net "P3V3_STBY_OUT")
			(options
				(clearance outline)
				(anchor circle)
			)
			(primitives
				(gr_poly
					(pts
						(arc
							(start -0.254 -0.1778)
							(mid -0.239121 -0.213721)
							(end -0.2032 -0.2286)
						)
						(arc
							(start 0.2032 -0.2286)
							(mid 0.239121 -0.213721)
							(end 0.254 -0.1778)
						)
						(arc
							(start 0.254 0.1778)
							(mid 0.239121 0.213721)
							(end 0.2032 0.2286)
						)
						(arc
							(start -0.2032 0.2286)
							(mid -0.239121 0.213721)
							(end -0.254 0.1778)
						)
					)
					(width 0)
					(fill yes)
				)
			)
		)
		(pad "2" smd custom
			(at 0 0.4572 180)
			(size 0.1143 0.1143)
			(layers "F.Cu" "F.Mask" "F.Paste")
			(net "GND")
			(options
				(clearance outline)
				(anchor circle)
			)
			(primitives
				(gr_poly
					(pts
						(arc
							(start -0.254 -0.1778)
							(mid -0.239121 -0.213721)
							(end -0.2032 -0.2286)
						)
						(arc
							(start 0.2032 -0.2286)
							(mid 0.239121 -0.213721)
							(end 0.254 -0.1778)
						)
						(arc
							(start 0.254 0.1778)
							(mid 0.239121 0.213721)
							(end 0.2032 0.2286)
						)
						(arc
							(start -0.2032 0.2286)
							(mid -0.239121 0.213721)
							(end -0.254 0.1778)
						)
					)
					(width 0)
					(fill yes)
				)
			)
		)
	)
	(footprint ""
		(layer "F.Cu")
		(at 71.882 -56.388 90)
		(property "Reference" "R312"
			(at 0 0 90)
			(layer "F.SilkS")
			(hide yes)
			(effects
				(font
					(size 1.27 1.27)
				)
			)
		)
		(property "Value" "4K7R2F-GP"
			(at 0.064008 -3.993896 90)
			(unlocked yes)
			(layer "F.Fab")
			(hide yes)
			(effects
				(font
					(size 1.016 1.016)
					(thickness 0.1524)
				)
			)
		)
		(property "Device Type" "R402H16"
			(at 0.064008 -5.517896 90)
			(unlocked yes)
			(layer "F.Fab")
			(hide yes)
			(effects
				(font
					(size 1.016 1.016)
					(thickness 0.1524)
				)
			)
		)
		(duplicate_pad_numbers_are_jumpers no)
		(fp_rect
			(start -0.381 0.8382)
			(end 0.381 -0.8382)
			(stroke
				(width 0)
				(type default)
			)
			(fill no)
			(layer "F.CrtYd")
		)
		(fp_rect
			(start -0.381 0.8382)
			(end 0.381 -0.8382)
			(stroke
				(width 0)
				(type default)
			)
			(fill no)
			(layer "F.Fab")
		)
		(pad "1" smd custom
			(at 0 -0.4318 90)
			(size 0.127 0.127)
			(layers "F.Cu" "F.Mask" "F.Paste")
			(net "P3V3_STBY")
			(options
				(clearance outline)
				(anchor circle)
			)
			(primitives
				(gr_poly
					(pts
						(arc
							(start -0.2032 -0.2794)
							(mid -0.239121 -0.264521)
							(end -0.254 -0.2286)
						)
						(arc
							(start -0.254 0.2286)
							(mid -0.239121 0.264521)
							(end -0.2032 0.2794)
						)
						(arc
							(start 0.2032 0.2794)
							(mid 0.239121 0.264521)
							(end 0.254 0.2286)
						)
						(arc
							(start 0.254 -0.2286)
							(mid 0.239121 -0.264521)
							(end 0.2032 -0.2794)
						)
					)
					(width 0)
					(fill yes)
				)
			)
		)
		(pad "2" smd custom
			(at 0 0.4318 90)
			(size 0.127 0.127)
			(layers "F.Cu" "F.Mask" "F.Paste")
			(net "BMC_I2C_DATA")
			(options
				(clearance outline)
				(anchor circle)
			)
			(primitives
				(gr_poly
					(pts
						(arc
							(start -0.2032 -0.2794)
							(mid -0.239121 -0.264521)
							(end -0.254 -0.2286)
						)
						(arc
							(start -0.254 0.2286)
							(mid -0.239121 0.264521)
							(end -0.2032 0.2794)
						)
						(arc
							(start 0.2032 0.2794)
							(mid 0.239121 0.264521)
							(end 0.254 0.2286)
						)
						(arc
							(start 0.254 -0.2286)
							(mid 0.239121 -0.264521)
							(end 0.2032 -0.2794)
						)
					)
					(width 0)
					(fill yes)
				)
			)
		)
	)
	(footprint ""
		(layer "F.Cu")
		(at 59.436 -25.146 -90)
		(property "Reference" "R253"
			(at 0 0 270)
			(layer "F.SilkS")
			(hide yes)
			(effects
				(font
					(size 1.27 1.27)
				)
			)
		)
		(property "Value" "1KR2F-3-GP"
			(at 0.064008 -3.993896 270)
			(unlocked yes)
			(layer "F.Fab")
			(hide yes)
			(effects
				(font
					(size 1.016 1.016)
					(thickness 0.1524)
				)
			)
		)
		(property "Device Type" "R402H16"
			(at 0.064008 -5.517896 270)
			(unlocked yes)
			(layer "F.Fab")
			(hide yes)
			(effects
				(font
					(size 1.016 1.016)
					(thickness 0.1524)
				)
			)
		)
		(duplicate_pad_numbers_are_jumpers no)
		(fp_rect
			(start -0.381 0.8382)
			(end 0.381 -0.8382)
			(stroke
				(width 0)
				(type default)
			)
			(fill no)
			(layer "F.CrtYd")
		)
		(fp_rect
			(start -0.381 0.8382)
			(end 0.381 -0.8382)
			(stroke
				(width 0)
				(type default)
			)
			(fill no)
			(layer "F.Fab")
		)
		(pad "1" smd custom
			(at 0 -0.4318 270)
			(size 0.127 0.127)
			(layers "F.Cu" "F.Mask" "F.Paste")
			(net "P3V3_STBY")
			(options
				(clearance outline)
				(anchor circle)
			)
			(primitives
				(gr_poly
					(pts
						(arc
							(start -0.2032 -0.2794)
							(mid -0.239121 -0.264521)
							(end -0.254 -0.2286)
						)
						(arc
							(start -0.254 0.2286)
							(mid -0.239121 0.264521)
							(end -0.2032 0.2794)
						)
						(arc
							(start 0.2032 0.2794)
							(mid 0.239121 0.264521)
							(end 0.254 0.2286)
						)
						(arc
							(start 0.254 -0.2286)
							(mid 0.239121 -0.264521)
							(end 0.2032 -0.2794)
						)
					)
					(width 0)
					(fill yes)
				)
			)
		)
		(pad "2" smd custom
			(at 0 0.4318 270)
			(size 0.127 0.127)
			(layers "F.Cu" "F.Mask" "F.Paste")
			(net "P1V8_G")
			(options
				(clearance outline)
				(anchor circle)
			)
			(primitives
				(gr_poly
					(pts
						(arc
							(start -0.2032 -0.2794)
							(mid -0.239121 -0.264521)
							(end -0.254 -0.2286)
						)
						(arc
							(start -0.254 0.2286)
							(mid -0.239121 0.264521)
							(end -0.2032 0.2794)
						)
						(arc
							(start 0.2032 0.2794)
							(mid 0.239121 0.264521)
							(end 0.254 0.2286)
						)
						(arc
							(start 0.254 -0.2286)
							(mid 0.239121 -0.264521)
							(end 0.2032 -0.2794)
						)
					)
					(width 0)
					(fill yes)
				)
			)
		)
	)
	(footprint ""
		(layer "F.Cu")
		(at 157.48 -47.498 90)
		(property "Reference" "Q6"
			(at 0 0 90)
			(layer "F.SilkS")
			(hide yes)
			(effects
				(font
					(size 1.27 1.27)
				)
			)
		)
		(property "Value" "2N7002A-7-GP"
			(at -4.3561 -5.7912 90)
			(unlocked yes)
			(layer "F.Fab")
			(hide yes)
			(effects
				(font
					(size 1.016 1.016)
					(thickness 0.1524)
				)
			)
		)
		(property "Device Type" "SOT23DGS2D4H48"
			(at -4.3561 -7.3152 90)
			(unlocked yes)
			(layer "F.Fab")
			(hide yes)
			(effects
				(font
					(size 1.016 1.016)
					(thickness 0.1524)
				)
			)
		)
		(duplicate_pad_numbers_are_jumpers no)
		(fp_line
			(start 1.7145 -0.4445)
			(end -1.7145 -0.4445)
			(stroke
				(width 0.1524)
				(type default)
			)
			(layer "F.SilkS")
		)
		(fp_line
			(start -1.7145 -0.4445)
			(end -1.7145 0.4445)
			(stroke
				(width 0.1524)
				(type default)
			)
			(layer "F.SilkS")
		)
		(fp_line
			(start 1.7145 0.4445)
			(end 1.7145 -0.4445)
			(stroke
				(width 0.1524)
				(type default)
			)
			(layer "F.SilkS")
		)
		(fp_line
			(start -1.7145 0.4445)
			(end 1.7145 0.4445)
			(stroke
				(width 0.1524)
				(type default)
			)
			(layer "F.SilkS")
		)
		(fp_poly
			(pts
				(xy -1.4224 1.5621) (xy -1.4224 0.9017) (xy -1.7145 0.9017) (xy -1.7145 -0.9017) (xy -0.4699 -0.9017)
				(xy -0.4699 -1.5621) (xy 0.4699 -1.5621) (xy 0.4699 -0.9017) (xy 1.7145 -0.9017) (xy 1.7145 0.9017)
				(xy 1.4224 0.9017) (xy 1.4224 1.5621) (xy 0.4826 1.5621) (xy 0.4826 0.9017) (xy -0.4826 0.9017)
				(xy -0.4826 1.5621)
			)
			(stroke
				(width 0)
				(type default)
			)
			(fill no)
			(layer "F.CrtYd")
		)
		(fp_poly
			(pts
				(xy -1.4224 1.5621) (xy -1.4224 0.9017) (xy -1.7145 0.9017) (xy -1.7145 -0.9017) (xy -0.4699 -0.9017)
				(xy -0.4699 -1.5621) (xy 0.4699 -1.5621) (xy 0.4699 -0.9017) (xy 1.7145 -0.9017) (xy 1.7145 0.9017)
				(xy 1.4224 0.9017) (xy 1.4224 1.5621) (xy 0.4826 1.5621) (xy 0.4826 0.9017) (xy -0.4826 0.9017)
				(xy -0.4826 1.5621)
			)
			(stroke
				(width 0)
				(type default)
			)
			(fill no)
			(layer "F.Fab")
		)
		(pad "D" smd custom
			(at 0 -1.069086 90)
			(size 0.17145 0.17145)
			(layers "F.Cu" "F.Mask" "F.Paste")
			(net "JTAG_CPU_PLD_TDO_D")
			(options
				(clearance outline)
				(anchor circle)
			)
			(primitives
				(gr_poly
					(pts
						(arc
							(start -0.1397 0.3683)
							(mid -0.283384 0.308784)
							(end -0.3429 0.1651)
						)
						(arc
							(start -0.3429 -0.1651)
							(mid -0.283384 -0.308784)
							(end -0.1397 -0.3683)
						)
						(arc
							(start 0.1397 -0.3683)
							(mid 0.283384 -0.308784)
							(end 0.3429 -0.1651)
						)
						(arc
							(start 0.3429 0.1651)
							(mid 0.283384 0.308784)
							(end 0.1397 0.3683)
						)
					)
					(width 0)
					(fill yes)
				)
			)
		)
		(pad "G" smd custom
			(at -0.94996 1.069086 90)
			(size 0.17145 0.17145)
			(layers "F.Cu" "F.Mask" "F.Paste")
			(net "JTAG_CHAIN_EN")
			(options
				(clearance outline)
				(anchor circle)
			)
			(primitives
				(gr_poly
					(pts
						(arc
							(start -0.1397 0.3683)
							(mid -0.283384 0.308784)
							(end -0.3429 0.1651)
						)
						(arc
							(start -0.3429 -0.1651)
							(mid -0.283384 -0.308784)
							(end -0.1397 -0.3683)
						)
						(arc
							(start 0.1397 -0.3683)
							(mid 0.283384 -0.308784)
							(end 0.3429 -0.1651)
						)
						(arc
							(start 0.3429 0.1651)
							(mid 0.283384 0.308784)
							(end 0.1397 0.3683)
						)
					)
					(width 0)
					(fill yes)
				)
			)
		)
		(pad "S" smd custom
			(at 0.94996 1.069086 90)
			(size 0.17145 0.17145)
			(layers "F.Cu" "F.Mask" "F.Paste")
			(net "XDP_SOC_CPU_TDO_S")
			(options
				(clearance outline)
				(anchor circle)
			)
			(primitives
				(gr_poly
					(pts
						(arc
							(start -0.1397 0.3683)
							(mid -0.283384 0.308784)
							(end -0.3429 0.1651)
						)
						(arc
							(start -0.3429 -0.1651)
							(mid -0.283384 -0.308784)
							(end -0.1397 -0.3683)
						)
						(arc
							(start 0.1397 -0.3683)
							(mid 0.283384 -0.308784)
							(end 0.3429 -0.1651)
						)
						(arc
							(start 0.3429 0.1651)
							(mid 0.283384 0.308784)
							(end 0.1397 0.3683)
						)
					)
					(width 0)
					(fill yes)
				)
			)
		)
	)
	(footprint ""
		(layer "F.Cu")
		(at 61.849 -63.754 180)
		(property "Reference" "PC38"
			(at 0 0 180)
			(layer "F.SilkS")
			(hide yes)
			(effects
				(font
					(size 1.27 1.27)
				)
			)
		)
		(property "Value" "SC47U6D3V5MX-1-GP"
			(at -0.0762 -6.1214 180)
			(unlocked yes)
			(layer "F.Fab")
			(hide yes)
			(effects
				(font
					(size 1.016 1.016)
					(thickness 0.1524)
				)
			)
		)
		(property "Device Type" "C805H54"
			(at -0.0762 -8.1534 180)
			(unlocked yes)
			(layer "F.Fab")
			(hide yes)
			(effects
				(font
					(size 1.016 1.016)
					(thickness 0.1524)
				)
			)
		)
		(duplicate_pad_numbers_are_jumpers no)
		(fp_line
			(start 0.6096 0)
			(end -0.6096 0)
			(stroke
				(width 0.3048)
				(type default)
			)
			(layer "F.SilkS")
		)
		(fp_poly
			(pts
				(xy -0.9017 1.4351) (xy 0.9017 1.4351) (xy 0.9017 -1.4351) (xy -0.9017 -1.4351)
			)
			(stroke
				(width 0)
				(type default)
			)
			(fill no)
			(layer "F.CrtYd")
		)
		(fp_poly
			(pts
				(xy 0.9017 1.4351) (xy 0.9017 -1.4351) (xy -0.9017 -1.4351) (xy -0.9017 1.4351)
			)
			(stroke
				(width 0)
				(type default)
			)
			(fill no)
			(layer "F.Fab")
		)
		(pad "1" smd rect
			(at 0 -0.8382 180)
			(size 1.5494 0.9398)
			(layers "F.Cu" "F.Mask" "F.Paste")
			(net "PVCCP")
		)
		(pad "2" smd rect
			(at 0 0.8382 180)
			(size 1.5494 0.9398)
			(layers "F.Cu" "F.Mask" "F.Paste")
			(net "GND")
		)
	)
	(footprint ""
		(layer "F.Cu")
		(at 15.8496 -58.3692 -90)
		(property "Reference" "PR56"
			(at 0 0 270)
			(layer "F.SilkS")
			(hide yes)
			(effects
				(font
					(size 1.27 1.27)
				)
			)
		)
		(property "Value" "0R2J-2-GP"
			(at 1.7907 -1.1176 270)
			(unlocked yes)
			(layer "F.Fab")
			(hide yes)
			(effects
				(font
					(size 1.016 1.016)
					(thickness 0.1524)
				)
			)
		)
		(property "Device Type" "R402H16"
			(at 1.7907 -2.6416 270)
			(unlocked yes)
			(layer "F.Fab")
			(hide yes)
			(effects
				(font
					(size 1.016 1.016)
					(thickness 0.1524)
				)
			)
		)
		(duplicate_pad_numbers_are_jumpers no)
		(fp_rect
			(start -0.381 0.8382)
			(end 0.381 -0.8382)
			(stroke
				(width 0)
				(type default)
			)
			(fill no)
			(layer "F.CrtYd")
		)
		(fp_rect
			(start -0.381 0.8382)
			(end 0.381 -0.8382)
			(stroke
				(width 0)
				(type default)
			)
			(fill no)
			(layer "F.Fab")
		)
		(pad "1" smd custom
			(at 0 -0.4318 270)
			(size 0.127 0.127)
			(layers "F.Cu" "F.Mask" "F.Paste")
			(net "PVCC_PVNN_EN_R")
			(options
				(clearance outline)
				(anchor circle)
			)
			(primitives
				(gr_poly
					(pts
						(arc
							(start -0.2032 -0.2794)
							(mid -0.239121 -0.264521)
							(end -0.254 -0.2286)
						)
						(arc
							(start -0.254 0.2286)
							(mid -0.239121 0.264521)
							(end -0.2032 0.2794)
						)
						(arc
							(start 0.2032 0.2794)
							(mid 0.239121 0.264521)
							(end 0.254 0.2286)
						)
						(arc
							(start 0.254 -0.2286)
							(mid 0.239121 -0.264521)
							(end 0.2032 -0.2794)
						)
					)
					(width 0)
					(fill yes)
				)
			)
		)
		(pad "2" smd custom
			(at 0 0.4318 270)
			(size 0.127 0.127)
			(layers "F.Cu" "F.Mask" "F.Paste")
			(net "PMU_SLP_S3#")
			(options
				(clearance outline)
				(anchor circle)
			)
			(primitives
				(gr_poly
					(pts
						(arc
							(start -0.2032 -0.2794)
							(mid -0.239121 -0.264521)
							(end -0.254 -0.2286)
						)
						(arc
							(start -0.254 0.2286)
							(mid -0.239121 0.264521)
							(end -0.2032 0.2794)
						)
						(arc
							(start 0.2032 0.2794)
							(mid 0.239121 0.264521)
							(end 0.254 0.2286)
						)
						(arc
							(start 0.254 -0.2286)
							(mid 0.239121 -0.264521)
							(end 0.2032 -0.2794)
						)
					)
					(width 0)
					(fill yes)
				)
			)
		)
	)
	(footprint ""
		(layer "F.Cu")
		(at 13.716 -31.877)
		(property "Reference" "PC173"
			(at 0 0 0)
			(layer "F.SilkS")
			(hide yes)
			(effects
				(font
					(size 1.27 1.27)
				)
			)
		)
		(property "Value" "SC1U10V2KX-1GP"
			(at 1.8923 -1.2065 0)
			(unlocked yes)
			(layer "F.Fab")
			(hide yes)
			(effects
				(font
					(size 1.016 1.016)
					(thickness 0.1524)
				)
			)
		)
		(property "Device Type" "C402H22"
			(at 1.8923 -2.7305 0)
			(unlocked yes)
			(layer "F.Fab")
			(hide yes)
			(effects
				(font
					(size 1.016 1.016)
					(thickness 0.1524)
				)
			)
		)
		(duplicate_pad_numbers_are_jumpers no)
		(fp_rect
			(start -0.381 0.7366)
			(end 0.381 -0.7366)
			(stroke
				(width 0)
				(type default)
			)
			(fill no)
			(layer "F.CrtYd")
		)
		(fp_rect
			(start -0.381 0.7366)
			(end 0.381 -0.7366)
			(stroke
				(width 0)
				(type default)
			)
			(fill no)
			(layer "F.Fab")
		)
		(pad "1" smd custom
			(at 0 -0.4572)
			(size 0.1143 0.1143)
			(layers "F.Cu" "F.Mask" "F.Paste")
			(net "P3V3_STBY_VFB")
			(options
				(clearance outline)
				(anchor circle)
			)
			(primitives
				(gr_poly
					(pts
						(arc
							(start -0.254 -0.1778)
							(mid -0.239121 -0.213721)
							(end -0.2032 -0.2286)
						)
						(arc
							(start 0.2032 -0.2286)
							(mid 0.239121 -0.213721)
							(end 0.254 -0.1778)
						)
						(arc
							(start 0.254 0.1778)
							(mid 0.239121 0.213721)
							(end 0.2032 0.2286)
						)
						(arc
							(start -0.2032 0.2286)
							(mid -0.239121 0.213721)
							(end -0.254 0.1778)
						)
					)
					(width 0)
					(fill yes)
				)
			)
		)
		(pad "2" smd custom
			(at 0 0.4572)
			(size 0.1143 0.1143)
			(layers "F.Cu" "F.Mask" "F.Paste")
			(net "AGND_P3V3_STBY")
			(options
				(clearance outline)
				(anchor circle)
			)
			(primitives
				(gr_poly
					(pts
						(arc
							(start -0.254 -0.1778)
							(mid -0.239121 -0.213721)
							(end -0.2032 -0.2286)
						)
						(arc
							(start 0.2032 -0.2286)
							(mid 0.239121 -0.213721)
							(end 0.254 -0.1778)
						)
						(arc
							(start 0.254 0.1778)
							(mid 0.239121 0.213721)
							(end 0.2032 0.2286)
						)
						(arc
							(start -0.2032 0.2286)
							(mid -0.239121 0.213721)
							(end -0.254 0.1778)
						)
					)
					(width 0)
					(fill yes)
				)
			)
		)
	)
	(footprint ""
		(layer "F.Cu")
		(at 109.218984 -58.944002 90)
		(property "Reference" "R21"
			(at 0 0 90)
			(layer "F.SilkS")
			(hide yes)
			(effects
				(font
					(size 1.27 1.27)
				)
			)
		)
		(property "Value" "100R3F-1-GP"
			(at -0.0254 -2.5146 90)
			(unlocked yes)
			(layer "F.Fab")
			(hide yes)
			(effects
				(font
					(size 1.016 1.016)
					(thickness 0.1524)
				)
			)
		)
		(property "Device Type" "R603H22"
			(at -0.0254 -4.0386 90)
			(unlocked yes)
			(layer "F.Fab")
			(hide yes)
			(effects
				(font
					(size 1.016 1.016)
					(thickness 0.1524)
				)
			)
		)
		(duplicate_pad_numbers_are_jumpers no)
		(fp_line
			(start 0.4318 0)
			(end 0.2032 0)
			(stroke
				(width 0.2032)
				(type default)
			)
			(layer "F.SilkS")
		)
		(fp_line
			(start -0.2032 0)
			(end -0.4191 0)
			(stroke
				(width 0.2032)
				(type default)
			)
			(layer "F.SilkS")
		)
		(fp_rect
			(start -0.635 1.1811)
			(end 0.635 -1.1811)
			(stroke
				(width 0)
				(type default)
			)
			(fill no)
			(layer "F.CrtYd")
		)
		(fp_rect
			(start -0.635 1.1811)
			(end 0.635 -1.1811)
			(stroke
				(width 0)
				(type default)
			)
			(fill no)
			(layer "F.Fab")
		)
		(pad "1" smd custom
			(at 0 -0.6604 90)
			(size 0.19685 0.19685)
			(layers "F.Cu" "F.Mask" "F.Paste")
			(net "M_A_MON1_P")
			(options
				(clearance outline)
				(anchor circle)
			)
			(primitives
				(gr_poly
					(pts
						(arc
							(start 0.508 -0.2921)
							(mid 0.478242 -0.363942)
							(end 0.4064 -0.3937)
						)
						(arc
							(start -0.4064 -0.3937)
							(mid -0.478242 -0.363942)
							(end -0.508 -0.2921)
						)
						(arc
							(start -0.508 0.2921)
							(mid -0.478242 0.363942)
							(end -0.4064 0.3937)
						)
						(arc
							(start 0.4064 0.3937)
							(mid 0.478242 0.363942)
							(end 0.508 0.2921)
						)
					)
					(width 0)
					(fill yes)
				)
			)
		)
		(pad "2" smd custom
			(at 0 0.6604 90)
			(size 0.19685 0.19685)
			(layers "F.Cu" "F.Mask" "F.Paste")
			(net "M_A_MON1_N")
			(options
				(clearance outline)
				(anchor circle)
			)
			(primitives
				(gr_poly
					(pts
						(arc
							(start 0.508 -0.2921)
							(mid 0.478242 -0.363942)
							(end 0.4064 -0.3937)
						)
						(arc
							(start -0.4064 -0.3937)
							(mid -0.478242 -0.363942)
							(end -0.508 -0.2921)
						)
						(arc
							(start -0.508 0.2921)
							(mid -0.478242 0.363942)
							(end -0.4064 0.3937)
						)
						(arc
							(start 0.4064 0.3937)
							(mid 0.478242 0.363942)
							(end 0.508 0.2921)
						)
					)
					(width 0)
					(fill yes)
				)
			)
		)
	)
	(footprint ""
		(layer "F.Cu")
		(at 183.134 -36.068)
		(property "Reference" "C38"
			(at 0 0 0)
			(layer "F.SilkS")
			(hide yes)
			(effects
				(font
					(size 1.27 1.27)
				)
			)
		)
		(property "Value" "SC1KP50V2KX-1GP"
			(at 1.8923 -1.2065 0)
			(unlocked yes)
			(layer "F.Fab")
			(hide yes)
			(effects
				(font
					(size 1.016 1.016)
					(thickness 0.1524)
				)
			)
		)
		(property "Device Type" "C402H22"
			(at 1.8923 -2.7305 0)
			(unlocked yes)
			(layer "F.Fab")
			(hide yes)
			(effects
				(font
					(size 1.016 1.016)
					(thickness 0.1524)
				)
			)
		)
		(duplicate_pad_numbers_are_jumpers no)
		(fp_rect
			(start -0.381 0.7366)
			(end 0.381 -0.7366)
			(stroke
				(width 0)
				(type default)
			)
			(fill no)
			(layer "F.CrtYd")
		)
		(fp_rect
			(start -0.381 0.7366)
			(end 0.381 -0.7366)
			(stroke
				(width 0)
				(type default)
			)
			(fill no)
			(layer "F.Fab")
		)
		(pad "1" smd custom
			(at 0 -0.4572)
			(size 0.1143 0.1143)
			(layers "F.Cu" "F.Mask" "F.Paste")
			(net "VR_PWREN_PVDDR_A")
			(options
				(clearance outline)
				(anchor circle)
			)
			(primitives
				(gr_poly
					(pts
						(arc
							(start -0.254 -0.1778)
							(mid -0.239121 -0.213721)
							(end -0.2032 -0.2286)
						)
						(arc
							(start 0.2032 -0.2286)
							(mid 0.239121 -0.213721)
							(end 0.254 -0.1778)
						)
						(arc
							(start 0.254 0.1778)
							(mid 0.239121 0.213721)
							(end 0.2032 0.2286)
						)
						(arc
							(start -0.2032 0.2286)
							(mid -0.239121 0.213721)
							(end -0.254 0.1778)
						)
					)
					(width 0)
					(fill yes)
				)
			)
		)
		(pad "2" smd custom
			(at 0 0.4572)
			(size 0.1143 0.1143)
			(layers "F.Cu" "F.Mask" "F.Paste")
			(net "GND")
			(options
				(clearance outline)
				(anchor circle)
			)
			(primitives
				(gr_poly
					(pts
						(arc
							(start -0.254 -0.1778)
							(mid -0.239121 -0.213721)
							(end -0.2032 -0.2286)
						)
						(arc
							(start 0.2032 -0.2286)
							(mid 0.239121 -0.213721)
							(end 0.254 -0.1778)
						)
						(arc
							(start 0.254 0.1778)
							(mid 0.239121 0.213721)
							(end 0.2032 0.2286)
						)
						(arc
							(start -0.2032 0.2286)
							(mid -0.239121 0.213721)
							(end -0.254 0.1778)
						)
					)
					(width 0)
					(fill yes)
				)
			)
		)
	)
	(footprint ""
		(layer "F.Cu")
		(at 187.833 -27.0002 180)
		(property "Reference" "PR161"
			(at 0 0 180)
			(layer "F.SilkS")
			(hide yes)
			(effects
				(font
					(size 1.27 1.27)
				)
			)
		)
		(property "Value" "4K99R2F-L-GP"
			(at 1.7907 -1.1176 180)
			(unlocked yes)
			(layer "F.Fab")
			(hide yes)
			(effects
				(font
					(size 1.016 1.016)
					(thickness 0.1524)
				)
			)
		)
		(property "Device Type" "R402H16"
			(at 1.7907 -2.6416 180)
			(unlocked yes)
			(layer "F.Fab")
			(hide yes)
			(effects
				(font
					(size 1.016 1.016)
					(thickness 0.1524)
				)
			)
		)
		(duplicate_pad_numbers_are_jumpers no)
		(fp_rect
			(start -0.381 0.8382)
			(end 0.381 -0.8382)
			(stroke
				(width 0)
				(type default)
			)
			(fill no)
			(layer "F.CrtYd")
		)
		(fp_rect
			(start -0.381 0.8382)
			(end 0.381 -0.8382)
			(stroke
				(width 0)
				(type default)
			)
			(fill no)
			(layer "F.Fab")
		)
		(pad "1" smd custom
			(at 0 -0.4318 180)
			(size 0.127 0.127)
			(layers "F.Cu" "F.Mask" "F.Paste")
			(net "VSENSE_PVDDR_A_VSEN")
			(options
				(clearance outline)
				(anchor circle)
			)
			(primitives
				(gr_poly
					(pts
						(arc
							(start -0.2032 -0.2794)
							(mid -0.239121 -0.264521)
							(end -0.254 -0.2286)
						)
						(arc
							(start -0.254 0.2286)
							(mid -0.239121 0.264521)
							(end -0.2032 0.2794)
						)
						(arc
							(start 0.2032 0.2794)
							(mid 0.239121 0.264521)
							(end 0.254 0.2286)
						)
						(arc
							(start 0.254 -0.2286)
							(mid 0.239121 -0.264521)
							(end 0.2032 -0.2794)
						)
					)
					(width 0)
					(fill yes)
				)
			)
		)
		(pad "2" smd custom
			(at 0 0.4318 180)
			(size 0.127 0.127)
			(layers "F.Cu" "F.Mask" "F.Paste")
			(net "VSENSE_PVDDR_A_VRTN")
			(options
				(clearance outline)
				(anchor circle)
			)
			(primitives
				(gr_poly
					(pts
						(arc
							(start -0.2032 -0.2794)
							(mid -0.239121 -0.264521)
							(end -0.254 -0.2286)
						)
						(arc
							(start -0.254 0.2286)
							(mid -0.239121 0.264521)
							(end -0.2032 0.2794)
						)
						(arc
							(start 0.2032 0.2794)
							(mid 0.239121 0.264521)
							(end 0.254 0.2286)
						)
						(arc
							(start 0.254 -0.2286)
							(mid 0.239121 -0.264521)
							(end 0.2032 -0.2794)
						)
					)
					(width 0)
					(fill yes)
				)
			)
		)
	)
	(footprint ""
		(layer "F.Cu")
		(at 77.978 -13.716 90)
		(property "Reference" "R193"
			(at 0 0 90)
			(layer "F.SilkS")
			(hide yes)
			(effects
				(font
					(size 1.27 1.27)
				)
			)
		)
		(property "Value" "0R2J-2-GP"
			(at 0.064008 -3.993896 90)
			(unlocked yes)
			(layer "F.Fab")
			(hide yes)
			(effects
				(font
					(size 1.016 1.016)
					(thickness 0.1524)
				)
			)
		)
		(property "Device Type" "R402H16"
			(at 0.064008 -5.517896 90)
			(unlocked yes)
			(layer "F.Fab")
			(hide yes)
			(effects
				(font
					(size 1.016 1.016)
					(thickness 0.1524)
				)
			)
		)
		(duplicate_pad_numbers_are_jumpers no)
		(fp_rect
			(start -0.381 0.8382)
			(end 0.381 -0.8382)
			(stroke
				(width 0)
				(type default)
			)
			(fill no)
			(layer "F.CrtYd")
		)
		(fp_rect
			(start -0.381 0.8382)
			(end 0.381 -0.8382)
			(stroke
				(width 0)
				(type default)
			)
			(fill no)
			(layer "F.Fab")
		)
		(pad "1" smd custom
			(at 0 -0.4318 90)
			(size 0.127 0.127)
			(layers "F.Cu" "F.Mask" "F.Paste")
			(net "PMU_BUF_PLTRST#")
			(options
				(clearance outline)
				(anchor circle)
			)
			(primitives
				(gr_poly
					(pts
						(arc
							(start -0.2032 -0.2794)
							(mid -0.239121 -0.264521)
							(end -0.254 -0.2286)
						)
						(arc
							(start -0.254 0.2286)
							(mid -0.239121 0.264521)
							(end -0.2032 0.2794)
						)
						(arc
							(start 0.2032 0.2794)
							(mid 0.239121 0.264521)
							(end 0.254 0.2286)
						)
						(arc
							(start 0.254 -0.2286)
							(mid 0.239121 -0.264521)
							(end 0.2032 -0.2794)
						)
					)
					(width 0)
					(fill yes)
				)
			)
		)
		(pad "2" smd custom
			(at 0 0.4318 90)
			(size 0.127 0.127)
			(layers "F.Cu" "F.Mask" "F.Paste")
			(net "PCIE_RESET#")
			(options
				(clearance outline)
				(anchor circle)
			)
			(primitives
				(gr_poly
					(pts
						(arc
							(start -0.2032 -0.2794)
							(mid -0.239121 -0.264521)
							(end -0.254 -0.2286)
						)
						(arc
							(start -0.254 0.2286)
							(mid -0.239121 0.264521)
							(end -0.2032 0.2794)
						)
						(arc
							(start 0.2032 0.2794)
							(mid 0.239121 0.264521)
							(end 0.254 0.2286)
						)
						(arc
							(start 0.254 -0.2286)
							(mid 0.239121 -0.264521)
							(end 0.2032 -0.2794)
						)
					)
					(width 0)
					(fill yes)
				)
			)
		)
	)
	(footprint ""
		(layer "F.Cu")
		(at 200.4822 -26.162 -90)
		(property "Reference" "PC183"
			(at 0 0 270)
			(layer "F.SilkS")
			(hide yes)
			(effects
				(font
					(size 1.27 1.27)
				)
			)
		)
		(property "Value" "SC47U16V0MX-GP"
			(at -2.3368 -3.5052 270)
			(unlocked yes)
			(layer "F.Fab")
			(hide yes)
			(effects
				(font
					(size 1.016 1.016)
					(thickness 0.1524)
				)
			)
		)
		(property "Device Type" "C1210H107"
			(at -2.3368 -5.0292 270)
			(unlocked yes)
			(layer "F.Fab")
			(hide yes)
			(effects
				(font
					(size 1.016 1.016)
					(thickness 0.1524)
				)
			)
		)
		(duplicate_pad_numbers_are_jumpers no)
		(fp_rect
			(start -1.4986 1.9685)
			(end 1.4986 -1.9685)
			(stroke
				(width 0)
				(type default)
			)
			(fill no)
			(layer "F.CrtYd")
		)
		(fp_rect
			(start -1.4986 1.9685)
			(end 1.4986 -1.9685)
			(stroke
				(width 0)
				(type default)
			)
			(fill no)
			(layer "F.Fab")
		)
		(pad "1" smd rect
			(at 0 -1.2446 270)
			(size 2.7432 1.1938)
			(layers "F.Cu" "F.Mask" "F.Paste")
			(net "PVDDR_VIN")
		)
		(pad "2" smd rect
			(at 0 1.2446 270)
			(size 2.7432 1.1938)
			(layers "F.Cu" "F.Mask" "F.Paste")
			(net "GND")
		)
	)
	(footprint ""
		(layer "F.Cu")
		(at 8.1788 -24.1554)
		(property "Reference" "PC90"
			(at 0 0 0)
			(layer "F.SilkS")
			(hide yes)
			(effects
				(font
					(size 1.27 1.27)
				)
			)
		)
		(property "Value" "SC4D7U25V5KX-1-GP"
			(at 0 -4.9022 0)
			(unlocked yes)
			(layer "F.Fab")
			(hide yes)
			(effects
				(font
					(size 1.016 1.016)
					(thickness 0.1524)
				)
			)
		)
		(property "Device Type" "C805H58"
			(at 0 -6.8072 0)
			(unlocked yes)
			(layer "F.Fab")
			(hide yes)
			(effects
				(font
					(size 1.016 1.016)
					(thickness 0.1524)
				)
			)
		)
		(duplicate_pad_numbers_are_jumpers no)
		(fp_line
			(start 0.6096 0)
			(end -0.6096 0)
			(stroke
				(width 0.3048)
				(type default)
			)
			(layer "F.SilkS")
		)
		(fp_poly
			(pts
				(xy -0.9017 1.4351) (xy 0.9017 1.4351) (xy 0.9017 -1.4351) (xy -0.9017 -1.4351)
			)
			(stroke
				(width 0)
				(type default)
			)
			(fill no)
			(layer "F.CrtYd")
		)
		(fp_poly
			(pts
				(xy 0.9017 1.4351) (xy 0.9017 -1.4351) (xy -0.9017 -1.4351) (xy -0.9017 1.4351)
			)
			(stroke
				(width 0)
				(type default)
			)
			(fill no)
			(layer "F.Fab")
		)
		(pad "1" smd rect
			(at 0 -0.8382)
			(size 1.5494 0.9398)
			(layers "F.Cu" "F.Mask" "F.Paste")
			(net "P1V0_VDD")
		)
		(pad "2" smd rect
			(at 0 0.8382)
			(size 1.5494 0.9398)
			(layers "F.Cu" "F.Mask" "F.Paste")
			(net "GND")
		)
	)
	(footprint ""
		(layer "F.Cu")
		(at 92.71 -13.208)
		(property "Reference" "R445"
			(at 0 0 0)
			(layer "F.SilkS")
			(hide yes)
			(effects
				(font
					(size 1.27 1.27)
				)
			)
		)
		(property "Value" "4K7R2F-GP"
			(at 1.7907 -1.1176 0)
			(unlocked yes)
			(layer "F.Fab")
			(hide yes)
			(effects
				(font
					(size 1.016 1.016)
					(thickness 0.1524)
				)
			)
		)
		(property "Device Type" "R402H16"
			(at 1.7907 -2.6416 0)
			(unlocked yes)
			(layer "F.Fab")
			(hide yes)
			(effects
				(font
					(size 1.016 1.016)
					(thickness 0.1524)
				)
			)
		)
		(duplicate_pad_numbers_are_jumpers no)
		(fp_rect
			(start -0.381 0.8382)
			(end 0.381 -0.8382)
			(stroke
				(width 0)
				(type default)
			)
			(fill no)
			(layer "F.CrtYd")
		)
		(fp_rect
			(start -0.381 0.8382)
			(end 0.381 -0.8382)
			(stroke
				(width 0)
				(type default)
			)
			(fill no)
			(layer "F.Fab")
		)
		(pad "1" smd custom
			(at 0 -0.4318)
			(size 0.127 0.127)
			(layers "F.Cu" "F.Mask" "F.Paste")
			(net "P3V3_STBY")
			(options
				(clearance outline)
				(anchor circle)
			)
			(primitives
				(gr_poly
					(pts
						(arc
							(start -0.2032 -0.2794)
							(mid -0.239121 -0.264521)
							(end -0.254 -0.2286)
						)
						(arc
							(start -0.254 0.2286)
							(mid -0.239121 0.264521)
							(end -0.2032 0.2794)
						)
						(arc
							(start 0.2032 0.2794)
							(mid 0.239121 0.264521)
							(end 0.254 0.2286)
						)
						(arc
							(start 0.254 -0.2286)
							(mid 0.239121 -0.264521)
							(end 0.2032 -0.2794)
						)
					)
					(width 0)
					(fill yes)
				)
			)
		)
		(pad "2" smd custom
			(at 0 0.4318)
			(size 0.127 0.127)
			(layers "F.Cu" "F.Mask" "F.Paste")
			(net "SLOT_ID1")
			(options
				(clearance outline)
				(anchor circle)
			)
			(primitives
				(gr_poly
					(pts
						(arc
							(start -0.2032 -0.2794)
							(mid -0.239121 -0.264521)
							(end -0.254 -0.2286)
						)
						(arc
							(start -0.254 0.2286)
							(mid -0.239121 0.264521)
							(end -0.2032 0.2794)
						)
						(arc
							(start 0.2032 0.2794)
							(mid 0.239121 0.264521)
							(end 0.254 0.2286)
						)
						(arc
							(start 0.254 -0.2286)
							(mid 0.239121 -0.264521)
							(end 0.2032 -0.2794)
						)
					)
					(width 0)
					(fill yes)
				)
			)
		)
	)
	(footprint ""
		(layer "F.Cu")
		(at 136.779 -21.082)
		(property "Reference" "C18"
			(at 0 0 0)
			(layer "F.SilkS")
			(hide yes)
			(effects
				(font
					(size 1.27 1.27)
				)
			)
		)
		(property "Value" "SCD1U10V2KX-5GP"
			(at 1.1811 -2.7051 0)
			(unlocked yes)
			(layer "F.Fab")
			(hide yes)
			(effects
				(font
					(size 1.016 1.016)
					(thickness 0.1524)
				)
			)
		)
		(property "Device Type" "C402H22"
			(at 1.1811 -4.2291 0)
			(unlocked yes)
			(layer "F.Fab")
			(hide yes)
			(effects
				(font
					(size 1.016 1.016)
					(thickness 0.1524)
				)
			)
		)
		(duplicate_pad_numbers_are_jumpers no)
		(fp_rect
			(start -0.381 0.7366)
			(end 0.381 -0.7366)
			(stroke
				(width 0)
				(type default)
			)
			(fill no)
			(layer "F.CrtYd")
		)
		(fp_rect
			(start -0.381 0.7366)
			(end 0.381 -0.7366)
			(stroke
				(width 0)
				(type default)
			)
			(fill no)
			(layer "F.Fab")
		)
		(pad "1" smd custom
			(at 0 -0.4572)
			(size 0.1143 0.1143)
			(layers "F.Cu" "F.Mask" "F.Paste")
			(net "P1V2_FPGA_D")
			(options
				(clearance outline)
				(anchor circle)
			)
			(primitives
				(gr_poly
					(pts
						(arc
							(start -0.254 -0.1778)
							(mid -0.239121 -0.213721)
							(end -0.2032 -0.2286)
						)
						(arc
							(start 0.2032 -0.2286)
							(mid 0.239121 -0.213721)
							(end 0.254 -0.1778)
						)
						(arc
							(start 0.254 0.1778)
							(mid 0.239121 0.213721)
							(end 0.2032 0.2286)
						)
						(arc
							(start -0.2032 0.2286)
							(mid -0.239121 0.213721)
							(end -0.254 0.1778)
						)
					)
					(width 0)
					(fill yes)
				)
			)
		)
		(pad "2" smd custom
			(at 0 0.4572)
			(size 0.1143 0.1143)
			(layers "F.Cu" "F.Mask" "F.Paste")
			(net "GND")
			(options
				(clearance outline)
				(anchor circle)
			)
			(primitives
				(gr_poly
					(pts
						(arc
							(start -0.254 -0.1778)
							(mid -0.239121 -0.213721)
							(end -0.2032 -0.2286)
						)
						(arc
							(start 0.2032 -0.2286)
							(mid 0.239121 -0.213721)
							(end 0.254 -0.1778)
						)
						(arc
							(start 0.254 0.1778)
							(mid 0.239121 0.213721)
							(end 0.2032 0.2286)
						)
						(arc
							(start -0.2032 0.2286)
							(mid -0.239121 0.213721)
							(end -0.254 0.1778)
						)
					)
					(width 0)
					(fill yes)
				)
			)
		)
	)
	(footprint ""
		(layer "F.Cu")
		(at 163.7792 -48.1076 90)
		(property "Reference" "R206"
			(at 0 0 90)
			(layer "F.SilkS")
			(hide yes)
			(effects
				(font
					(size 1.27 1.27)
				)
			)
		)
		(property "Value" "0R2J-2-GP"
			(at 1.7907 -1.1176 90)
			(unlocked yes)
			(layer "F.Fab")
			(hide yes)
			(effects
				(font
					(size 1.016 1.016)
					(thickness 0.1524)
				)
			)
		)
		(property "Device Type" "R402H16"
			(at 1.7907 -2.6416 90)
			(unlocked yes)
			(layer "F.Fab")
			(hide yes)
			(effects
				(font
					(size 1.016 1.016)
					(thickness 0.1524)
				)
			)
		)
		(duplicate_pad_numbers_are_jumpers no)
		(fp_rect
			(start -0.381 0.8382)
			(end 0.381 -0.8382)
			(stroke
				(width 0)
				(type default)
			)
			(fill no)
			(layer "F.CrtYd")
		)
		(fp_rect
			(start -0.381 0.8382)
			(end 0.381 -0.8382)
			(stroke
				(width 0)
				(type default)
			)
			(fill no)
			(layer "F.Fab")
		)
		(pad "1" smd custom
			(at 0 -0.4318 90)
			(size 0.127 0.127)
			(layers "F.Cu" "F.Mask" "F.Paste")
			(net "JTAG_PLD_TDO")
			(options
				(clearance outline)
				(anchor circle)
			)
			(primitives
				(gr_poly
					(pts
						(arc
							(start -0.2032 -0.2794)
							(mid -0.239121 -0.264521)
							(end -0.254 -0.2286)
						)
						(arc
							(start -0.254 0.2286)
							(mid -0.239121 0.264521)
							(end -0.2032 0.2794)
						)
						(arc
							(start 0.2032 0.2794)
							(mid 0.239121 0.264521)
							(end 0.254 0.2286)
						)
						(arc
							(start 0.254 -0.2286)
							(mid 0.239121 -0.264521)
							(end 0.2032 -0.2794)
						)
					)
					(width 0)
					(fill yes)
				)
			)
		)
		(pad "2" smd custom
			(at 0 0.4318 90)
			(size 0.127 0.127)
			(layers "F.Cu" "F.Mask" "F.Paste")
			(net "JTAG_PLD_TDO_D")
			(options
				(clearance outline)
				(anchor circle)
			)
			(primitives
				(gr_poly
					(pts
						(arc
							(start -0.2032 -0.2794)
							(mid -0.239121 -0.264521)
							(end -0.254 -0.2286)
						)
						(arc
							(start -0.254 0.2286)
							(mid -0.239121 0.264521)
							(end -0.2032 0.2794)
						)
						(arc
							(start 0.2032 0.2794)
							(mid 0.239121 0.264521)
							(end 0.254 0.2286)
						)
						(arc
							(start 0.254 -0.2286)
							(mid 0.239121 -0.264521)
							(end 0.2032 -0.2794)
						)
					)
					(width 0)
					(fill yes)
				)
			)
		)
	)
	(footprint ""
		(layer "F.Cu")
		(at 156.718 -20.193)
		(property "Reference" "TP14"
			(at 0 0 0)
			(layer "F.SilkS")
			(hide yes)
			(effects
				(font
					(size 1.27 1.27)
				)
			)
		)
		(property "Value" "TPAD28-1-GP-U"
			(at 0.0508 -1.9304 0)
			(unlocked yes)
			(layer "F.Fab")
			(hide yes)
			(effects
				(font
					(size 1.016 1.016)
					(thickness 0.1524)
				)
			)
		)
		(property "Device Type" "TPAD28-1-U"
			(at 0.0508 -3.4544 0)
			(unlocked yes)
			(layer "F.Fab")
			(hide yes)
			(effects
				(font
					(size 1.016 1.016)
					(thickness 0.1524)
				)
			)
		)
		(duplicate_pad_numbers_are_jumpers no)
		(fp_poly
			(pts
				(arc
					(start 0.3556 0)
					(mid -0.3556 0)
					(end 0.3556 0)
				)
			)
			(stroke
				(width 0)
				(type default)
			)
			(fill no)
			(layer "F.CrtYd")
		)
		(fp_poly
			(pts
				(arc
					(start 0.9525 0)
					(mid -0.9525 0)
					(end 0.9525 0)
				)
			)
			(stroke
				(width 0)
				(type default)
			)
			(fill no)
			(layer "F.Fab")
		)
		(pad "1" smd circle
			(at 0 0)
			(size 0.7112 0.7112)
			(layers "F.Cu" "F.Mask" "F.Paste")
			(net "TP_FPGA_P110")
		)
	)
	(footprint ""
		(layer "F.Cu")
		(at 183.388 -55.626 180)
		(property "Reference" "R200"
			(at 0 0 180)
			(layer "F.SilkS")
			(hide yes)
			(effects
				(font
					(size 1.27 1.27)
				)
			)
		)
		(property "Value" "0R2J-2-GP"
			(at 0.064008 -3.993896 180)
			(unlocked yes)
			(layer "F.Fab")
			(hide yes)
			(effects
				(font
					(size 1.016 1.016)
					(thickness 0.1524)
				)
			)
		)
		(property "Device Type" "R402H16"
			(at 0.064008 -5.517896 180)
			(unlocked yes)
			(layer "F.Fab")
			(hide yes)
			(effects
				(font
					(size 1.016 1.016)
					(thickness 0.1524)
				)
			)
		)
		(duplicate_pad_numbers_are_jumpers no)
		(fp_rect
			(start -0.381 0.8382)
			(end 0.381 -0.8382)
			(stroke
				(width 0)
				(type default)
			)
			(fill no)
			(layer "F.CrtYd")
		)
		(fp_rect
			(start -0.381 0.8382)
			(end 0.381 -0.8382)
			(stroke
				(width 0)
				(type default)
			)
			(fill no)
			(layer "F.Fab")
		)
		(pad "1" smd custom
			(at 0 -0.4318 180)
			(size 0.127 0.127)
			(layers "F.Cu" "F.Mask" "F.Paste")
			(net "PV_VDDR_VREF_A")
			(options
				(clearance outline)
				(anchor circle)
			)
			(primitives
				(gr_poly
					(pts
						(arc
							(start -0.2032 -0.2794)
							(mid -0.239121 -0.264521)
							(end -0.254 -0.2286)
						)
						(arc
							(start -0.254 0.2286)
							(mid -0.239121 0.264521)
							(end -0.2032 0.2794)
						)
						(arc
							(start 0.2032 0.2794)
							(mid 0.239121 0.264521)
							(end 0.254 0.2286)
						)
						(arc
							(start 0.254 -0.2286)
							(mid 0.239121 -0.264521)
							(end 0.2032 -0.2794)
						)
					)
					(width 0)
					(fill yes)
				)
			)
		)
		(pad "2" smd custom
			(at 0 0.4318 180)
			(size 0.127 0.127)
			(layers "F.Cu" "F.Mask" "F.Paste")
			(net "DDR3_M_A_VREF_DQ1")
			(options
				(clearance outline)
				(anchor circle)
			)
			(primitives
				(gr_poly
					(pts
						(arc
							(start -0.2032 -0.2794)
							(mid -0.239121 -0.264521)
							(end -0.254 -0.2286)
						)
						(arc
							(start -0.254 0.2286)
							(mid -0.239121 0.264521)
							(end -0.2032 0.2794)
						)
						(arc
							(start 0.2032 0.2794)
							(mid 0.239121 0.264521)
							(end 0.254 0.2286)
						)
						(arc
							(start 0.254 -0.2286)
							(mid 0.239121 -0.264521)
							(end 0.2032 -0.2794)
						)
					)
					(width 0)
					(fill yes)
				)
			)
		)
	)
	(footprint ""
		(layer "F.Cu")
		(at 45.974 -68.072 180)
		(property "Reference" "PC29"
			(at 0 0 180)
			(layer "F.SilkS")
			(hide yes)
			(effects
				(font
					(size 1.27 1.27)
				)
			)
		)
		(property "Value" "SC47U6D3V5MX-1-GP"
			(at 0 -4.9022 180)
			(unlocked yes)
			(layer "F.Fab")
			(hide yes)
			(effects
				(font
					(size 1.016 1.016)
					(thickness 0.1524)
				)
			)
		)
		(property "Device Type" "C805H54"
			(at 0 -6.8072 180)
			(unlocked yes)
			(layer "F.Fab")
			(hide yes)
			(effects
				(font
					(size 1.016 1.016)
					(thickness 0.1524)
				)
			)
		)
		(duplicate_pad_numbers_are_jumpers no)
		(fp_line
			(start 0.6096 0)
			(end -0.6096 0)
			(stroke
				(width 0.3048)
				(type default)
			)
			(layer "F.SilkS")
		)
		(fp_poly
			(pts
				(xy -0.9017 1.4351) (xy 0.9017 1.4351) (xy 0.9017 -1.4351) (xy -0.9017 -1.4351)
			)
			(stroke
				(width 0)
				(type default)
			)
			(fill no)
			(layer "F.CrtYd")
		)
		(fp_poly
			(pts
				(xy 0.9017 1.4351) (xy 0.9017 -1.4351) (xy -0.9017 -1.4351) (xy -0.9017 1.4351)
			)
			(stroke
				(width 0)
				(type default)
			)
			(fill no)
			(layer "F.Fab")
		)
		(pad "1" smd rect
			(at 0 -0.8382 180)
			(size 1.5494 0.9398)
			(layers "F.Cu" "F.Mask" "F.Paste")
			(net "PVNN")
		)
		(pad "2" smd rect
			(at 0 0.8382 180)
			(size 1.5494 0.9398)
			(layers "F.Cu" "F.Mask" "F.Paste")
			(net "GND")
		)
	)
	(footprint ""
		(layer "F.Cu")
		(at 183.642 -37.338 90)
		(property "Reference" "R96"
			(at 0 0 90)
			(layer "F.SilkS")
			(hide yes)
			(effects
				(font
					(size 1.27 1.27)
				)
			)
		)
		(property "Value" "150R2J-L1-GP-U"
			(at 1.7907 -1.1176 90)
			(unlocked yes)
			(layer "F.Fab")
			(hide yes)
			(effects
				(font
					(size 1.016 1.016)
					(thickness 0.1524)
				)
			)
		)
		(property "Device Type" "R402H16"
			(at 1.7907 -2.6416 90)
			(unlocked yes)
			(layer "F.Fab")
			(hide yes)
			(effects
				(font
					(size 1.016 1.016)
					(thickness 0.1524)
				)
			)
		)
		(duplicate_pad_numbers_are_jumpers no)
		(fp_rect
			(start -0.381 0.8382)
			(end 0.381 -0.8382)
			(stroke
				(width 0)
				(type default)
			)
			(fill no)
			(layer "F.CrtYd")
		)
		(fp_rect
			(start -0.381 0.8382)
			(end 0.381 -0.8382)
			(stroke
				(width 0)
				(type default)
			)
			(fill no)
			(layer "F.Fab")
		)
		(pad "1" smd custom
			(at 0 -0.4318 90)
			(size 0.127 0.127)
			(layers "F.Cu" "F.Mask" "F.Paste")
			(net "SVID_CPU_CLK")
			(options
				(clearance outline)
				(anchor circle)
			)
			(primitives
				(gr_poly
					(pts
						(arc
							(start -0.2032 -0.2794)
							(mid -0.239121 -0.264521)
							(end -0.254 -0.2286)
						)
						(arc
							(start -0.254 0.2286)
							(mid -0.239121 0.264521)
							(end -0.2032 0.2794)
						)
						(arc
							(start 0.2032 0.2794)
							(mid 0.239121 0.264521)
							(end 0.254 0.2286)
						)
						(arc
							(start 0.254 -0.2286)
							(mid 0.239121 -0.264521)
							(end 0.2032 -0.2794)
						)
					)
					(width 0)
					(fill yes)
				)
			)
		)
		(pad "2" smd custom
			(at 0 0.4318 90)
			(size 0.127 0.127)
			(layers "F.Cu" "F.Mask" "F.Paste")
			(net "SVID_CLK_A")
			(options
				(clearance outline)
				(anchor circle)
			)
			(primitives
				(gr_poly
					(pts
						(arc
							(start -0.2032 -0.2794)
							(mid -0.239121 -0.264521)
							(end -0.254 -0.2286)
						)
						(arc
							(start -0.254 0.2286)
							(mid -0.239121 0.264521)
							(end -0.2032 0.2794)
						)
						(arc
							(start 0.2032 0.2794)
							(mid 0.239121 0.264521)
							(end 0.254 0.2286)
						)
						(arc
							(start 0.254 -0.2286)
							(mid 0.239121 -0.264521)
							(end 0.2032 -0.2794)
						)
					)
					(width 0)
					(fill yes)
				)
			)
		)
	)
	(footprint ""
		(layer "F.Cu")
		(at 182.5498 -31.7246 180)
		(property "Reference" "PR149"
			(at 0 0 180)
			(layer "F.SilkS")
			(hide yes)
			(effects
				(font
					(size 1.27 1.27)
				)
			)
		)
		(property "Value" "1KR2F-3-GP"
			(at 1.7907 -1.1176 180)
			(unlocked yes)
			(layer "F.Fab")
			(hide yes)
			(effects
				(font
					(size 1.016 1.016)
					(thickness 0.1524)
				)
			)
		)
		(property "Device Type" "R402H16"
			(at 1.7907 -2.6416 180)
			(unlocked yes)
			(layer "F.Fab")
			(hide yes)
			(effects
				(font
					(size 1.016 1.016)
					(thickness 0.1524)
				)
			)
		)
		(duplicate_pad_numbers_are_jumpers no)
		(fp_rect
			(start -0.381 0.8382)
			(end 0.381 -0.8382)
			(stroke
				(width 0)
				(type default)
			)
			(fill no)
			(layer "F.CrtYd")
		)
		(fp_rect
			(start -0.381 0.8382)
			(end 0.381 -0.8382)
			(stroke
				(width 0)
				(type default)
			)
			(fill no)
			(layer "F.Fab")
		)
		(pad "1" smd custom
			(at 0 -0.4318 180)
			(size 0.127 0.127)
			(layers "F.Cu" "F.Mask" "F.Paste")
			(net "VR_PVDDR_A_COMP")
			(options
				(clearance outline)
				(anchor circle)
			)
			(primitives
				(gr_poly
					(pts
						(arc
							(start -0.2032 -0.2794)
							(mid -0.239121 -0.264521)
							(end -0.254 -0.2286)
						)
						(arc
							(start -0.254 0.2286)
							(mid -0.239121 0.264521)
							(end -0.2032 0.2794)
						)
						(arc
							(start 0.2032 0.2794)
							(mid 0.239121 0.264521)
							(end 0.254 0.2286)
						)
						(arc
							(start 0.254 -0.2286)
							(mid 0.239121 -0.264521)
							(end 0.2032 -0.2794)
						)
					)
					(width 0)
					(fill yes)
				)
			)
		)
		(pad "2" smd custom
			(at 0 0.4318 180)
			(size 0.127 0.127)
			(layers "F.Cu" "F.Mask" "F.Paste")
			(net "GND")
			(options
				(clearance outline)
				(anchor circle)
			)
			(primitives
				(gr_poly
					(pts
						(arc
							(start -0.2032 -0.2794)
							(mid -0.239121 -0.264521)
							(end -0.254 -0.2286)
						)
						(arc
							(start -0.254 0.2286)
							(mid -0.239121 0.264521)
							(end -0.2032 0.2794)
						)
						(arc
							(start 0.2032 0.2794)
							(mid 0.239121 0.264521)
							(end 0.254 0.2286)
						)
						(arc
							(start 0.254 -0.2286)
							(mid 0.239121 -0.264521)
							(end 0.2032 -0.2794)
						)
					)
					(width 0)
					(fill yes)
				)
			)
		)
	)
	(footprint ""
		(layer "F.Cu")
		(at 31.0896 -57.9374 -90)
		(property "Reference" "PC12"
			(at 0 0 270)
			(layer "F.SilkS")
			(hide yes)
			(effects
				(font
					(size 1.27 1.27)
				)
			)
		)
		(property "Value" "SC47U16V0MX-GP"
			(at -2.3368 -3.5052 270)
			(unlocked yes)
			(layer "F.Fab")
			(hide yes)
			(effects
				(font
					(size 1.016 1.016)
					(thickness 0.1524)
				)
			)
		)
		(property "Device Type" "C1210H107"
			(at -2.3368 -5.0292 270)
			(unlocked yes)
			(layer "F.Fab")
			(hide yes)
			(effects
				(font
					(size 1.016 1.016)
					(thickness 0.1524)
				)
			)
		)
		(duplicate_pad_numbers_are_jumpers no)
		(fp_rect
			(start -1.4986 1.9685)
			(end 1.4986 -1.9685)
			(stroke
				(width 0)
				(type default)
			)
			(fill no)
			(layer "F.CrtYd")
		)
		(fp_rect
			(start -1.4986 1.9685)
			(end 1.4986 -1.9685)
			(stroke
				(width 0)
				(type default)
			)
			(fill no)
			(layer "F.Fab")
		)
		(pad "1" smd rect
			(at 0 -1.2446 270)
			(size 2.7432 1.1938)
			(layers "F.Cu" "F.Mask" "F.Paste")
			(net "VR_FET_SW_P12V_PVCCP_PVNN")
		)
		(pad "2" smd rect
			(at 0 1.2446 270)
			(size 2.7432 1.1938)
			(layers "F.Cu" "F.Mask" "F.Paste")
			(net "GND")
		)
	)
	(footprint ""
		(layer "F.Cu")
		(at 183.642 -38.862 -90)
		(property "Reference" "PR126"
			(at 0 0 270)
			(layer "F.SilkS")
			(hide yes)
			(effects
				(font
					(size 1.27 1.27)
				)
			)
		)
		(property "Value" "10D7R2F-GP"
			(at 1.7907 -1.1176 270)
			(unlocked yes)
			(layer "F.Fab")
			(hide yes)
			(effects
				(font
					(size 1.016 1.016)
					(thickness 0.1524)
				)
			)
		)
		(property "Device Type" "R402H16"
			(at 1.7907 -2.6416 270)
			(unlocked yes)
			(layer "F.Fab")
			(hide yes)
			(effects
				(font
					(size 1.016 1.016)
					(thickness 0.1524)
				)
			)
		)
		(duplicate_pad_numbers_are_jumpers no)
		(fp_rect
			(start -0.381 0.8382)
			(end 0.381 -0.8382)
			(stroke
				(width 0)
				(type default)
			)
			(fill no)
			(layer "F.CrtYd")
		)
		(fp_rect
			(start -0.381 0.8382)
			(end 0.381 -0.8382)
			(stroke
				(width 0)
				(type default)
			)
			(fill no)
			(layer "F.Fab")
		)
		(pad "1" smd custom
			(at 0 -0.4318 270)
			(size 0.127 0.127)
			(layers "F.Cu" "F.Mask" "F.Paste")
			(net "SVID_DIO_A")
			(options
				(clearance outline)
				(anchor circle)
			)
			(primitives
				(gr_poly
					(pts
						(arc
							(start -0.2032 -0.2794)
							(mid -0.239121 -0.264521)
							(end -0.254 -0.2286)
						)
						(arc
							(start -0.254 0.2286)
							(mid -0.239121 0.264521)
							(end -0.2032 0.2794)
						)
						(arc
							(start 0.2032 0.2794)
							(mid 0.239121 0.264521)
							(end 0.254 0.2286)
						)
						(arc
							(start 0.254 -0.2286)
							(mid 0.239121 -0.264521)
							(end 0.2032 -0.2794)
						)
					)
					(width 0)
					(fill yes)
				)
			)
		)
		(pad "2" smd custom
			(at 0 0.4318 270)
			(size 0.127 0.127)
			(layers "F.Cu" "F.Mask" "F.Paste")
			(net "SVID_CPU_DATA")
			(options
				(clearance outline)
				(anchor circle)
			)
			(primitives
				(gr_poly
					(pts
						(arc
							(start -0.2032 -0.2794)
							(mid -0.239121 -0.264521)
							(end -0.254 -0.2286)
						)
						(arc
							(start -0.254 0.2286)
							(mid -0.239121 0.264521)
							(end -0.2032 0.2794)
						)
						(arc
							(start 0.2032 0.2794)
							(mid 0.239121 0.264521)
							(end 0.254 0.2286)
						)
						(arc
							(start 0.254 -0.2286)
							(mid 0.239121 -0.264521)
							(end 0.2032 -0.2794)
						)
					)
					(width 0)
					(fill yes)
				)
			)
		)
	)
	(footprint ""
		(layer "F.Cu")
		(at 26.035 -43.434 180)
		(property "Reference" "PC73"
			(at 0 0 180)
			(layer "F.SilkS")
			(hide yes)
			(effects
				(font
					(size 1.27 1.27)
				)
			)
		)
		(property "Value" "SC100U6D3V6MX-GP"
			(at 0.0127 -3.4671 180)
			(unlocked yes)
			(layer "F.Fab")
			(hide yes)
			(effects
				(font
					(size 1.016 1.016)
					(thickness 0.1524)
				)
			)
		)
		(property "Device Type" "C1206H71"
			(at 0.0127 -4.9911 180)
			(unlocked yes)
			(layer "F.Fab")
			(hide yes)
			(effects
				(font
					(size 1.016 1.016)
					(thickness 0.1524)
				)
			)
		)
		(duplicate_pad_numbers_are_jumpers no)
		(fp_rect
			(start -1.0541 1.9812)
			(end 1.0541 -1.9812)
			(stroke
				(width 0)
				(type default)
			)
			(fill no)
			(layer "F.CrtYd")
		)
		(fp_rect
			(start -1.0541 1.9812)
			(end 1.0541 -1.9812)
			(stroke
				(width 0)
				(type default)
			)
			(fill no)
			(layer "F.Fab")
		)
		(pad "1" smd rect
			(at 0 -1.3462 180)
			(size 1.8542 1.016)
			(layers "F.Cu" "F.Mask" "F.Paste")
			(net "P3V3_STBY_OUT")
		)
		(pad "2" smd rect
			(at 0 1.3462 180)
			(size 1.8542 1.016)
			(layers "F.Cu" "F.Mask" "F.Paste")
			(net "GND")
		)
	)
	(footprint ""
		(layer "F.Cu")
		(at 50.8 -46.355)
		(property "Reference" "R56"
			(at 0 0 0)
			(layer "F.SilkS")
			(hide yes)
			(effects
				(font
					(size 1.27 1.27)
				)
			)
		)
		(property "Value" "0R2J-2-GP"
			(at 0.064008 -3.993896 0)
			(unlocked yes)
			(layer "F.Fab")
			(hide yes)
			(effects
				(font
					(size 1.016 1.016)
					(thickness 0.1524)
				)
			)
		)
		(property "Device Type" "R402H16"
			(at 0.064008 -5.517896 0)
			(unlocked yes)
			(layer "F.Fab")
			(hide yes)
			(effects
				(font
					(size 1.016 1.016)
					(thickness 0.1524)
				)
			)
		)
		(duplicate_pad_numbers_are_jumpers no)
		(fp_rect
			(start -0.381 0.8382)
			(end 0.381 -0.8382)
			(stroke
				(width 0)
				(type default)
			)
			(fill no)
			(layer "F.CrtYd")
		)
		(fp_rect
			(start -0.381 0.8382)
			(end 0.381 -0.8382)
			(stroke
				(width 0)
				(type default)
			)
			(fill no)
			(layer "F.Fab")
		)
		(pad "1" smd custom
			(at 0 -0.4318)
			(size 0.127 0.127)
			(layers "F.Cu" "F.Mask" "F.Paste")
			(net "P1V0_STBY_PG")
			(options
				(clearance outline)
				(anchor circle)
			)
			(primitives
				(gr_poly
					(pts
						(arc
							(start -0.2032 -0.2794)
							(mid -0.239121 -0.264521)
							(end -0.254 -0.2286)
						)
						(arc
							(start -0.254 0.2286)
							(mid -0.239121 0.264521)
							(end -0.2032 0.2794)
						)
						(arc
							(start 0.2032 0.2794)
							(mid 0.239121 0.264521)
							(end 0.254 0.2286)
						)
						(arc
							(start 0.254 -0.2286)
							(mid 0.239121 -0.264521)
							(end 0.2032 -0.2794)
						)
					)
					(width 0)
					(fill yes)
				)
			)
		)
		(pad "2" smd custom
			(at 0 0.4318)
			(size 0.127 0.127)
			(layers "F.Cu" "F.Mask" "F.Paste")
			(net "SW_P3V3_CPU_LV_G2")
			(options
				(clearance outline)
				(anchor circle)
			)
			(primitives
				(gr_poly
					(pts
						(arc
							(start -0.2032 -0.2794)
							(mid -0.239121 -0.264521)
							(end -0.254 -0.2286)
						)
						(arc
							(start -0.254 0.2286)
							(mid -0.239121 0.264521)
							(end -0.2032 0.2794)
						)
						(arc
							(start 0.2032 0.2794)
							(mid 0.239121 0.264521)
							(end 0.254 0.2286)
						)
						(arc
							(start 0.254 -0.2286)
							(mid 0.239121 -0.264521)
							(end 0.2032 -0.2794)
						)
					)
					(width 0)
					(fill yes)
				)
			)
		)
	)
	(footprint ""
		(layer "F.Cu")
		(at 78.867 -59.944 180)
		(property "Reference" "C83"
			(at 0 0 180)
			(layer "F.SilkS")
			(hide yes)
			(effects
				(font
					(size 1.27 1.27)
				)
			)
		)
		(property "Value" "SCD1U16V2KX-3GP"
			(at 1.8923 -1.2065 180)
			(unlocked yes)
			(layer "F.Fab")
			(hide yes)
			(effects
				(font
					(size 1.016 1.016)
					(thickness 0.1524)
				)
			)
		)
		(property "Device Type" "C402H22"
			(at 1.8923 -2.7305 180)
			(unlocked yes)
			(layer "F.Fab")
			(hide yes)
			(effects
				(font
					(size 1.016 1.016)
					(thickness 0.1524)
				)
			)
		)
		(duplicate_pad_numbers_are_jumpers no)
		(fp_rect
			(start -0.381 0.7366)
			(end 0.381 -0.7366)
			(stroke
				(width 0)
				(type default)
			)
			(fill no)
			(layer "F.CrtYd")
		)
		(fp_rect
			(start -0.381 0.7366)
			(end 0.381 -0.7366)
			(stroke
				(width 0)
				(type default)
			)
			(fill no)
			(layer "F.Fab")
		)
		(pad "1" smd custom
			(at 0 -0.4572 180)
			(size 0.1143 0.1143)
			(layers "F.Cu" "F.Mask" "F.Paste")
			(net "VOL1_SEN_VREF")
			(options
				(clearance outline)
				(anchor circle)
			)
			(primitives
				(gr_poly
					(pts
						(arc
							(start -0.254 -0.1778)
							(mid -0.239121 -0.213721)
							(end -0.2032 -0.2286)
						)
						(arc
							(start 0.2032 -0.2286)
							(mid 0.239121 -0.213721)
							(end 0.254 -0.1778)
						)
						(arc
							(start 0.254 0.1778)
							(mid 0.239121 0.213721)
							(end 0.2032 0.2286)
						)
						(arc
							(start -0.2032 0.2286)
							(mid -0.239121 0.213721)
							(end -0.254 0.1778)
						)
					)
					(width 0)
					(fill yes)
				)
			)
		)
		(pad "2" smd custom
			(at 0 0.4572 180)
			(size 0.1143 0.1143)
			(layers "F.Cu" "F.Mask" "F.Paste")
			(net "GND")
			(options
				(clearance outline)
				(anchor circle)
			)
			(primitives
				(gr_poly
					(pts
						(arc
							(start -0.254 -0.1778)
							(mid -0.239121 -0.213721)
							(end -0.2032 -0.2286)
						)
						(arc
							(start 0.2032 -0.2286)
							(mid 0.239121 -0.213721)
							(end 0.254 -0.1778)
						)
						(arc
							(start 0.254 0.1778)
							(mid 0.239121 0.213721)
							(end 0.2032 0.2286)
						)
						(arc
							(start -0.2032 0.2286)
							(mid -0.239121 0.213721)
							(end -0.254 0.1778)
						)
					)
					(width 0)
					(fill yes)
				)
			)
		)
	)
	(footprint ""
		(layer "F.Cu")
		(at 185.039 -13.716 90)
		(property "Reference" "PC119"
			(at 0 0 90)
			(layer "F.SilkS")
			(hide yes)
			(effects
				(font
					(size 1.27 1.27)
				)
			)
		)
		(property "Value" "SC10U6D3V3MX-GP"
			(at 0 -2.8194 90)
			(unlocked yes)
			(layer "F.Fab")
			(hide yes)
			(effects
				(font
					(size 1.016 1.016)
					(thickness 0.1524)
				)
			)
		)
		(property "Device Type" "C603H38"
			(at 0 -4.3434 90)
			(unlocked yes)
			(layer "F.Fab")
			(hide yes)
			(effects
				(font
					(size 1.016 1.016)
					(thickness 0.1524)
				)
			)
		)
		(duplicate_pad_numbers_are_jumpers no)
		(fp_line
			(start -0.4064 0)
			(end 0.4064 0)
			(stroke
				(width 0.2286)
				(type default)
			)
			(layer "F.SilkS")
		)
		(fp_rect
			(start -0.635 1.1811)
			(end 0.635 -1.1811)
			(stroke
				(width 0)
				(type default)
			)
			(fill no)
			(layer "F.CrtYd")
		)
		(fp_rect
			(start -0.635 1.1811)
			(end 0.635 -1.1811)
			(stroke
				(width 0)
				(type default)
			)
			(fill no)
			(layer "F.Fab")
		)
		(pad "1" smd custom
			(at 0 -0.6604 90)
			(size 0.19685 0.19685)
			(layers "F.Cu" "F.Mask" "F.Paste")
			(net "GND")
			(options
				(clearance outline)
				(anchor circle)
			)
			(primitives
				(gr_poly
					(pts
						(arc
							(start 0.508 -0.2921)
							(mid 0.478242 -0.363942)
							(end 0.4064 -0.3937)
						)
						(arc
							(start -0.4064 -0.3937)
							(mid -0.478242 -0.363942)
							(end -0.508 -0.2921)
						)
						(arc
							(start -0.508 0.2921)
							(mid -0.478242 0.363942)
							(end -0.4064 0.3937)
						)
						(arc
							(start 0.4064 0.3937)
							(mid 0.478242 0.363942)
							(end 0.508 0.2921)
						)
					)
					(width 0)
					(fill yes)
				)
			)
		)
		(pad "2" smd custom
			(at 0 0.6604 90)
			(size 0.19685 0.19685)
			(layers "F.Cu" "F.Mask" "F.Paste")
			(net "PV_VTT_DDR_B")
			(options
				(clearance outline)
				(anchor circle)
			)
			(primitives
				(gr_poly
					(pts
						(arc
							(start 0.508 -0.2921)
							(mid 0.478242 -0.363942)
							(end 0.4064 -0.3937)
						)
						(arc
							(start -0.4064 -0.3937)
							(mid -0.478242 -0.363942)
							(end -0.508 -0.2921)
						)
						(arc
							(start -0.508 0.2921)
							(mid -0.478242 0.363942)
							(end -0.4064 0.3937)
						)
						(arc
							(start 0.4064 0.3937)
							(mid 0.478242 0.363942)
							(end 0.508 0.2921)
						)
					)
					(width 0)
					(fill yes)
				)
			)
		)
	)
	(footprint ""
		(layer "F.Cu")
		(at 43.0022 -49.1744 -90)
		(property "Reference" "R43"
			(at 0 0 270)
			(layer "F.SilkS")
			(hide yes)
			(effects
				(font
					(size 1.27 1.27)
				)
			)
		)
		(property "Value" "30KR2F-GP"
			(at 0.064008 -3.993896 270)
			(unlocked yes)
			(layer "F.Fab")
			(hide yes)
			(effects
				(font
					(size 1.016 1.016)
					(thickness 0.1524)
				)
			)
		)
		(property "Device Type" "R402H16"
			(at 0.064008 -5.517896 270)
			(unlocked yes)
			(layer "F.Fab")
			(hide yes)
			(effects
				(font
					(size 1.016 1.016)
					(thickness 0.1524)
				)
			)
		)
		(duplicate_pad_numbers_are_jumpers no)
		(fp_rect
			(start -0.381 0.8382)
			(end 0.381 -0.8382)
			(stroke
				(width 0)
				(type default)
			)
			(fill no)
			(layer "F.CrtYd")
		)
		(fp_rect
			(start -0.381 0.8382)
			(end 0.381 -0.8382)
			(stroke
				(width 0)
				(type default)
			)
			(fill no)
			(layer "F.Fab")
		)
		(pad "1" smd custom
			(at 0 -0.4318 270)
			(size 0.127 0.127)
			(layers "F.Cu" "F.Mask" "F.Paste")
			(net "P3V3_CPU")
			(options
				(clearance outline)
				(anchor circle)
			)
			(primitives
				(gr_poly
					(pts
						(arc
							(start -0.2032 -0.2794)
							(mid -0.239121 -0.264521)
							(end -0.254 -0.2286)
						)
						(arc
							(start -0.254 0.2286)
							(mid -0.239121 0.264521)
							(end -0.2032 0.2794)
						)
						(arc
							(start 0.2032 0.2794)
							(mid 0.239121 0.264521)
							(end 0.254 0.2286)
						)
						(arc
							(start 0.254 -0.2286)
							(mid 0.239121 -0.264521)
							(end 0.2032 -0.2794)
						)
					)
					(width 0)
					(fill yes)
				)
			)
		)
		(pad "2" smd custom
			(at 0 0.4318 270)
			(size 0.127 0.127)
			(layers "F.Cu" "F.Mask" "F.Paste")
			(net "P3V3_CPU_DELAY_IN")
			(options
				(clearance outline)
				(anchor circle)
			)
			(primitives
				(gr_poly
					(pts
						(arc
							(start -0.2032 -0.2794)
							(mid -0.239121 -0.264521)
							(end -0.254 -0.2286)
						)
						(arc
							(start -0.254 0.2286)
							(mid -0.239121 0.264521)
							(end -0.2032 0.2794)
						)
						(arc
							(start 0.2032 0.2794)
							(mid 0.239121 0.264521)
							(end 0.254 0.2286)
						)
						(arc
							(start 0.254 -0.2286)
							(mid 0.239121 -0.264521)
							(end 0.2032 -0.2794)
						)
					)
					(width 0)
					(fill yes)
				)
			)
		)
	)
	(footprint ""
		(layer "F.Cu")
		(at 141.0462 -53.2384)
		(property "Reference" "C356"
			(at 0 0 0)
			(layer "F.SilkS")
			(hide yes)
			(effects
				(font
					(size 1.27 1.27)
				)
			)
		)
		(property "Value" "SCD1U16V2KX-3GP"
			(at 1.8923 -1.2065 0)
			(unlocked yes)
			(layer "F.Fab")
			(hide yes)
			(effects
				(font
					(size 1.016 1.016)
					(thickness 0.1524)
				)
			)
		)
		(property "Device Type" "C402H22"
			(at 1.8923 -2.7305 0)
			(unlocked yes)
			(layer "F.Fab")
			(hide yes)
			(effects
				(font
					(size 1.016 1.016)
					(thickness 0.1524)
				)
			)
		)
		(duplicate_pad_numbers_are_jumpers no)
		(fp_rect
			(start -0.381 0.7366)
			(end 0.381 -0.7366)
			(stroke
				(width 0)
				(type default)
			)
			(fill no)
			(layer "F.CrtYd")
		)
		(fp_rect
			(start -0.381 0.7366)
			(end 0.381 -0.7366)
			(stroke
				(width 0)
				(type default)
			)
			(fill no)
			(layer "F.Fab")
		)
		(pad "1" smd custom
			(at 0 -0.4572)
			(size 0.1143 0.1143)
			(layers "F.Cu" "F.Mask" "F.Paste")
			(net "P3V3_STBY")
			(options
				(clearance outline)
				(anchor circle)
			)
			(primitives
				(gr_poly
					(pts
						(arc
							(start -0.254 -0.1778)
							(mid -0.239121 -0.213721)
							(end -0.2032 -0.2286)
						)
						(arc
							(start 0.2032 -0.2286)
							(mid 0.239121 -0.213721)
							(end 0.254 -0.1778)
						)
						(arc
							(start 0.254 0.1778)
							(mid 0.239121 0.213721)
							(end 0.2032 0.2286)
						)
						(arc
							(start -0.2032 0.2286)
							(mid -0.239121 0.213721)
							(end -0.254 0.1778)
						)
					)
					(width 0)
					(fill yes)
				)
			)
		)
		(pad "2" smd custom
			(at 0 0.4572)
			(size 0.1143 0.1143)
			(layers "F.Cu" "F.Mask" "F.Paste")
			(net "GND")
			(options
				(clearance outline)
				(anchor circle)
			)
			(primitives
				(gr_poly
					(pts
						(arc
							(start -0.254 -0.1778)
							(mid -0.239121 -0.213721)
							(end -0.2032 -0.2286)
						)
						(arc
							(start 0.2032 -0.2286)
							(mid 0.239121 -0.213721)
							(end 0.254 -0.1778)
						)
						(arc
							(start 0.254 0.1778)
							(mid 0.239121 0.213721)
							(end 0.2032 0.2286)
						)
						(arc
							(start -0.2032 0.2286)
							(mid -0.239121 0.213721)
							(end -0.254 0.1778)
						)
					)
					(width 0)
					(fill yes)
				)
			)
		)
	)
	(footprint ""
		(layer "F.Cu")
		(at 30.861 -33.02 180)
		(property "Reference" "C120"
			(at 0 0 180)
			(layer "F.SilkS")
			(hide yes)
			(effects
				(font
					(size 1.27 1.27)
				)
			)
		)
		(property "Value" "SCD1U16V2KX-3GP"
			(at 1.1811 -2.7051 180)
			(unlocked yes)
			(layer "F.Fab")
			(hide yes)
			(effects
				(font
					(size 1.016 1.016)
					(thickness 0.1524)
				)
			)
		)
		(property "Device Type" "C402H22"
			(at 1.1811 -4.2291 180)
			(unlocked yes)
			(layer "F.Fab")
			(hide yes)
			(effects
				(font
					(size 1.016 1.016)
					(thickness 0.1524)
				)
			)
		)
		(duplicate_pad_numbers_are_jumpers no)
		(fp_rect
			(start -0.381 0.7366)
			(end 0.381 -0.7366)
			(stroke
				(width 0)
				(type default)
			)
			(fill no)
			(layer "F.CrtYd")
		)
		(fp_rect
			(start -0.381 0.7366)
			(end 0.381 -0.7366)
			(stroke
				(width 0)
				(type default)
			)
			(fill no)
			(layer "F.Fab")
		)
		(pad "1" smd custom
			(at 0 -0.4572 180)
			(size 0.1143 0.1143)
			(layers "F.Cu" "F.Mask" "F.Paste")
			(net "XDP_RST_BTN_R#")
			(options
				(clearance outline)
				(anchor circle)
			)
			(primitives
				(gr_poly
					(pts
						(arc
							(start -0.254 -0.1778)
							(mid -0.239121 -0.213721)
							(end -0.2032 -0.2286)
						)
						(arc
							(start 0.2032 -0.2286)
							(mid 0.239121 -0.213721)
							(end 0.254 -0.1778)
						)
						(arc
							(start 0.254 0.1778)
							(mid 0.239121 0.213721)
							(end 0.2032 0.2286)
						)
						(arc
							(start -0.2032 0.2286)
							(mid -0.239121 0.213721)
							(end -0.254 0.1778)
						)
					)
					(width 0)
					(fill yes)
				)
			)
		)
		(pad "2" smd custom
			(at 0 0.4572 180)
			(size 0.1143 0.1143)
			(layers "F.Cu" "F.Mask" "F.Paste")
			(net "GND")
			(options
				(clearance outline)
				(anchor circle)
			)
			(primitives
				(gr_poly
					(pts
						(arc
							(start -0.254 -0.1778)
							(mid -0.239121 -0.213721)
							(end -0.2032 -0.2286)
						)
						(arc
							(start 0.2032 -0.2286)
							(mid 0.239121 -0.213721)
							(end 0.254 -0.1778)
						)
						(arc
							(start 0.254 0.1778)
							(mid 0.239121 0.213721)
							(end 0.2032 0.2286)
						)
						(arc
							(start -0.2032 0.2286)
							(mid -0.239121 0.213721)
							(end -0.254 0.1778)
						)
					)
					(width 0)
					(fill yes)
				)
			)
		)
	)
	(footprint ""
		(layer "F.Cu")
		(at 118.237 -36.084002 180)
		(property "Reference" "PR117"
			(at 0 0 180)
			(layer "F.SilkS")
			(hide yes)
			(effects
				(font
					(size 1.27 1.27)
				)
			)
		)
		(property "Value" "10R2F-L-GP"
			(at 0.064008 -3.993896 180)
			(unlocked yes)
			(layer "F.Fab")
			(hide yes)
			(effects
				(font
					(size 1.016 1.016)
					(thickness 0.1524)
				)
			)
		)
		(property "Device Type" "R402H14"
			(at 0.064008 -5.517896 180)
			(unlocked yes)
			(layer "F.Fab")
			(hide yes)
			(effects
				(font
					(size 1.016 1.016)
					(thickness 0.1524)
				)
			)
		)
		(duplicate_pad_numbers_are_jumpers no)
		(fp_rect
			(start -0.381 0.8382)
			(end 0.381 -0.8382)
			(stroke
				(width 0)
				(type default)
			)
			(fill no)
			(layer "F.CrtYd")
		)
		(fp_rect
			(start -0.381 0.8382)
			(end 0.381 -0.8382)
			(stroke
				(width 0)
				(type default)
			)
			(fill no)
			(layer "F.Fab")
		)
		(pad "1" smd custom
			(at 0 -0.4318 180)
			(size 0.127 0.127)
			(layers "F.Cu" "F.Mask" "F.Paste")
			(net "PVCCP")
			(options
				(clearance outline)
				(anchor circle)
			)
			(primitives
				(gr_poly
					(pts
						(arc
							(start -0.2032 -0.2794)
							(mid -0.239121 -0.264521)
							(end -0.254 -0.2286)
						)
						(arc
							(start -0.254 0.2286)
							(mid -0.239121 0.264521)
							(end -0.2032 0.2794)
						)
						(arc
							(start 0.2032 0.2794)
							(mid 0.239121 0.264521)
							(end 0.254 0.2286)
						)
						(arc
							(start 0.254 -0.2286)
							(mid 0.239121 -0.264521)
							(end 0.2032 -0.2794)
						)
					)
					(width 0)
					(fill yes)
				)
			)
		)
		(pad "2" smd custom
			(at 0 0.4318 180)
			(size 0.127 0.127)
			(layers "F.Cu" "F.Mask" "F.Paste")
			(net "VR_PVCCP_VSEN")
			(options
				(clearance outline)
				(anchor circle)
			)
			(primitives
				(gr_poly
					(pts
						(arc
							(start -0.2032 -0.2794)
							(mid -0.239121 -0.264521)
							(end -0.254 -0.2286)
						)
						(arc
							(start -0.254 0.2286)
							(mid -0.239121 0.264521)
							(end -0.2032 0.2794)
						)
						(arc
							(start 0.2032 0.2794)
							(mid 0.239121 0.264521)
							(end 0.254 0.2286)
						)
						(arc
							(start 0.254 -0.2286)
							(mid 0.239121 -0.264521)
							(end 0.2032 -0.2794)
						)
					)
					(width 0)
					(fill yes)
				)
			)
		)
	)
	(footprint ""
		(layer "F.Cu")
		(at 161.036 -35.052 180)
		(property "Reference" "R164"
			(at 0 0 180)
			(layer "F.SilkS")
			(hide yes)
			(effects
				(font
					(size 1.27 1.27)
				)
			)
		)
		(property "Value" "10KR2F-2-GP"
			(at 0.064008 -3.993896 180)
			(unlocked yes)
			(layer "F.Fab")
			(hide yes)
			(effects
				(font
					(size 1.016 1.016)
					(thickness 0.1524)
				)
			)
		)
		(property "Device Type" "R402H16"
			(at 0.064008 -5.517896 180)
			(unlocked yes)
			(layer "F.Fab")
			(hide yes)
			(effects
				(font
					(size 1.016 1.016)
					(thickness 0.1524)
				)
			)
		)
		(duplicate_pad_numbers_are_jumpers no)
		(fp_rect
			(start -0.381 0.8382)
			(end 0.381 -0.8382)
			(stroke
				(width 0)
				(type default)
			)
			(fill no)
			(layer "F.CrtYd")
		)
		(fp_rect
			(start -0.381 0.8382)
			(end 0.381 -0.8382)
			(stroke
				(width 0)
				(type default)
			)
			(fill no)
			(layer "F.Fab")
		)
		(pad "1" smd custom
			(at 0 -0.4318 180)
			(size 0.127 0.127)
			(layers "F.Cu" "F.Mask" "F.Paste")
			(net "DISABLE")
			(options
				(clearance outline)
				(anchor circle)
			)
			(primitives
				(gr_poly
					(pts
						(arc
							(start -0.2032 -0.2794)
							(mid -0.239121 -0.264521)
							(end -0.254 -0.2286)
						)
						(arc
							(start -0.254 0.2286)
							(mid -0.239121 0.264521)
							(end -0.2032 0.2794)
						)
						(arc
							(start 0.2032 0.2794)
							(mid 0.239121 0.264521)
							(end 0.254 0.2286)
						)
						(arc
							(start 0.254 -0.2286)
							(mid 0.239121 -0.264521)
							(end 0.2032 -0.2794)
						)
					)
					(width 0)
					(fill yes)
				)
			)
		)
		(pad "2" smd custom
			(at 0 0.4318 180)
			(size 0.127 0.127)
			(layers "F.Cu" "F.Mask" "F.Paste")
			(net "GND")
			(options
				(clearance outline)
				(anchor circle)
			)
			(primitives
				(gr_poly
					(pts
						(arc
							(start -0.2032 -0.2794)
							(mid -0.239121 -0.264521)
							(end -0.254 -0.2286)
						)
						(arc
							(start -0.254 0.2286)
							(mid -0.239121 0.264521)
							(end -0.2032 0.2794)
						)
						(arc
							(start 0.2032 0.2794)
							(mid 0.239121 0.264521)
							(end 0.254 0.2286)
						)
						(arc
							(start 0.254 -0.2286)
							(mid 0.239121 -0.264521)
							(end 0.2032 -0.2794)
						)
					)
					(width 0)
					(fill yes)
				)
			)
		)
	)
	(footprint ""
		(layer "F.Cu")
		(at 86.106 -15.113)
		(property "Reference" "PC199"
			(at 0 0 0)
			(layer "F.SilkS")
			(hide yes)
			(effects
				(font
					(size 1.27 1.27)
				)
			)
		)
		(property "Value" "SC10U6D3V5KX-4GP"
			(at -0.0762 -6.1214 0)
			(unlocked yes)
			(layer "F.Fab")
			(hide yes)
			(effects
				(font
					(size 1.016 1.016)
					(thickness 0.1524)
				)
			)
		)
		(property "Device Type" "C805H58"
			(at -0.0762 -8.1534 0)
			(unlocked yes)
			(layer "F.Fab")
			(hide yes)
			(effects
				(font
					(size 1.016 1.016)
					(thickness 0.1524)
				)
			)
		)
		(duplicate_pad_numbers_are_jumpers no)
		(fp_line
			(start 0.6096 0)
			(end -0.6096 0)
			(stroke
				(width 0.3048)
				(type default)
			)
			(layer "F.SilkS")
		)
		(fp_poly
			(pts
				(xy -0.9017 1.4351) (xy 0.9017 1.4351) (xy 0.9017 -1.4351) (xy -0.9017 -1.4351)
			)
			(stroke
				(width 0)
				(type default)
			)
			(fill no)
			(layer "F.CrtYd")
		)
		(fp_poly
			(pts
				(xy 0.9017 1.4351) (xy 0.9017 -1.4351) (xy -0.9017 -1.4351) (xy -0.9017 1.4351)
			)
			(stroke
				(width 0)
				(type default)
			)
			(fill no)
			(layer "F.Fab")
		)
		(pad "1" smd rect
			(at 0 -0.8382)
			(size 1.5494 0.9398)
			(layers "F.Cu" "F.Mask" "F.Paste")
			(net "TPS74801_1V35_OUT")
		)
		(pad "2" smd rect
			(at 0 0.8382)
			(size 1.5494 0.9398)
			(layers "F.Cu" "F.Mask" "F.Paste")
			(net "GND")
		)
	)
	(footprint ""
		(layer "F.Cu")
		(at 40.767 -50.419 180)
		(property "Reference" "R132"
			(at 0 0 180)
			(layer "F.SilkS")
			(hide yes)
			(effects
				(font
					(size 1.27 1.27)
				)
			)
		)
		(property "Value" "2D2R3J-2-GP"
			(at -0.0254 -2.0193 180)
			(unlocked yes)
			(layer "F.Fab")
			(hide yes)
			(effects
				(font
					(size 1.016 1.016)
					(thickness 0.1524)
				)
			)
		)
		(property "Device Type" "R603H22"
			(at -0.0254 -3.5433 180)
			(unlocked yes)
			(layer "F.Fab")
			(hide yes)
			(effects
				(font
					(size 1.016 1.016)
					(thickness 0.1524)
				)
			)
		)
		(duplicate_pad_numbers_are_jumpers no)
		(fp_line
			(start 0.4318 0)
			(end 0.2032 0)
			(stroke
				(width 0.2032)
				(type default)
			)
			(layer "F.SilkS")
		)
		(fp_line
			(start -0.2032 0)
			(end -0.4191 0)
			(stroke
				(width 0.2032)
				(type default)
			)
			(layer "F.SilkS")
		)
		(fp_rect
			(start -0.635 1.1811)
			(end 0.635 -1.1811)
			(stroke
				(width 0)
				(type default)
			)
			(fill no)
			(layer "F.CrtYd")
		)
		(fp_rect
			(start -0.635 1.1811)
			(end 0.635 -1.1811)
			(stroke
				(width 0)
				(type default)
			)
			(fill no)
			(layer "F.Fab")
		)
		(pad "1" smd custom
			(at 0 -0.6604 180)
			(size 0.19685 0.19685)
			(layers "F.Cu" "F.Mask" "F.Paste")
			(net "P3V3_CLK_R_PCI")
			(options
				(clearance outline)
				(anchor circle)
			)
			(primitives
				(gr_poly
					(pts
						(arc
							(start 0.508 -0.2921)
							(mid 0.478242 -0.363942)
							(end 0.4064 -0.3937)
						)
						(arc
							(start -0.4064 -0.3937)
							(mid -0.478242 -0.363942)
							(end -0.508 -0.2921)
						)
						(arc
							(start -0.508 0.2921)
							(mid -0.478242 0.363942)
							(end -0.4064 0.3937)
						)
						(arc
							(start 0.4064 0.3937)
							(mid 0.478242 0.363942)
							(end 0.508 0.2921)
						)
					)
					(width 0)
					(fill yes)
				)
			)
		)
		(pad "2" smd custom
			(at 0 0.6604 180)
			(size 0.19685 0.19685)
			(layers "F.Cu" "F.Mask" "F.Paste")
			(net "P3V3_CLK_PCI")
			(options
				(clearance outline)
				(anchor circle)
			)
			(primitives
				(gr_poly
					(pts
						(arc
							(start 0.508 -0.2921)
							(mid 0.478242 -0.363942)
							(end 0.4064 -0.3937)
						)
						(arc
							(start -0.4064 -0.3937)
							(mid -0.478242 -0.363942)
							(end -0.508 -0.2921)
						)
						(arc
							(start -0.508 0.2921)
							(mid -0.478242 0.363942)
							(end -0.4064 0.3937)
						)
						(arc
							(start 0.4064 0.3937)
							(mid 0.478242 0.363942)
							(end 0.508 0.2921)
						)
					)
					(width 0)
					(fill yes)
				)
			)
		)
	)
	(footprint ""
		(layer "F.Cu")
		(at 49.657 -18.415 90)
		(property "Reference" "R326"
			(at 0 0 90)
			(layer "F.SilkS")
			(hide yes)
			(effects
				(font
					(size 1.27 1.27)
				)
			)
		)
		(property "Value" "4K7R2F-GP"
			(at 0.064008 -3.993896 90)
			(unlocked yes)
			(layer "F.Fab")
			(hide yes)
			(effects
				(font
					(size 1.016 1.016)
					(thickness 0.1524)
				)
			)
		)
		(property "Device Type" "R402H16"
			(at 0.064008 -5.517896 90)
			(unlocked yes)
			(layer "F.Fab")
			(hide yes)
			(effects
				(font
					(size 1.016 1.016)
					(thickness 0.1524)
				)
			)
		)
		(duplicate_pad_numbers_are_jumpers no)
		(fp_rect
			(start -0.381 0.8382)
			(end 0.381 -0.8382)
			(stroke
				(width 0)
				(type default)
			)
			(fill no)
			(layer "F.CrtYd")
		)
		(fp_rect
			(start -0.381 0.8382)
			(end 0.381 -0.8382)
			(stroke
				(width 0)
				(type default)
			)
			(fill no)
			(layer "F.Fab")
		)
		(pad "1" smd custom
			(at 0 -0.4318 90)
			(size 0.127 0.127)
			(layers "F.Cu" "F.Mask" "F.Paste")
			(net "CLKBUFF_OE0#")
			(options
				(clearance outline)
				(anchor circle)
			)
			(primitives
				(gr_poly
					(pts
						(arc
							(start -0.2032 -0.2794)
							(mid -0.239121 -0.264521)
							(end -0.254 -0.2286)
						)
						(arc
							(start -0.254 0.2286)
							(mid -0.239121 0.264521)
							(end -0.2032 0.2794)
						)
						(arc
							(start 0.2032 0.2794)
							(mid 0.239121 0.264521)
							(end 0.254 0.2286)
						)
						(arc
							(start 0.254 -0.2286)
							(mid 0.239121 -0.264521)
							(end 0.2032 -0.2794)
						)
					)
					(width 0)
					(fill yes)
				)
			)
		)
		(pad "2" smd custom
			(at 0 0.4318 90)
			(size 0.127 0.127)
			(layers "F.Cu" "F.Mask" "F.Paste")
			(net "GND")
			(options
				(clearance outline)
				(anchor circle)
			)
			(primitives
				(gr_poly
					(pts
						(arc
							(start -0.2032 -0.2794)
							(mid -0.239121 -0.264521)
							(end -0.254 -0.2286)
						)
						(arc
							(start -0.254 0.2286)
							(mid -0.239121 0.264521)
							(end -0.2032 0.2794)
						)
						(arc
							(start 0.2032 0.2794)
							(mid 0.239121 0.264521)
							(end 0.254 0.2286)
						)
						(arc
							(start 0.254 -0.2286)
							(mid 0.239121 -0.264521)
							(end 0.2032 -0.2794)
						)
					)
					(width 0)
					(fill yes)
				)
			)
		)
	)
	(footprint ""
		(layer "F.Cu")
		(at 73.533 -55.118 180)
		(property "Reference" "R134"
			(at 0 0 180)
			(layer "F.SilkS")
			(hide yes)
			(effects
				(font
					(size 1.27 1.27)
				)
			)
		)
		(property "Value" "0R2J-2-GP"
			(at 0.064008 -3.993896 180)
			(unlocked yes)
			(layer "F.Fab")
			(hide yes)
			(effects
				(font
					(size 1.016 1.016)
					(thickness 0.1524)
				)
			)
		)
		(property "Device Type" "R402H16"
			(at 0.064008 -5.517896 180)
			(unlocked yes)
			(layer "F.Fab")
			(hide yes)
			(effects
				(font
					(size 1.016 1.016)
					(thickness 0.1524)
				)
			)
		)
		(duplicate_pad_numbers_are_jumpers no)
		(fp_rect
			(start -0.381 0.8382)
			(end 0.381 -0.8382)
			(stroke
				(width 0)
				(type default)
			)
			(fill no)
			(layer "F.CrtYd")
		)
		(fp_rect
			(start -0.381 0.8382)
			(end 0.381 -0.8382)
			(stroke
				(width 0)
				(type default)
			)
			(fill no)
			(layer "F.Fab")
		)
		(pad "1" smd custom
			(at 0 -0.4318 180)
			(size 0.127 0.127)
			(layers "F.Cu" "F.Mask" "F.Paste")
			(net "P1V0")
			(options
				(clearance outline)
				(anchor circle)
			)
			(primitives
				(gr_poly
					(pts
						(arc
							(start -0.2032 -0.2794)
							(mid -0.239121 -0.264521)
							(end -0.254 -0.2286)
						)
						(arc
							(start -0.254 0.2286)
							(mid -0.239121 0.264521)
							(end -0.2032 0.2794)
						)
						(arc
							(start 0.2032 0.2794)
							(mid 0.239121 0.264521)
							(end 0.254 0.2286)
						)
						(arc
							(start 0.254 -0.2286)
							(mid 0.239121 -0.264521)
							(end 0.2032 -0.2794)
						)
					)
					(width 0)
					(fill yes)
				)
			)
		)
		(pad "2" smd custom
			(at 0 0.4318 180)
			(size 0.127 0.127)
			(layers "F.Cu" "F.Mask" "F.Paste")
			(net "P1V0_SENSE")
			(options
				(clearance outline)
				(anchor circle)
			)
			(primitives
				(gr_poly
					(pts
						(arc
							(start -0.2032 -0.2794)
							(mid -0.239121 -0.264521)
							(end -0.254 -0.2286)
						)
						(arc
							(start -0.254 0.2286)
							(mid -0.239121 0.264521)
							(end -0.2032 0.2794)
						)
						(arc
							(start 0.2032 0.2794)
							(mid 0.239121 0.264521)
							(end 0.254 0.2286)
						)
						(arc
							(start 0.254 -0.2286)
							(mid 0.239121 -0.264521)
							(end 0.2032 -0.2794)
						)
					)
					(width 0)
					(fill yes)
				)
			)
		)
	)
	(footprint ""
		(layer "F.Cu")
		(at 47.8536 -52.0065)
		(property "Reference" "C35"
			(at 0 0 0)
			(layer "F.SilkS")
			(hide yes)
			(effects
				(font
					(size 1.27 1.27)
				)
			)
		)
		(property "Value" "SCD1U10V2KX-5GP"
			(at 1.8923 -1.2065 0)
			(unlocked yes)
			(layer "F.Fab")
			(hide yes)
			(effects
				(font
					(size 1.016 1.016)
					(thickness 0.1524)
				)
			)
		)
		(property "Device Type" "C402H22"
			(at 1.8923 -2.7305 0)
			(unlocked yes)
			(layer "F.Fab")
			(hide yes)
			(effects
				(font
					(size 1.016 1.016)
					(thickness 0.1524)
				)
			)
		)
		(duplicate_pad_numbers_are_jumpers no)
		(fp_rect
			(start -0.381 0.7366)
			(end 0.381 -0.7366)
			(stroke
				(width 0)
				(type default)
			)
			(fill no)
			(layer "F.CrtYd")
		)
		(fp_rect
			(start -0.381 0.7366)
			(end 0.381 -0.7366)
			(stroke
				(width 0)
				(type default)
			)
			(fill no)
			(layer "F.Fab")
		)
		(pad "1" smd custom
			(at 0 -0.4572)
			(size 0.1143 0.1143)
			(layers "F.Cu" "F.Mask" "F.Paste")
			(net "P1V5_CLK_VDD_CORE")
			(options
				(clearance outline)
				(anchor circle)
			)
			(primitives
				(gr_poly
					(pts
						(arc
							(start -0.254 -0.1778)
							(mid -0.239121 -0.213721)
							(end -0.2032 -0.2286)
						)
						(arc
							(start 0.2032 -0.2286)
							(mid 0.239121 -0.213721)
							(end 0.254 -0.1778)
						)
						(arc
							(start 0.254 0.1778)
							(mid 0.239121 0.213721)
							(end 0.2032 0.2286)
						)
						(arc
							(start -0.2032 0.2286)
							(mid -0.239121 0.213721)
							(end -0.254 0.1778)
						)
					)
					(width 0)
					(fill yes)
				)
			)
		)
		(pad "2" smd custom
			(at 0 0.4572)
			(size 0.1143 0.1143)
			(layers "F.Cu" "F.Mask" "F.Paste")
			(net "GND")
			(options
				(clearance outline)
				(anchor circle)
			)
			(primitives
				(gr_poly
					(pts
						(arc
							(start -0.254 -0.1778)
							(mid -0.239121 -0.213721)
							(end -0.2032 -0.2286)
						)
						(arc
							(start 0.2032 -0.2286)
							(mid 0.239121 -0.213721)
							(end 0.254 -0.1778)
						)
						(arc
							(start 0.254 0.1778)
							(mid 0.239121 0.213721)
							(end 0.2032 0.2286)
						)
						(arc
							(start -0.2032 0.2286)
							(mid -0.239121 0.213721)
							(end -0.254 0.1778)
						)
					)
					(width 0)
					(fill yes)
				)
			)
		)
	)
	(footprint ""
		(layer "F.Cu")
		(at 74.041 -33.655 90)
		(property "Reference" "R107"
			(at 0 0 90)
			(layer "F.SilkS")
			(hide yes)
			(effects
				(font
					(size 1.27 1.27)
				)
			)
		)
		(property "Value" "4K7R2F-GP"
			(at 0.064008 -3.993896 90)
			(unlocked yes)
			(layer "F.Fab")
			(hide yes)
			(effects
				(font
					(size 1.016 1.016)
					(thickness 0.1524)
				)
			)
		)
		(property "Device Type" "R402H16"
			(at 0.064008 -5.517896 90)
			(unlocked yes)
			(layer "F.Fab")
			(hide yes)
			(effects
				(font
					(size 1.016 1.016)
					(thickness 0.1524)
				)
			)
		)
		(duplicate_pad_numbers_are_jumpers no)
		(fp_rect
			(start -0.381 0.8382)
			(end 0.381 -0.8382)
			(stroke
				(width 0)
				(type default)
			)
			(fill no)
			(layer "F.CrtYd")
		)
		(fp_rect
			(start -0.381 0.8382)
			(end 0.381 -0.8382)
			(stroke
				(width 0)
				(type default)
			)
			(fill no)
			(layer "F.Fab")
		)
		(pad "1" smd custom
			(at 0 -0.4318 90)
			(size 0.127 0.127)
			(layers "F.Cu" "F.Mask" "F.Paste")
			(net "P3V3_CPU")
			(options
				(clearance outline)
				(anchor circle)
			)
			(primitives
				(gr_poly
					(pts
						(arc
							(start -0.2032 -0.2794)
							(mid -0.239121 -0.264521)
							(end -0.254 -0.2286)
						)
						(arc
							(start -0.254 0.2286)
							(mid -0.239121 0.264521)
							(end -0.2032 0.2794)
						)
						(arc
							(start 0.2032 0.2794)
							(mid 0.239121 0.264521)
							(end 0.254 0.2286)
						)
						(arc
							(start 0.254 -0.2286)
							(mid 0.239121 -0.264521)
							(end 0.2032 -0.2794)
						)
					)
					(width 0)
					(fill yes)
				)
			)
		)
		(pad "2" smd custom
			(at 0 0.4318 90)
			(size 0.127 0.127)
			(layers "F.Cu" "F.Mask" "F.Paste")
			(net "XDP_CPU_RESET#")
			(options
				(clearance outline)
				(anchor circle)
			)
			(primitives
				(gr_poly
					(pts
						(arc
							(start -0.2032 -0.2794)
							(mid -0.239121 -0.264521)
							(end -0.254 -0.2286)
						)
						(arc
							(start -0.254 0.2286)
							(mid -0.239121 0.264521)
							(end -0.2032 0.2794)
						)
						(arc
							(start 0.2032 0.2794)
							(mid 0.239121 0.264521)
							(end 0.254 0.2286)
						)
						(arc
							(start 0.254 -0.2286)
							(mid 0.239121 -0.264521)
							(end 0.2032 -0.2794)
						)
					)
					(width 0)
					(fill yes)
				)
			)
		)
	)
	(footprint ""
		(layer "F.Cu")
		(at 159.639 -33.782 90)
		(property "Reference" "R148"
			(at 0 0 90)
			(layer "F.SilkS")
			(hide yes)
			(effects
				(font
					(size 1.27 1.27)
				)
			)
		)
		(property "Value" "300R2F-GP"
			(at 0.064008 -3.993896 90)
			(unlocked yes)
			(layer "F.Fab")
			(hide yes)
			(effects
				(font
					(size 1.016 1.016)
					(thickness 0.1524)
				)
			)
		)
		(property "Device Type" "R402H16"
			(at 0.064008 -5.517896 90)
			(unlocked yes)
			(layer "F.Fab")
			(hide yes)
			(effects
				(font
					(size 1.016 1.016)
					(thickness 0.1524)
				)
			)
		)
		(duplicate_pad_numbers_are_jumpers no)
		(fp_rect
			(start -0.381 0.8382)
			(end 0.381 -0.8382)
			(stroke
				(width 0)
				(type default)
			)
			(fill no)
			(layer "F.CrtYd")
		)
		(fp_rect
			(start -0.381 0.8382)
			(end 0.381 -0.8382)
			(stroke
				(width 0)
				(type default)
			)
			(fill no)
			(layer "F.Fab")
		)
		(pad "1" smd custom
			(at 0 -0.4318 90)
			(size 0.127 0.127)
			(layers "F.Cu" "F.Mask" "F.Paste")
			(net "HEARTBEAT_R_LED")
			(options
				(clearance outline)
				(anchor circle)
			)
			(primitives
				(gr_poly
					(pts
						(arc
							(start -0.2032 -0.2794)
							(mid -0.239121 -0.264521)
							(end -0.254 -0.2286)
						)
						(arc
							(start -0.254 0.2286)
							(mid -0.239121 0.264521)
							(end -0.2032 0.2794)
						)
						(arc
							(start 0.2032 0.2794)
							(mid 0.239121 0.264521)
							(end 0.254 0.2286)
						)
						(arc
							(start 0.254 -0.2286)
							(mid 0.239121 -0.264521)
							(end 0.2032 -0.2794)
						)
					)
					(width 0)
					(fill yes)
				)
			)
		)
		(pad "2" smd custom
			(at 0 0.4318 90)
			(size 0.127 0.127)
			(layers "F.Cu" "F.Mask" "F.Paste")
			(net "P3V3_STBY")
			(options
				(clearance outline)
				(anchor circle)
			)
			(primitives
				(gr_poly
					(pts
						(arc
							(start -0.2032 -0.2794)
							(mid -0.239121 -0.264521)
							(end -0.254 -0.2286)
						)
						(arc
							(start -0.254 0.2286)
							(mid -0.239121 0.264521)
							(end -0.2032 0.2794)
						)
						(arc
							(start 0.2032 0.2794)
							(mid 0.239121 0.264521)
							(end 0.254 0.2286)
						)
						(arc
							(start 0.254 -0.2286)
							(mid 0.239121 -0.264521)
							(end 0.2032 -0.2794)
						)
					)
					(width 0)
					(fill yes)
				)
			)
		)
	)
	(footprint ""
		(layer "F.Cu")
		(at 189.865 -16.129 180)
		(property "Reference" "C290"
			(at 0 0 180)
			(layer "F.SilkS")
			(hide yes)
			(effects
				(font
					(size 1.27 1.27)
				)
			)
		)
		(property "Value" "SC10U6D3V3MX-GP"
			(at 0 -2.8194 180)
			(unlocked yes)
			(layer "F.Fab")
			(hide yes)
			(effects
				(font
					(size 1.016 1.016)
					(thickness 0.1524)
				)
			)
		)
		(property "Device Type" "C603H38"
			(at 0 -4.3434 180)
			(unlocked yes)
			(layer "F.Fab")
			(hide yes)
			(effects
				(font
					(size 1.016 1.016)
					(thickness 0.1524)
				)
			)
		)
		(duplicate_pad_numbers_are_jumpers no)
		(fp_line
			(start -0.4064 0)
			(end 0.4064 0)
			(stroke
				(width 0.2286)
				(type default)
			)
			(layer "F.SilkS")
		)
		(fp_rect
			(start -0.635 1.1811)
			(end 0.635 -1.1811)
			(stroke
				(width 0)
				(type default)
			)
			(fill no)
			(layer "F.CrtYd")
		)
		(fp_rect
			(start -0.635 1.1811)
			(end 0.635 -1.1811)
			(stroke
				(width 0)
				(type default)
			)
			(fill no)
			(layer "F.Fab")
		)
		(pad "1" smd custom
			(at 0 -0.6604 180)
			(size 0.19685 0.19685)
			(layers "F.Cu" "F.Mask" "F.Paste")
			(net "PV_VTT_DDR_B")
			(options
				(clearance outline)
				(anchor circle)
			)
			(primitives
				(gr_poly
					(pts
						(arc
							(start 0.508 -0.2921)
							(mid 0.478242 -0.363942)
							(end 0.4064 -0.3937)
						)
						(arc
							(start -0.4064 -0.3937)
							(mid -0.478242 -0.363942)
							(end -0.508 -0.2921)
						)
						(arc
							(start -0.508 0.2921)
							(mid -0.478242 0.363942)
							(end -0.4064 0.3937)
						)
						(arc
							(start 0.4064 0.3937)
							(mid 0.478242 0.363942)
							(end 0.508 0.2921)
						)
					)
					(width 0)
					(fill yes)
				)
			)
		)
		(pad "2" smd custom
			(at 0 0.6604 180)
			(size 0.19685 0.19685)
			(layers "F.Cu" "F.Mask" "F.Paste")
			(net "GND")
			(options
				(clearance outline)
				(anchor circle)
			)
			(primitives
				(gr_poly
					(pts
						(arc
							(start 0.508 -0.2921)
							(mid 0.478242 -0.363942)
							(end 0.4064 -0.3937)
						)
						(arc
							(start -0.4064 -0.3937)
							(mid -0.478242 -0.363942)
							(end -0.508 -0.2921)
						)
						(arc
							(start -0.508 0.2921)
							(mid -0.478242 0.363942)
							(end -0.4064 0.3937)
						)
						(arc
							(start 0.4064 0.3937)
							(mid 0.478242 0.363942)
							(end 0.508 0.2921)
						)
					)
					(width 0)
					(fill yes)
				)
			)
		)
	)
	(footprint ""
		(layer "F.Cu")
		(at 45.7454 -30.4546 -90)
		(property "Reference" "U43"
			(at 0 0 270)
			(layer "F.SilkS")
			(hide yes)
			(effects
				(font
					(size 1.27 1.27)
				)
			)
		)
		(property "Value" "SN74LVC1G11DCKR-GP"
			(at -4.897374 3.525266 270)
			(unlocked yes)
			(layer "F.Fab")
			(hide yes)
			(effects
				(font
					(size 1.016 1.016)
					(thickness 0.1524)
				)
			)
		)
		(property "Device Type" "UMT6H44"
			(at -4.897374 2.001266 270)
			(unlocked yes)
			(layer "F.Fab")
			(hide yes)
			(effects
				(font
					(size 1.016 1.016)
					(thickness 0.1524)
				)
			)
		)
		(duplicate_pad_numbers_are_jumpers no)
		(fp_line
			(start -1.0033 0.3556)
			(end 1.0033 0.3556)
			(stroke
				(width 0.1524)
				(type default)
			)
			(layer "F.SilkS")
		)
		(fp_line
			(start 1.0033 0.3556)
			(end 1.0033 -0.3556)
			(stroke
				(width 0.1524)
				(type default)
			)
			(layer "F.SilkS")
		)
		(fp_line
			(start -1.1557 0.2921)
			(end -1.1557 1.2954)
			(stroke
				(width 0.254)
				(type default)
			)
			(layer "F.SilkS")
		)
		(fp_line
			(start -1.0033 -0.3556)
			(end -1.0033 0.3556)
			(stroke
				(width 0.1524)
				(type default)
			)
			(layer "F.SilkS")
		)
		(fp_line
			(start 1.0033 -0.3556)
			(end -1.0033 -0.3556)
			(stroke
				(width 0.1524)
				(type default)
			)
			(layer "F.SilkS")
		)
		(fp_poly
			(pts
				(xy -1.016 0.3556) (xy 1.016 0.3556) (xy 1.016 -0.3556) (xy -1.016 -0.3556)
			)
			(stroke
				(width 0)
				(type default)
			)
			(fill yes)
			(layer "F.SilkS")
		)
		(fp_poly
			(pts
				(xy -1.0033 -0.8763) (xy -1.2573 -0.8763) (xy -1.2573 0.8763) (xy -0.9906 0.8763) (xy -0.9906 1.4097)
				(xy 0.9906 1.4097) (xy 0.9906 0.8763) (xy 1.2573 0.8763) (xy 1.2573 -0.8763) (xy 0.9906 -0.8763)
				(xy 0.9906 -1.4097) (xy -0.9906 -1.4097) (xy -0.9906 -0.8763)
			)
			(stroke
				(width 0)
				(type default)
			)
			(fill no)
			(layer "F.CrtYd")
		)
		(fp_poly
			(pts
				(xy -1.0033 -0.8763) (xy -1.2573 -0.8763) (xy -1.2573 0.8763) (xy -1.0033 0.8763) (xy -0.9906 0.8763)
				(xy -0.9906 1.4097) (xy 0.9906 1.4097) (xy 0.9906 0.8763) (xy 1.0033 0.8763) (xy 1.2573 0.8763)
				(xy 1.2573 -0.8763) (xy 1.0033 -0.8763) (xy 0.9906 -0.8763) (xy 0.9906 -1.4097) (xy -0.9906 -1.4097)
				(xy -0.9906 -0.8763)
			)
			(stroke
				(width 0)
				(type default)
			)
			(fill no)
			(layer "F.Fab")
		)
		(pad "1" smd rect
			(at -0.65024 0.94996 270)
			(size 0.4064 0.6604)
			(layers "F.Cu" "F.Mask" "F.Paste")
			(net "BMC_PWRBTN#")
		)
		(pad "2" smd rect
			(at 0 0.94996 270)
			(size 0.4064 0.6604)
			(layers "F.Cu" "F.Mask" "F.Paste")
			(net "GND")
		)
		(pad "3" smd rect
			(at 0.65024 0.94996 270)
			(size 0.4064 0.6604)
			(layers "F.Cu" "F.Mask" "F.Paste")
			(net "FPGA_PWRBTN#")
		)
		(pad "4" smd rect
			(at 0.65024 -0.94996 270)
			(size 0.4064 0.6604)
			(layers "F.Cu" "F.Mask" "F.Paste")
			(net "PMU_PWRBTN_R#")
		)
		(pad "5" smd rect
			(at 0 -0.94996 270)
			(size 0.4064 0.6604)
			(layers "F.Cu" "F.Mask" "F.Paste")
			(net "P3V3_CPU")
		)
		(pad "6" smd rect
			(at -0.65024 -0.94996 270)
			(size 0.4064 0.6604)
			(layers "F.Cu" "F.Mask" "F.Paste")
			(net "XDP_PWRBTN#")
		)
	)
	(footprint ""
		(layer "F.Cu")
		(at 59.817 -17.78 90)
		(property "Reference" "R174"
			(at 0 0 90)
			(layer "F.SilkS")
			(hide yes)
			(effects
				(font
					(size 1.27 1.27)
				)
			)
		)
		(property "Value" "0R2J-2-GP"
			(at 0.064008 -3.993896 90)
			(unlocked yes)
			(layer "F.Fab")
			(hide yes)
			(effects
				(font
					(size 1.016 1.016)
					(thickness 0.1524)
				)
			)
		)
		(property "Device Type" "R402H16"
			(at 0.064008 -5.517896 90)
			(unlocked yes)
			(layer "F.Fab")
			(hide yes)
			(effects
				(font
					(size 1.016 1.016)
					(thickness 0.1524)
				)
			)
		)
		(duplicate_pad_numbers_are_jumpers no)
		(fp_rect
			(start -0.381 0.8382)
			(end 0.381 -0.8382)
			(stroke
				(width 0)
				(type default)
			)
			(fill no)
			(layer "F.CrtYd")
		)
		(fp_rect
			(start -0.381 0.8382)
			(end 0.381 -0.8382)
			(stroke
				(width 0)
				(type default)
			)
			(fill no)
			(layer "F.Fab")
		)
		(pad "1" smd custom
			(at 0 -0.4318 90)
			(size 0.127 0.127)
			(layers "F.Cu" "F.Mask" "F.Paste")
			(net "SPI_CLK_GBE_R")
			(options
				(clearance outline)
				(anchor circle)
			)
			(primitives
				(gr_poly
					(pts
						(arc
							(start -0.2032 -0.2794)
							(mid -0.239121 -0.264521)
							(end -0.254 -0.2286)
						)
						(arc
							(start -0.254 0.2286)
							(mid -0.239121 0.264521)
							(end -0.2032 0.2794)
						)
						(arc
							(start 0.2032 0.2794)
							(mid 0.239121 0.264521)
							(end 0.254 0.2286)
						)
						(arc
							(start 0.254 -0.2286)
							(mid 0.239121 -0.264521)
							(end 0.2032 -0.2794)
						)
					)
					(width 0)
					(fill yes)
				)
			)
		)
		(pad "2" smd custom
			(at 0 0.4318 90)
			(size 0.127 0.127)
			(layers "F.Cu" "F.Mask" "F.Paste")
			(net "SPI_CLK_GBE")
			(options
				(clearance outline)
				(anchor circle)
			)
			(primitives
				(gr_poly
					(pts
						(arc
							(start -0.2032 -0.2794)
							(mid -0.239121 -0.264521)
							(end -0.254 -0.2286)
						)
						(arc
							(start -0.254 0.2286)
							(mid -0.239121 0.264521)
							(end -0.2032 0.2794)
						)
						(arc
							(start 0.2032 0.2794)
							(mid 0.239121 0.264521)
							(end 0.254 0.2286)
						)
						(arc
							(start 0.254 -0.2286)
							(mid 0.239121 -0.264521)
							(end 0.2032 -0.2794)
						)
					)
					(width 0)
					(fill yes)
				)
			)
		)
	)
	(footprint ""
		(layer "F.Cu")
		(at 55.2958 -48.26)
		(property "Reference" "PC101"
			(at 0 0 0)
			(layer "F.SilkS")
			(hide yes)
			(effects
				(font
					(size 1.27 1.27)
				)
			)
		)
		(property "Value" "SC680P50V2KX-2GP"
			(at 1.8923 -1.2065 0)
			(unlocked yes)
			(layer "F.Fab")
			(hide yes)
			(effects
				(font
					(size 1.016 1.016)
					(thickness 0.1524)
				)
			)
		)
		(property "Device Type" "C402H22"
			(at 1.8923 -2.7305 0)
			(unlocked yes)
			(layer "F.Fab")
			(hide yes)
			(effects
				(font
					(size 1.016 1.016)
					(thickness 0.1524)
				)
			)
		)
		(duplicate_pad_numbers_are_jumpers no)
		(fp_rect
			(start -0.381 0.7366)
			(end 0.381 -0.7366)
			(stroke
				(width 0)
				(type default)
			)
			(fill no)
			(layer "F.CrtYd")
		)
		(fp_rect
			(start -0.381 0.7366)
			(end 0.381 -0.7366)
			(stroke
				(width 0)
				(type default)
			)
			(fill no)
			(layer "F.Fab")
		)
		(pad "1" smd custom
			(at 0 -0.4572)
			(size 0.1143 0.1143)
			(layers "F.Cu" "F.Mask" "F.Paste")
			(net "VR_PVIN_P1V0_STBY")
			(options
				(clearance outline)
				(anchor circle)
			)
			(primitives
				(gr_poly
					(pts
						(arc
							(start -0.254 -0.1778)
							(mid -0.239121 -0.213721)
							(end -0.2032 -0.2286)
						)
						(arc
							(start 0.2032 -0.2286)
							(mid 0.239121 -0.213721)
							(end 0.254 -0.1778)
						)
						(arc
							(start 0.254 0.1778)
							(mid 0.239121 0.213721)
							(end 0.2032 0.2286)
						)
						(arc
							(start -0.2032 0.2286)
							(mid -0.239121 0.213721)
							(end -0.254 0.1778)
						)
					)
					(width 0)
					(fill yes)
				)
			)
		)
		(pad "2" smd custom
			(at 0 0.4572)
			(size 0.1143 0.1143)
			(layers "F.Cu" "F.Mask" "F.Paste")
			(net "GND")
			(options
				(clearance outline)
				(anchor circle)
			)
			(primitives
				(gr_poly
					(pts
						(arc
							(start -0.254 -0.1778)
							(mid -0.239121 -0.213721)
							(end -0.2032 -0.2286)
						)
						(arc
							(start 0.2032 -0.2286)
							(mid 0.239121 -0.213721)
							(end 0.254 -0.1778)
						)
						(arc
							(start 0.254 0.1778)
							(mid 0.239121 0.213721)
							(end 0.2032 0.2286)
						)
						(arc
							(start -0.2032 0.2286)
							(mid -0.239121 0.213721)
							(end -0.254 0.1778)
						)
					)
					(width 0)
					(fill yes)
				)
			)
		)
	)
	(footprint ""
		(layer "F.Cu")
		(at 169.672 -53.2892 180)
		(property "Reference" "R79"
			(at 0 0 180)
			(layer "F.SilkS")
			(hide yes)
			(effects
				(font
					(size 1.27 1.27)
				)
			)
		)
		(property "Value" "1KR2F-3-GP"
			(at 0.064008 -3.993896 180)
			(unlocked yes)
			(layer "F.Fab")
			(hide yes)
			(effects
				(font
					(size 1.016 1.016)
					(thickness 0.1524)
				)
			)
		)
		(property "Device Type" "R402H16"
			(at 0.064008 -5.517896 180)
			(unlocked yes)
			(layer "F.Fab")
			(hide yes)
			(effects
				(font
					(size 1.016 1.016)
					(thickness 0.1524)
				)
			)
		)
		(duplicate_pad_numbers_are_jumpers no)
		(fp_rect
			(start -0.381 0.8382)
			(end 0.381 -0.8382)
			(stroke
				(width 0)
				(type default)
			)
			(fill no)
			(layer "F.CrtYd")
		)
		(fp_rect
			(start -0.381 0.8382)
			(end 0.381 -0.8382)
			(stroke
				(width 0)
				(type default)
			)
			(fill no)
			(layer "F.Fab")
		)
		(pad "1" smd custom
			(at 0 -0.4318 180)
			(size 0.127 0.127)
			(layers "F.Cu" "F.Mask" "F.Paste")
			(net "C_DATA0")
			(options
				(clearance outline)
				(anchor circle)
			)
			(primitives
				(gr_poly
					(pts
						(arc
							(start -0.2032 -0.2794)
							(mid -0.239121 -0.264521)
							(end -0.254 -0.2286)
						)
						(arc
							(start -0.254 0.2286)
							(mid -0.239121 0.264521)
							(end -0.2032 0.2794)
						)
						(arc
							(start 0.2032 0.2794)
							(mid 0.239121 0.264521)
							(end 0.254 0.2286)
						)
						(arc
							(start 0.254 -0.2286)
							(mid 0.239121 -0.264521)
							(end 0.2032 -0.2794)
						)
					)
					(width 0)
					(fill yes)
				)
			)
		)
		(pad "2" smd custom
			(at 0 0.4318 180)
			(size 0.127 0.127)
			(layers "F.Cu" "F.Mask" "F.Paste")
			(net "P3V3_STBY")
			(options
				(clearance outline)
				(anchor circle)
			)
			(primitives
				(gr_poly
					(pts
						(arc
							(start -0.2032 -0.2794)
							(mid -0.239121 -0.264521)
							(end -0.254 -0.2286)
						)
						(arc
							(start -0.254 0.2286)
							(mid -0.239121 0.264521)
							(end -0.2032 0.2794)
						)
						(arc
							(start 0.2032 0.2794)
							(mid 0.239121 0.264521)
							(end 0.254 0.2286)
						)
						(arc
							(start 0.254 -0.2286)
							(mid 0.239121 -0.264521)
							(end 0.2032 -0.2794)
						)
					)
					(width 0)
					(fill yes)
				)
			)
		)
	)
	(footprint ""
		(layer "F.Cu")
		(at 69.596 -55.626 90)
		(property "Reference" "R166"
			(at 0 0 90)
			(layer "F.SilkS")
			(hide yes)
			(effects
				(font
					(size 1.27 1.27)
				)
			)
		)
		(property "Value" "0R2J-2-GP"
			(at 1.7907 -1.1176 90)
			(unlocked yes)
			(layer "F.Fab")
			(hide yes)
			(effects
				(font
					(size 1.016 1.016)
					(thickness 0.1524)
				)
			)
		)
		(property "Device Type" "R402H16"
			(at 1.7907 -2.6416 90)
			(unlocked yes)
			(layer "F.Fab")
			(hide yes)
			(effects
				(font
					(size 1.016 1.016)
					(thickness 0.1524)
				)
			)
		)
		(duplicate_pad_numbers_are_jumpers no)
		(fp_rect
			(start -0.381 0.8382)
			(end 0.381 -0.8382)
			(stroke
				(width 0)
				(type default)
			)
			(fill no)
			(layer "F.CrtYd")
		)
		(fp_rect
			(start -0.381 0.8382)
			(end 0.381 -0.8382)
			(stroke
				(width 0)
				(type default)
			)
			(fill no)
			(layer "F.Fab")
		)
		(pad "1" smd custom
			(at 0 -0.4318 90)
			(size 0.127 0.127)
			(layers "F.Cu" "F.Mask" "F.Paste")
			(net "P1V8")
			(options
				(clearance outline)
				(anchor circle)
			)
			(primitives
				(gr_poly
					(pts
						(arc
							(start -0.2032 -0.2794)
							(mid -0.239121 -0.264521)
							(end -0.254 -0.2286)
						)
						(arc
							(start -0.254 0.2286)
							(mid -0.239121 0.264521)
							(end -0.2032 0.2794)
						)
						(arc
							(start 0.2032 0.2794)
							(mid 0.239121 0.264521)
							(end 0.254 0.2286)
						)
						(arc
							(start 0.254 -0.2286)
							(mid 0.239121 -0.264521)
							(end 0.2032 -0.2794)
						)
					)
					(width 0)
					(fill yes)
				)
			)
		)
		(pad "2" smd custom
			(at 0 0.4318 90)
			(size 0.127 0.127)
			(layers "F.Cu" "F.Mask" "F.Paste")
			(net "P1V8_SENSE")
			(options
				(clearance outline)
				(anchor circle)
			)
			(primitives
				(gr_poly
					(pts
						(arc
							(start -0.2032 -0.2794)
							(mid -0.239121 -0.264521)
							(end -0.254 -0.2286)
						)
						(arc
							(start -0.254 0.2286)
							(mid -0.239121 0.264521)
							(end -0.2032 0.2794)
						)
						(arc
							(start 0.2032 0.2794)
							(mid 0.239121 0.264521)
							(end 0.254 0.2286)
						)
						(arc
							(start 0.254 -0.2286)
							(mid 0.239121 -0.264521)
							(end 0.2032 -0.2794)
						)
					)
					(width 0)
					(fill yes)
				)
			)
		)
	)
	(footprint ""
		(layer "F.Cu")
		(at 197.612 -4.064 90)
		(property "Reference" "C87"
			(at 0 0 90)
			(layer "F.SilkS")
			(hide yes)
			(effects
				(font
					(size 1.27 1.27)
				)
			)
		)
		(property "Value" "SC1U6D3V2KX-GP"
			(at 1.1811 -2.7051 90)
			(unlocked yes)
			(layer "F.Fab")
			(hide yes)
			(effects
				(font
					(size 1.016 1.016)
					(thickness 0.1524)
				)
			)
		)
		(property "Device Type" "C402H22"
			(at 1.1811 -4.2291 90)
			(unlocked yes)
			(layer "F.Fab")
			(hide yes)
			(effects
				(font
					(size 1.016 1.016)
					(thickness 0.1524)
				)
			)
		)
		(duplicate_pad_numbers_are_jumpers no)
		(fp_rect
			(start -0.381 0.7366)
			(end 0.381 -0.7366)
			(stroke
				(width 0)
				(type default)
			)
			(fill no)
			(layer "F.CrtYd")
		)
		(fp_rect
			(start -0.381 0.7366)
			(end 0.381 -0.7366)
			(stroke
				(width 0)
				(type default)
			)
			(fill no)
			(layer "F.Fab")
		)
		(pad "1" smd custom
			(at 0 -0.4572 90)
			(size 0.1143 0.1143)
			(layers "F.Cu" "F.Mask" "F.Paste")
			(net "PV_VTT_DDR_B")
			(options
				(clearance outline)
				(anchor circle)
			)
			(primitives
				(gr_poly
					(pts
						(arc
							(start -0.254 -0.1778)
							(mid -0.239121 -0.213721)
							(end -0.2032 -0.2286)
						)
						(arc
							(start 0.2032 -0.2286)
							(mid 0.239121 -0.213721)
							(end 0.254 -0.1778)
						)
						(arc
							(start 0.254 0.1778)
							(mid 0.239121 0.213721)
							(end 0.2032 0.2286)
						)
						(arc
							(start -0.2032 0.2286)
							(mid -0.239121 0.213721)
							(end -0.254 0.1778)
						)
					)
					(width 0)
					(fill yes)
				)
			)
		)
		(pad "2" smd custom
			(at 0 0.4572 90)
			(size 0.1143 0.1143)
			(layers "F.Cu" "F.Mask" "F.Paste")
			(net "GND")
			(options
				(clearance outline)
				(anchor circle)
			)
			(primitives
				(gr_poly
					(pts
						(arc
							(start -0.254 -0.1778)
							(mid -0.239121 -0.213721)
							(end -0.2032 -0.2286)
						)
						(arc
							(start 0.2032 -0.2286)
							(mid 0.239121 -0.213721)
							(end 0.254 -0.1778)
						)
						(arc
							(start 0.254 0.1778)
							(mid 0.239121 0.213721)
							(end 0.2032 0.2286)
						)
						(arc
							(start -0.2032 0.2286)
							(mid -0.239121 0.213721)
							(end -0.254 0.1778)
						)
					)
					(width 0)
					(fill yes)
				)
			)
		)
	)
	(footprint ""
		(layer "F.Cu")
		(at 7.5184 -22.225 90)
		(property "Reference" "PR116"
			(at 0 0 90)
			(layer "F.SilkS")
			(hide yes)
			(effects
				(font
					(size 1.27 1.27)
				)
			)
		)
		(property "Value" "78K7R2F-GP"
			(at 1.7907 -1.1176 90)
			(unlocked yes)
			(layer "F.Fab")
			(hide yes)
			(effects
				(font
					(size 1.016 1.016)
					(thickness 0.1524)
				)
			)
		)
		(property "Device Type" "R402H16"
			(at 1.7907 -2.6416 90)
			(unlocked yes)
			(layer "F.Fab")
			(hide yes)
			(effects
				(font
					(size 1.016 1.016)
					(thickness 0.1524)
				)
			)
		)
		(duplicate_pad_numbers_are_jumpers no)
		(fp_rect
			(start -0.381 0.8382)
			(end 0.381 -0.8382)
			(stroke
				(width 0)
				(type default)
			)
			(fill no)
			(layer "F.CrtYd")
		)
		(fp_rect
			(start -0.381 0.8382)
			(end 0.381 -0.8382)
			(stroke
				(width 0)
				(type default)
			)
			(fill no)
			(layer "F.Fab")
		)
		(pad "1" smd custom
			(at 0 -0.4318 90)
			(size 0.127 0.127)
			(layers "F.Cu" "F.Mask" "F.Paste")
			(net "AGND_P1V0")
			(options
				(clearance outline)
				(anchor circle)
			)
			(primitives
				(gr_poly
					(pts
						(arc
							(start -0.2032 -0.2794)
							(mid -0.239121 -0.264521)
							(end -0.254 -0.2286)
						)
						(arc
							(start -0.254 0.2286)
							(mid -0.239121 0.264521)
							(end -0.2032 0.2794)
						)
						(arc
							(start 0.2032 0.2794)
							(mid 0.239121 0.264521)
							(end 0.254 0.2286)
						)
						(arc
							(start 0.254 -0.2286)
							(mid 0.239121 -0.264521)
							(end 0.2032 -0.2794)
						)
					)
					(width 0)
					(fill yes)
				)
			)
		)
		(pad "2" smd custom
			(at 0 0.4318 90)
			(size 0.127 0.127)
			(layers "F.Cu" "F.Mask" "F.Paste")
			(net "P1V0_TRIP")
			(options
				(clearance outline)
				(anchor circle)
			)
			(primitives
				(gr_poly
					(pts
						(arc
							(start -0.2032 -0.2794)
							(mid -0.239121 -0.264521)
							(end -0.254 -0.2286)
						)
						(arc
							(start -0.254 0.2286)
							(mid -0.239121 0.264521)
							(end -0.2032 0.2794)
						)
						(arc
							(start 0.2032 0.2794)
							(mid 0.239121 0.264521)
							(end 0.254 0.2286)
						)
						(arc
							(start 0.254 -0.2286)
							(mid 0.239121 -0.264521)
							(end 0.2032 -0.2794)
						)
					)
					(width 0)
					(fill yes)
				)
			)
		)
	)
	(footprint ""
		(layer "F.Cu")
		(at 116.967 -37.354002 90)
		(property "Reference" "PR108"
			(at 0 0 90)
			(layer "F.SilkS")
			(hide yes)
			(effects
				(font
					(size 1.27 1.27)
				)
			)
		)
		(property "Value" "0R2J-2-GP"
			(at 0.064008 -3.993896 90)
			(unlocked yes)
			(layer "F.Fab")
			(hide yes)
			(effects
				(font
					(size 1.016 1.016)
					(thickness 0.1524)
				)
			)
		)
		(property "Device Type" "R402H16"
			(at 0.064008 -5.517896 90)
			(unlocked yes)
			(layer "F.Fab")
			(hide yes)
			(effects
				(font
					(size 1.016 1.016)
					(thickness 0.1524)
				)
			)
		)
		(duplicate_pad_numbers_are_jumpers no)
		(fp_rect
			(start -0.381 0.8382)
			(end 0.381 -0.8382)
			(stroke
				(width 0)
				(type default)
			)
			(fill no)
			(layer "F.CrtYd")
		)
		(fp_rect
			(start -0.381 0.8382)
			(end 0.381 -0.8382)
			(stroke
				(width 0)
				(type default)
			)
			(fill no)
			(layer "F.Fab")
		)
		(pad "1" smd custom
			(at 0 -0.4318 90)
			(size 0.127 0.127)
			(layers "F.Cu" "F.Mask" "F.Paste")
			(net "AVV_VSSCPUVIDSIO_1P03_SENSE")
			(options
				(clearance outline)
				(anchor circle)
			)
			(primitives
				(gr_poly
					(pts
						(arc
							(start -0.2032 -0.2794)
							(mid -0.239121 -0.264521)
							(end -0.254 -0.2286)
						)
						(arc
							(start -0.254 0.2286)
							(mid -0.239121 0.264521)
							(end -0.2032 0.2794)
						)
						(arc
							(start 0.2032 0.2794)
							(mid 0.239121 0.264521)
							(end 0.254 0.2286)
						)
						(arc
							(start 0.254 -0.2286)
							(mid 0.239121 -0.264521)
							(end 0.2032 -0.2794)
						)
					)
					(width 0)
					(fill yes)
				)
			)
		)
		(pad "2" smd custom
			(at 0 0.4318 90)
			(size 0.127 0.127)
			(layers "F.Cu" "F.Mask" "F.Paste")
			(net "VR_PVCCP_RTN")
			(options
				(clearance outline)
				(anchor circle)
			)
			(primitives
				(gr_poly
					(pts
						(arc
							(start -0.2032 -0.2794)
							(mid -0.239121 -0.264521)
							(end -0.254 -0.2286)
						)
						(arc
							(start -0.254 0.2286)
							(mid -0.239121 0.264521)
							(end -0.2032 0.2794)
						)
						(arc
							(start 0.2032 0.2794)
							(mid 0.239121 0.264521)
							(end 0.254 0.2286)
						)
						(arc
							(start 0.254 -0.2286)
							(mid 0.239121 -0.264521)
							(end 0.2032 -0.2794)
						)
					)
					(width 0)
					(fill yes)
				)
			)
		)
	)
	(footprint ""
		(layer "F.Cu")
		(at 194.691 -33.274 180)
		(property "Reference" "PC95"
			(at 0 0 180)
			(layer "F.SilkS")
			(hide yes)
			(effects
				(font
					(size 1.27 1.27)
				)
			)
		)
		(property "Value" "SCD1U25V2KX-2-GP"
			(at 1.8923 -1.2065 180)
			(unlocked yes)
			(layer "F.Fab")
			(hide yes)
			(effects
				(font
					(size 1.016 1.016)
					(thickness 0.1524)
				)
			)
		)
		(property "Device Type" "C402H22"
			(at 1.8923 -2.7305 180)
			(unlocked yes)
			(layer "F.Fab")
			(hide yes)
			(effects
				(font
					(size 1.016 1.016)
					(thickness 0.1524)
				)
			)
		)
		(duplicate_pad_numbers_are_jumpers no)
		(fp_rect
			(start -0.381 0.7366)
			(end 0.381 -0.7366)
			(stroke
				(width 0)
				(type default)
			)
			(fill no)
			(layer "F.CrtYd")
		)
		(fp_rect
			(start -0.381 0.7366)
			(end 0.381 -0.7366)
			(stroke
				(width 0)
				(type default)
			)
			(fill no)
			(layer "F.Fab")
		)
		(pad "1" smd custom
			(at 0 -0.4572 180)
			(size 0.1143 0.1143)
			(layers "F.Cu" "F.Mask" "F.Paste")
			(net "VR_PVDDR_A_BOOT1")
			(options
				(clearance outline)
				(anchor circle)
			)
			(primitives
				(gr_poly
					(pts
						(arc
							(start -0.254 -0.1778)
							(mid -0.239121 -0.213721)
							(end -0.2032 -0.2286)
						)
						(arc
							(start 0.2032 -0.2286)
							(mid 0.239121 -0.213721)
							(end 0.254 -0.1778)
						)
						(arc
							(start 0.254 0.1778)
							(mid 0.239121 0.213721)
							(end 0.2032 0.2286)
						)
						(arc
							(start -0.2032 0.2286)
							(mid -0.239121 0.213721)
							(end -0.254 0.1778)
						)
					)
					(width 0)
					(fill yes)
				)
			)
		)
		(pad "2" smd custom
			(at 0 0.4572 180)
			(size 0.1143 0.1143)
			(layers "F.Cu" "F.Mask" "F.Paste")
			(net "VR_PVDDR_A_PHASE1")
			(options
				(clearance outline)
				(anchor circle)
			)
			(primitives
				(gr_poly
					(pts
						(arc
							(start -0.254 -0.1778)
							(mid -0.239121 -0.213721)
							(end -0.2032 -0.2286)
						)
						(arc
							(start 0.2032 -0.2286)
							(mid 0.239121 -0.213721)
							(end 0.254 -0.1778)
						)
						(arc
							(start 0.254 0.1778)
							(mid 0.239121 0.213721)
							(end 0.2032 0.2286)
						)
						(arc
							(start -0.2032 0.2286)
							(mid -0.239121 0.213721)
							(end -0.254 0.1778)
						)
					)
					(width 0)
					(fill yes)
				)
			)
		)
	)
	(footprint ""
		(layer "F.Cu")
		(at 29.972 -13.335 180)
		(property "Reference" "R421"
			(at 0 0 180)
			(layer "F.SilkS")
			(hide yes)
			(effects
				(font
					(size 1.27 1.27)
				)
			)
		)
		(property "Value" "0R2J-2-GP"
			(at 1.7907 -1.1176 180)
			(unlocked yes)
			(layer "F.Fab")
			(hide yes)
			(effects
				(font
					(size 1.016 1.016)
					(thickness 0.1524)
				)
			)
		)
		(property "Device Type" "R402H16"
			(at 1.7907 -2.6416 180)
			(unlocked yes)
			(layer "F.Fab")
			(hide yes)
			(effects
				(font
					(size 1.016 1.016)
					(thickness 0.1524)
				)
			)
		)
		(duplicate_pad_numbers_are_jumpers no)
		(fp_rect
			(start -0.381 0.8382)
			(end 0.381 -0.8382)
			(stroke
				(width 0)
				(type default)
			)
			(fill no)
			(layer "F.CrtYd")
		)
		(fp_rect
			(start -0.381 0.8382)
			(end 0.381 -0.8382)
			(stroke
				(width 0)
				(type default)
			)
			(fill no)
			(layer "F.Fab")
		)
		(pad "1" smd custom
			(at 0 -0.4318 180)
			(size 0.127 0.127)
			(layers "F.Cu" "F.Mask" "F.Paste")
			(net "BMC_I2C_CLK")
			(options
				(clearance outline)
				(anchor circle)
			)
			(primitives
				(gr_poly
					(pts
						(arc
							(start -0.2032 -0.2794)
							(mid -0.239121 -0.264521)
							(end -0.254 -0.2286)
						)
						(arc
							(start -0.254 0.2286)
							(mid -0.239121 0.264521)
							(end -0.2032 0.2794)
						)
						(arc
							(start 0.2032 0.2794)
							(mid 0.239121 0.264521)
							(end 0.254 0.2286)
						)
						(arc
							(start 0.254 -0.2286)
							(mid 0.239121 -0.264521)
							(end 0.2032 -0.2794)
						)
					)
					(width 0)
					(fill yes)
				)
			)
		)
		(pad "2" smd custom
			(at 0 0.4318 180)
			(size 0.127 0.127)
			(layers "F.Cu" "F.Mask" "F.Paste")
			(net "PCIE_GF_I2C_CLK")
			(options
				(clearance outline)
				(anchor circle)
			)
			(primitives
				(gr_poly
					(pts
						(arc
							(start -0.2032 -0.2794)
							(mid -0.239121 -0.264521)
							(end -0.254 -0.2286)
						)
						(arc
							(start -0.254 0.2286)
							(mid -0.239121 0.264521)
							(end -0.2032 0.2794)
						)
						(arc
							(start 0.2032 0.2794)
							(mid 0.239121 0.264521)
							(end 0.254 0.2286)
						)
						(arc
							(start 0.254 -0.2286)
							(mid 0.239121 -0.264521)
							(end 0.2032 -0.2794)
						)
					)
					(width 0)
					(fill yes)
				)
			)
		)
	)
	(footprint ""
		(layer "F.Cu")
		(at 42.799 -15.494 -90)
		(property "Reference" "R60"
			(at 0 0 270)
			(layer "F.SilkS")
			(hide yes)
			(effects
				(font
					(size 1.27 1.27)
				)
			)
		)
		(property "Value" "2D2R3J-2-GP"
			(at -0.0254 -2.0193 270)
			(unlocked yes)
			(layer "F.Fab")
			(hide yes)
			(effects
				(font
					(size 1.016 1.016)
					(thickness 0.1524)
				)
			)
		)
		(property "Device Type" "R603H22"
			(at -0.0254 -3.5433 270)
			(unlocked yes)
			(layer "F.Fab")
			(hide yes)
			(effects
				(font
					(size 1.016 1.016)
					(thickness 0.1524)
				)
			)
		)
		(duplicate_pad_numbers_are_jumpers no)
		(fp_line
			(start -0.2032 0)
			(end -0.4191 0)
			(stroke
				(width 0.2032)
				(type default)
			)
			(layer "F.SilkS")
		)
		(fp_line
			(start 0.4318 0)
			(end 0.2032 0)
			(stroke
				(width 0.2032)
				(type default)
			)
			(layer "F.SilkS")
		)
		(fp_rect
			(start -0.635 1.1811)
			(end 0.635 -1.1811)
			(stroke
				(width 0)
				(type default)
			)
			(fill no)
			(layer "F.CrtYd")
		)
		(fp_rect
			(start -0.635 1.1811)
			(end 0.635 -1.1811)
			(stroke
				(width 0)
				(type default)
			)
			(fill no)
			(layer "F.Fab")
		)
		(pad "1" smd custom
			(at 0 -0.6604 270)
			(size 0.19685 0.19685)
			(layers "F.Cu" "F.Mask" "F.Paste")
			(net "P3V3_VDD_CLKBUFF_R")
			(options
				(clearance outline)
				(anchor circle)
			)
			(primitives
				(gr_poly
					(pts
						(arc
							(start 0.508 -0.2921)
							(mid 0.478242 -0.363942)
							(end 0.4064 -0.3937)
						)
						(arc
							(start -0.4064 -0.3937)
							(mid -0.478242 -0.363942)
							(end -0.508 -0.2921)
						)
						(arc
							(start -0.508 0.2921)
							(mid -0.478242 0.363942)
							(end -0.4064 0.3937)
						)
						(arc
							(start 0.4064 0.3937)
							(mid 0.478242 0.363942)
							(end 0.508 0.2921)
						)
					)
					(width 0)
					(fill yes)
				)
			)
		)
		(pad "2" smd custom
			(at 0 0.6604 270)
			(size 0.19685 0.19685)
			(layers "F.Cu" "F.Mask" "F.Paste")
			(net "P3V3_VDD_CLKBUFF")
			(options
				(clearance outline)
				(anchor circle)
			)
			(primitives
				(gr_poly
					(pts
						(arc
							(start 0.508 -0.2921)
							(mid 0.478242 -0.363942)
							(end 0.4064 -0.3937)
						)
						(arc
							(start -0.4064 -0.3937)
							(mid -0.478242 -0.363942)
							(end -0.508 -0.2921)
						)
						(arc
							(start -0.508 0.2921)
							(mid -0.478242 0.363942)
							(end -0.4064 0.3937)
						)
						(arc
							(start 0.4064 0.3937)
							(mid 0.478242 0.363942)
							(end 0.508 0.2921)
						)
					)
					(width 0)
					(fill yes)
				)
			)
		)
	)
	(footprint ""
		(layer "F.Cu")
		(at 182.372 -33.5026)
		(property "Reference" "PR140"
			(at 0 0 0)
			(layer "F.SilkS")
			(hide yes)
			(effects
				(font
					(size 1.27 1.27)
				)
			)
		)
		(property "Value" "5K11R2F-L1-GP"
			(at 1.7907 -1.1176 0)
			(unlocked yes)
			(layer "F.Fab")
			(hide yes)
			(effects
				(font
					(size 1.016 1.016)
					(thickness 0.1524)
				)
			)
		)
		(property "Device Type" "R402H16"
			(at 1.7907 -2.6416 0)
			(unlocked yes)
			(layer "F.Fab")
			(hide yes)
			(effects
				(font
					(size 1.016 1.016)
					(thickness 0.1524)
				)
			)
		)
		(duplicate_pad_numbers_are_jumpers no)
		(fp_rect
			(start -0.381 0.8382)
			(end 0.381 -0.8382)
			(stroke
				(width 0)
				(type default)
			)
			(fill no)
			(layer "F.CrtYd")
		)
		(fp_rect
			(start -0.381 0.8382)
			(end 0.381 -0.8382)
			(stroke
				(width 0)
				(type default)
			)
			(fill no)
			(layer "F.Fab")
		)
		(pad "1" smd custom
			(at 0 -0.4318)
			(size 0.127 0.127)
			(layers "F.Cu" "F.Mask" "F.Paste")
			(net "P3V3_STBY")
			(options
				(clearance outline)
				(anchor circle)
			)
			(primitives
				(gr_poly
					(pts
						(arc
							(start -0.2032 -0.2794)
							(mid -0.239121 -0.264521)
							(end -0.254 -0.2286)
						)
						(arc
							(start -0.254 0.2286)
							(mid -0.239121 0.264521)
							(end -0.2032 0.2794)
						)
						(arc
							(start 0.2032 0.2794)
							(mid 0.239121 0.264521)
							(end 0.254 0.2286)
						)
						(arc
							(start 0.254 -0.2286)
							(mid 0.239121 -0.264521)
							(end 0.2032 -0.2794)
						)
					)
					(width 0)
					(fill yes)
				)
			)
		)
		(pad "2" smd custom
			(at 0 0.4318)
			(size 0.127 0.127)
			(layers "F.Cu" "F.Mask" "F.Paste")
			(net "PVCCP_PVNN_VRHOT#")
			(options
				(clearance outline)
				(anchor circle)
			)
			(primitives
				(gr_poly
					(pts
						(arc
							(start -0.2032 -0.2794)
							(mid -0.239121 -0.264521)
							(end -0.254 -0.2286)
						)
						(arc
							(start -0.254 0.2286)
							(mid -0.239121 0.264521)
							(end -0.2032 0.2794)
						)
						(arc
							(start 0.2032 0.2794)
							(mid 0.239121 0.264521)
							(end 0.254 0.2286)
						)
						(arc
							(start 0.254 -0.2286)
							(mid 0.239121 -0.264521)
							(end 0.2032 -0.2794)
						)
					)
					(width 0)
					(fill yes)
				)
			)
		)
	)
	(footprint ""
		(layer "F.Cu")
		(at 29.2354 -54.5084 -90)
		(property "Reference" "PR47"
			(at 0 0 270)
			(layer "F.SilkS")
			(hide yes)
			(effects
				(font
					(size 1.27 1.27)
				)
			)
		)
		(property "Value" "0R2J-2-GP"
			(at 1.7907 -1.1176 270)
			(unlocked yes)
			(layer "F.Fab")
			(hide yes)
			(effects
				(font
					(size 1.016 1.016)
					(thickness 0.1524)
				)
			)
		)
		(property "Device Type" "R402H16"
			(at 1.7907 -2.6416 270)
			(unlocked yes)
			(layer "F.Fab")
			(hide yes)
			(effects
				(font
					(size 1.016 1.016)
					(thickness 0.1524)
				)
			)
		)
		(duplicate_pad_numbers_are_jumpers no)
		(fp_rect
			(start -0.381 0.8382)
			(end 0.381 -0.8382)
			(stroke
				(width 0)
				(type default)
			)
			(fill no)
			(layer "F.CrtYd")
		)
		(fp_rect
			(start -0.381 0.8382)
			(end 0.381 -0.8382)
			(stroke
				(width 0)
				(type default)
			)
			(fill no)
			(layer "F.Fab")
		)
		(pad "1" smd custom
			(at 0 -0.4318 270)
			(size 0.127 0.127)
			(layers "F.Cu" "F.Mask" "F.Paste")
			(net "VR_PVCCP_PHASE")
			(options
				(clearance outline)
				(anchor circle)
			)
			(primitives
				(gr_poly
					(pts
						(arc
							(start -0.2032 -0.2794)
							(mid -0.239121 -0.264521)
							(end -0.254 -0.2286)
						)
						(arc
							(start -0.254 0.2286)
							(mid -0.239121 0.264521)
							(end -0.2032 0.2794)
						)
						(arc
							(start 0.2032 0.2794)
							(mid 0.239121 0.264521)
							(end 0.254 0.2286)
						)
						(arc
							(start 0.254 -0.2286)
							(mid 0.239121 -0.264521)
							(end 0.2032 -0.2794)
						)
					)
					(width 0)
					(fill yes)
				)
			)
		)
		(pad "2" smd custom
			(at 0 0.4318 270)
			(size 0.127 0.127)
			(layers "F.Cu" "F.Mask" "F.Paste")
			(net "VR_PVCCP_BOOT_R")
			(options
				(clearance outline)
				(anchor circle)
			)
			(primitives
				(gr_poly
					(pts
						(arc
							(start -0.2032 -0.2794)
							(mid -0.239121 -0.264521)
							(end -0.254 -0.2286)
						)
						(arc
							(start -0.254 0.2286)
							(mid -0.239121 0.264521)
							(end -0.2032 0.2794)
						)
						(arc
							(start 0.2032 0.2794)
							(mid 0.239121 0.264521)
							(end 0.254 0.2286)
						)
						(arc
							(start 0.254 -0.2286)
							(mid 0.239121 -0.264521)
							(end 0.2032 -0.2794)
						)
					)
					(width 0)
					(fill yes)
				)
			)
		)
	)
	(footprint ""
		(layer "F.Cu")
		(at 45.974 -21.082 180)
		(property "Reference" "C310"
			(at 0 0 180)
			(layer "F.SilkS")
			(hide yes)
			(effects
				(font
					(size 1.27 1.27)
				)
			)
		)
		(property "Value" "SCD1U10V2KX-5GP"
			(at 1.8923 -1.2065 180)
			(unlocked yes)
			(layer "F.Fab")
			(hide yes)
			(effects
				(font
					(size 1.016 1.016)
					(thickness 0.1524)
				)
			)
		)
		(property "Device Type" "C402H22"
			(at 1.8923 -2.7305 180)
			(unlocked yes)
			(layer "F.Fab")
			(hide yes)
			(effects
				(font
					(size 1.016 1.016)
					(thickness 0.1524)
				)
			)
		)
		(duplicate_pad_numbers_are_jumpers no)
		(fp_rect
			(start -0.381 0.7366)
			(end 0.381 -0.7366)
			(stroke
				(width 0)
				(type default)
			)
			(fill no)
			(layer "F.CrtYd")
		)
		(fp_rect
			(start -0.381 0.7366)
			(end 0.381 -0.7366)
			(stroke
				(width 0)
				(type default)
			)
			(fill no)
			(layer "F.Fab")
		)
		(pad "1" smd custom
			(at 0 -0.4572 180)
			(size 0.1143 0.1143)
			(layers "F.Cu" "F.Mask" "F.Paste")
			(net "P3V3_VDD_CLKBUFF")
			(options
				(clearance outline)
				(anchor circle)
			)
			(primitives
				(gr_poly
					(pts
						(arc
							(start -0.254 -0.1778)
							(mid -0.239121 -0.213721)
							(end -0.2032 -0.2286)
						)
						(arc
							(start 0.2032 -0.2286)
							(mid 0.239121 -0.213721)
							(end 0.254 -0.1778)
						)
						(arc
							(start 0.254 0.1778)
							(mid 0.239121 0.213721)
							(end 0.2032 0.2286)
						)
						(arc
							(start -0.2032 0.2286)
							(mid -0.239121 0.213721)
							(end -0.254 0.1778)
						)
					)
					(width 0)
					(fill yes)
				)
			)
		)
		(pad "2" smd custom
			(at 0 0.4572 180)
			(size 0.1143 0.1143)
			(layers "F.Cu" "F.Mask" "F.Paste")
			(net "GND")
			(options
				(clearance outline)
				(anchor circle)
			)
			(primitives
				(gr_poly
					(pts
						(arc
							(start -0.254 -0.1778)
							(mid -0.239121 -0.213721)
							(end -0.2032 -0.2286)
						)
						(arc
							(start 0.2032 -0.2286)
							(mid 0.239121 -0.213721)
							(end 0.254 -0.1778)
						)
						(arc
							(start 0.254 0.1778)
							(mid 0.239121 0.213721)
							(end 0.2032 0.2286)
						)
						(arc
							(start -0.2032 0.2286)
							(mid -0.239121 0.213721)
							(end -0.254 0.1778)
						)
					)
					(width 0)
					(fill yes)
				)
			)
		)
	)
	(footprint ""
		(layer "F.Cu")
		(at 154.94 -13.209778 90)
		(property "Reference" "PR205"
			(at 0 0 90)
			(layer "F.SilkS")
			(hide yes)
			(effects
				(font
					(size 1.27 1.27)
				)
			)
		)
		(property "Value" "0R2J-2-GP"
			(at 1.7907 -1.1176 90)
			(unlocked yes)
			(layer "F.Fab")
			(hide yes)
			(effects
				(font
					(size 1.016 1.016)
					(thickness 0.1524)
				)
			)
		)
		(property "Device Type" "R402H16"
			(at 1.7907 -2.6416 90)
			(unlocked yes)
			(layer "F.Fab")
			(hide yes)
			(effects
				(font
					(size 1.016 1.016)
					(thickness 0.1524)
				)
			)
		)
		(duplicate_pad_numbers_are_jumpers no)
		(fp_rect
			(start -0.381 0.8382)
			(end 0.381 -0.8382)
			(stroke
				(width 0)
				(type default)
			)
			(fill no)
			(layer "F.CrtYd")
		)
		(fp_rect
			(start -0.381 0.8382)
			(end 0.381 -0.8382)
			(stroke
				(width 0)
				(type default)
			)
			(fill no)
			(layer "F.Fab")
		)
		(pad "1" smd custom
			(at 0 -0.4318 90)
			(size 0.127 0.127)
			(layers "F.Cu" "F.Mask" "F.Paste")
			(net "VSENSE_PVDDR_A_VRTN")
			(options
				(clearance outline)
				(anchor circle)
			)
			(primitives
				(gr_poly
					(pts
						(arc
							(start -0.2032 -0.2794)
							(mid -0.239121 -0.264521)
							(end -0.254 -0.2286)
						)
						(arc
							(start -0.254 0.2286)
							(mid -0.239121 0.264521)
							(end -0.2032 0.2794)
						)
						(arc
							(start 0.2032 0.2794)
							(mid 0.239121 0.264521)
							(end 0.254 0.2286)
						)
						(arc
							(start 0.254 -0.2286)
							(mid 0.239121 -0.264521)
							(end 0.2032 -0.2794)
						)
					)
					(width 0)
					(fill yes)
				)
			)
		)
		(pad "2" smd custom
			(at 0 0.4318 90)
			(size 0.127 0.127)
			(layers "F.Cu" "F.Mask" "F.Paste")
			(net "GND")
			(options
				(clearance outline)
				(anchor circle)
			)
			(primitives
				(gr_poly
					(pts
						(arc
							(start -0.2032 -0.2794)
							(mid -0.239121 -0.264521)
							(end -0.254 -0.2286)
						)
						(arc
							(start -0.254 0.2286)
							(mid -0.239121 0.264521)
							(end -0.2032 0.2794)
						)
						(arc
							(start 0.2032 0.2794)
							(mid 0.239121 0.264521)
							(end 0.254 0.2286)
						)
						(arc
							(start 0.254 -0.2286)
							(mid 0.239121 -0.264521)
							(end 0.2032 -0.2794)
						)
					)
					(width 0)
					(fill yes)
				)
			)
		)
	)
	(footprint ""
		(layer "F.Cu")
		(at 188.9506 -28.2194 90)
		(property "Reference" "PR211"
			(at 0 0 90)
			(layer "F.SilkS")
			(hide yes)
			(effects
				(font
					(size 1.27 1.27)
				)
			)
		)
		(property "Value" "100R2F-L1-GP-U"
			(at 1.7907 -1.1176 90)
			(unlocked yes)
			(layer "F.Fab")
			(hide yes)
			(effects
				(font
					(size 1.016 1.016)
					(thickness 0.1524)
				)
			)
		)
		(property "Device Type" "R402H14"
			(at 1.7907 -2.6416 90)
			(unlocked yes)
			(layer "F.Fab")
			(hide yes)
			(effects
				(font
					(size 1.016 1.016)
					(thickness 0.1524)
				)
			)
		)
		(duplicate_pad_numbers_are_jumpers no)
		(fp_rect
			(start -0.381 0.8382)
			(end 0.381 -0.8382)
			(stroke
				(width 0)
				(type default)
			)
			(fill no)
			(layer "F.CrtYd")
		)
		(fp_rect
			(start -0.381 0.8382)
			(end 0.381 -0.8382)
			(stroke
				(width 0)
				(type default)
			)
			(fill no)
			(layer "F.Fab")
		)
		(pad "1" smd custom
			(at 0 -0.4318 90)
			(size 0.127 0.127)
			(layers "F.Cu" "F.Mask" "F.Paste")
			(net "VR_PVDDR_A_SUMN")
			(options
				(clearance outline)
				(anchor circle)
			)
			(primitives
				(gr_poly
					(pts
						(arc
							(start -0.2032 -0.2794)
							(mid -0.239121 -0.264521)
							(end -0.254 -0.2286)
						)
						(arc
							(start -0.254 0.2286)
							(mid -0.239121 0.264521)
							(end -0.2032 0.2794)
						)
						(arc
							(start 0.2032 0.2794)
							(mid 0.239121 0.264521)
							(end 0.254 0.2286)
						)
						(arc
							(start 0.254 -0.2286)
							(mid 0.239121 -0.264521)
							(end 0.2032 -0.2794)
						)
					)
					(width 0)
					(fill yes)
				)
			)
		)
		(pad "2" smd custom
			(at 0 0.4318 90)
			(size 0.127 0.127)
			(layers "F.Cu" "F.Mask" "F.Paste")
			(net "VR_PVDDRA_ISUMN1")
			(options
				(clearance outline)
				(anchor circle)
			)
			(primitives
				(gr_poly
					(pts
						(arc
							(start -0.2032 -0.2794)
							(mid -0.239121 -0.264521)
							(end -0.254 -0.2286)
						)
						(arc
							(start -0.254 0.2286)
							(mid -0.239121 0.264521)
							(end -0.2032 0.2794)
						)
						(arc
							(start 0.2032 0.2794)
							(mid 0.239121 0.264521)
							(end 0.254 0.2286)
						)
						(arc
							(start 0.254 -0.2286)
							(mid 0.239121 -0.264521)
							(end 0.2032 -0.2794)
						)
					)
					(width 0)
					(fill yes)
				)
			)
		)
	)
	(footprint ""
		(layer "F.Cu")
		(at 164.719 -42.418 180)
		(property "Reference" "C21"
			(at 0 0 180)
			(layer "F.SilkS")
			(hide yes)
			(effects
				(font
					(size 1.27 1.27)
				)
			)
		)
		(property "Value" "SCD1U10V2KX-5GP"
			(at 1.1811 -2.7051 180)
			(unlocked yes)
			(layer "F.Fab")
			(hide yes)
			(effects
				(font
					(size 1.016 1.016)
					(thickness 0.1524)
				)
			)
		)
		(property "Device Type" "C402H22"
			(at 1.1811 -4.2291 180)
			(unlocked yes)
			(layer "F.Fab")
			(hide yes)
			(effects
				(font
					(size 1.016 1.016)
					(thickness 0.1524)
				)
			)
		)
		(duplicate_pad_numbers_are_jumpers no)
		(fp_rect
			(start -0.381 0.7366)
			(end 0.381 -0.7366)
			(stroke
				(width 0)
				(type default)
			)
			(fill no)
			(layer "F.CrtYd")
		)
		(fp_rect
			(start -0.381 0.7366)
			(end 0.381 -0.7366)
			(stroke
				(width 0)
				(type default)
			)
			(fill no)
			(layer "F.Fab")
		)
		(pad "1" smd custom
			(at 0 -0.4572 180)
			(size 0.1143 0.1143)
			(layers "F.Cu" "F.Mask" "F.Paste")
			(net "GND")
			(options
				(clearance outline)
				(anchor circle)
			)
			(primitives
				(gr_poly
					(pts
						(arc
							(start -0.254 -0.1778)
							(mid -0.239121 -0.213721)
							(end -0.2032 -0.2286)
						)
						(arc
							(start 0.2032 -0.2286)
							(mid 0.239121 -0.213721)
							(end 0.254 -0.1778)
						)
						(arc
							(start 0.254 0.1778)
							(mid 0.239121 0.213721)
							(end 0.2032 0.2286)
						)
						(arc
							(start -0.2032 0.2286)
							(mid -0.239121 0.213721)
							(end -0.254 0.1778)
						)
					)
					(width 0)
					(fill yes)
				)
			)
		)
		(pad "2" smd custom
			(at 0 0.4572 180)
			(size 0.1143 0.1143)
			(layers "F.Cu" "F.Mask" "F.Paste")
			(net "P3V3_STBY")
			(options
				(clearance outline)
				(anchor circle)
			)
			(primitives
				(gr_poly
					(pts
						(arc
							(start -0.254 -0.1778)
							(mid -0.239121 -0.213721)
							(end -0.2032 -0.2286)
						)
						(arc
							(start 0.2032 -0.2286)
							(mid 0.239121 -0.213721)
							(end 0.254 -0.1778)
						)
						(arc
							(start 0.254 0.1778)
							(mid 0.239121 0.213721)
							(end 0.2032 0.2286)
						)
						(arc
							(start -0.2032 0.2286)
							(mid -0.239121 0.213721)
							(end -0.254 0.1778)
						)
					)
					(width 0)
					(fill yes)
				)
			)
		)
	)
	(footprint ""
		(layer "F.Cu")
		(at 28.9179 -38.862 -90)
		(property "Reference" "PR191"
			(at 0 0 270)
			(layer "F.SilkS")
			(hide yes)
			(effects
				(font
					(size 1.27 1.27)
				)
			)
		)
		(property "Value" "0R6J-3-GP"
			(at 0.0127 -3.2766 270)
			(unlocked yes)
			(layer "F.Fab")
			(hide yes)
			(effects
				(font
					(size 1.016 1.016)
					(thickness 0.1524)
				)
			)
		)
		(property "Device Type" "R1206H28"
			(at 0.0127 -4.8006 270)
			(unlocked yes)
			(layer "F.Fab")
			(hide yes)
			(effects
				(font
					(size 1.016 1.016)
					(thickness 0.1524)
				)
			)
		)
		(duplicate_pad_numbers_are_jumpers no)
		(fp_line
			(start -0.7239 0.381)
			(end 0.7239 0.381)
			(stroke
				(width 0.1524)
				(type default)
			)
			(layer "F.SilkS")
		)
		(fp_line
			(start 0.7239 0.381)
			(end 0.7239 -0.381)
			(stroke
				(width 0.1524)
				(type default)
			)
			(layer "F.SilkS")
		)
		(fp_line
			(start -0.7239 -0.381)
			(end -0.7239 0.381)
			(stroke
				(width 0.1524)
				(type default)
			)
			(layer "F.SilkS")
		)
		(fp_line
			(start 0.7239 -0.381)
			(end -0.7239 -0.381)
			(stroke
				(width 0.1524)
				(type default)
			)
			(layer "F.SilkS")
		)
		(fp_poly
			(pts
				(xy -0.7239 0.381) (xy 0.7239 0.381) (xy 0.7239 -0.381) (xy -0.7239 -0.381)
			)
			(stroke
				(width 0)
				(type default)
			)
			(fill yes)
			(layer "F.SilkS")
		)
		(fp_rect
			(start -1.0541 1.9812)
			(end 1.0541 -1.9812)
			(stroke
				(width 0)
				(type default)
			)
			(fill no)
			(layer "F.CrtYd")
		)
		(fp_rect
			(start -1.0541 1.9812)
			(end 1.0541 -1.9812)
			(stroke
				(width 0)
				(type default)
			)
			(fill no)
			(layer "F.Fab")
		)
		(pad "1" smd rect
			(at 0 -1.3462 270)
			(size 1.8542 1.016)
			(layers "F.Cu" "F.Mask" "F.Paste")
			(net "P3V3_STBY")
		)
		(pad "2" smd rect
			(at 0 1.3462 270)
			(size 1.8542 1.016)
			(layers "F.Cu" "F.Mask" "F.Paste")
			(net "P3V3_STBY_OUT")
		)
	)
	(footprint ""
		(layer "F.Cu")
		(at 137.40384 -56.46039 90)
		(property "Reference" "PU4"
			(at 0 0 90)
			(layer "F.SilkS")
			(hide yes)
			(effects
				(font
					(size 1.27 1.27)
				)
			)
		)
		(property "Value" "TPS51200-GP-U1"
			(at 2.9083 1.397 90)
			(unlocked yes)
			(layer "F.Fab")
			(hide yes)
			(effects
				(font
					(size 1.016 1.016)
					(thickness 0.1524)
				)
			)
		)
		(property "Device Type" "QFN10-G4H40"
			(at 2.9083 -0.127 90)
			(unlocked yes)
			(layer "F.Fab")
			(hide yes)
			(effects
				(font
					(size 1.016 1.016)
					(thickness 0.1524)
				)
			)
		)
		(duplicate_pad_numbers_are_jumpers no)
		(fp_poly
			(pts
				(xy 1.0287 -2.0066) (xy 1.27 -2.2479) (xy 0.7874 -2.2479)
			)
			(stroke
				(width 0)
				(type default)
			)
			(fill yes)
			(layer "F.SilkS")
		)
		(fp_rect
			(start -1.7526 2.0066)
			(end 1.7526 -2.0066)
			(stroke
				(width 0)
				(type default)
			)
			(fill no)
			(layer "F.CrtYd")
		)
		(fp_rect
			(start -1.7526 2.0066)
			(end 1.7526 -2.0066)
			(stroke
				(width 0)
				(type default)
			)
			(fill no)
			(layer "F.Fab")
		)
		(pad "1" smd rect
			(at 0.999998 -1.4605 90)
			(size 0.3048 0.8382)
			(layers "F.Cu" "F.Mask" "F.Paste")
			(net "PV_VTT_DDR_REFIN")
		)
		(pad "2" smd rect
			(at 0.500126 -1.4605 90)
			(size 0.3048 0.8382)
			(layers "F.Cu" "F.Mask" "F.Paste")
			(net "PV_VDDR")
		)
		(pad "3" smd rect
			(at 0 -1.4605 90)
			(size 0.3048 0.8382)
			(layers "F.Cu" "F.Mask" "F.Paste")
			(net "PV_VTT_DDR_A")
		)
		(pad "4" smd rect
			(at -0.500126 -1.4605 90)
			(size 0.3048 0.8382)
			(layers "F.Cu" "F.Mask" "F.Paste")
			(net "GND")
		)
		(pad "5" smd rect
			(at -0.999998 -1.4605 90)
			(size 0.3048 0.8382)
			(layers "F.Cu" "F.Mask" "F.Paste")
			(net "PV_VTT_DDR_SNS")
		)
		(pad "6" smd rect
			(at -0.999998 1.4605 90)
			(size 0.3048 0.8382)
			(layers "F.Cu" "F.Mask" "F.Paste")
			(net "PV_VTT_DDR_REFO")
		)
		(pad "7" smd rect
			(at -0.500126 1.4605 90)
			(size 0.3048 0.8382)
			(layers "F.Cu" "F.Mask" "F.Paste")
			(net "PV_VTT_DDR_EN")
		)
		(pad "8" smd rect
			(at 0 1.4605 90)
			(size 0.3048 0.8382)
			(layers "F.Cu" "F.Mask" "F.Paste")
			(net "GND")
		)
		(pad "9" smd rect
			(at 0.500126 1.4605 90)
			(size 0.3048 0.8382)
			(layers "F.Cu" "F.Mask" "F.Paste")
			(net "PV_VTT_DDR_R_PG")
		)
		(pad "10" smd rect
			(at 0.999998 1.4605 90)
			(size 0.3048 0.8382)
			(layers "F.Cu" "F.Mask" "F.Paste")
			(net "PV_VTT_DDR_VIN")
		)
		(pad "11" smd rect
			(at 0 0 90)
			(size 2.9972 1.6764)
			(layers "F.Cu" "F.Mask" "F.Paste")
			(net "GND")
		)
	)
	(footprint ""
		(layer "F.Cu")
		(at 33.401 -13.081)
		(property "Reference" "R422"
			(at 0 0 0)
			(layer "F.SilkS")
			(hide yes)
			(effects
				(font
					(size 1.27 1.27)
				)
			)
		)
		(property "Value" "0R2J-2-GP"
			(at 1.7907 -1.1176 0)
			(unlocked yes)
			(layer "F.Fab")
			(hide yes)
			(effects
				(font
					(size 1.016 1.016)
					(thickness 0.1524)
				)
			)
		)
		(property "Device Type" "R402H16"
			(at 1.7907 -2.6416 0)
			(unlocked yes)
			(layer "F.Fab")
			(hide yes)
			(effects
				(font
					(size 1.016 1.016)
					(thickness 0.1524)
				)
			)
		)
		(duplicate_pad_numbers_are_jumpers no)
		(fp_rect
			(start -0.381 0.8382)
			(end 0.381 -0.8382)
			(stroke
				(width 0)
				(type default)
			)
			(fill no)
			(layer "F.CrtYd")
		)
		(fp_rect
			(start -0.381 0.8382)
			(end 0.381 -0.8382)
			(stroke
				(width 0)
				(type default)
			)
			(fill no)
			(layer "F.Fab")
		)
		(pad "1" smd custom
			(at 0 -0.4318)
			(size 0.127 0.127)
			(layers "F.Cu" "F.Mask" "F.Paste")
			(net "BMC_I2C_DATA")
			(options
				(clearance outline)
				(anchor circle)
			)
			(primitives
				(gr_poly
					(pts
						(arc
							(start -0.2032 -0.2794)
							(mid -0.239121 -0.264521)
							(end -0.254 -0.2286)
						)
						(arc
							(start -0.254 0.2286)
							(mid -0.239121 0.264521)
							(end -0.2032 0.2794)
						)
						(arc
							(start 0.2032 0.2794)
							(mid 0.239121 0.264521)
							(end 0.254 0.2286)
						)
						(arc
							(start 0.254 -0.2286)
							(mid 0.239121 -0.264521)
							(end 0.2032 -0.2794)
						)
					)
					(width 0)
					(fill yes)
				)
			)
		)
		(pad "2" smd custom
			(at 0 0.4318)
			(size 0.127 0.127)
			(layers "F.Cu" "F.Mask" "F.Paste")
			(net "PCIE_GF_I2C_DATA")
			(options
				(clearance outline)
				(anchor circle)
			)
			(primitives
				(gr_poly
					(pts
						(arc
							(start -0.2032 -0.2794)
							(mid -0.239121 -0.264521)
							(end -0.254 -0.2286)
						)
						(arc
							(start -0.254 0.2286)
							(mid -0.239121 0.264521)
							(end -0.2032 0.2794)
						)
						(arc
							(start 0.2032 0.2794)
							(mid 0.239121 0.264521)
							(end 0.254 0.2286)
						)
						(arc
							(start 0.254 -0.2286)
							(mid 0.239121 -0.264521)
							(end 0.2032 -0.2794)
						)
					)
					(width 0)
					(fill yes)
				)
			)
		)
	)
	(footprint ""
		(layer "F.Cu")
		(at 38.354 -39.116)
		(property "Reference" "R249"
			(at 0 0 0)
			(layer "F.SilkS")
			(hide yes)
			(effects
				(font
					(size 1.27 1.27)
				)
			)
		)
		(property "Value" "0R2J-2-GP"
			(at 0.064008 -3.993896 0)
			(unlocked yes)
			(layer "F.Fab")
			(hide yes)
			(effects
				(font
					(size 1.016 1.016)
					(thickness 0.1524)
				)
			)
		)
		(property "Device Type" "R402H16"
			(at 0.064008 -5.517896 0)
			(unlocked yes)
			(layer "F.Fab")
			(hide yes)
			(effects
				(font
					(size 1.016 1.016)
					(thickness 0.1524)
				)
			)
		)
		(duplicate_pad_numbers_are_jumpers no)
		(fp_rect
			(start -0.381 0.8382)
			(end 0.381 -0.8382)
			(stroke
				(width 0)
				(type default)
			)
			(fill no)
			(layer "F.CrtYd")
		)
		(fp_rect
			(start -0.381 0.8382)
			(end 0.381 -0.8382)
			(stroke
				(width 0)
				(type default)
			)
			(fill no)
			(layer "F.Fab")
		)
		(pad "1" smd custom
			(at 0 -0.4318)
			(size 0.127 0.127)
			(layers "F.Cu" "F.Mask" "F.Paste")
			(net "SMBUS_HOST_CLK")
			(options
				(clearance outline)
				(anchor circle)
			)
			(primitives
				(gr_poly
					(pts
						(arc
							(start -0.2032 -0.2794)
							(mid -0.239121 -0.264521)
							(end -0.254 -0.2286)
						)
						(arc
							(start -0.254 0.2286)
							(mid -0.239121 0.264521)
							(end -0.2032 0.2794)
						)
						(arc
							(start 0.2032 0.2794)
							(mid 0.239121 0.264521)
							(end 0.254 0.2286)
						)
						(arc
							(start 0.254 -0.2286)
							(mid 0.239121 -0.264521)
							(end 0.2032 -0.2794)
						)
					)
					(width 0)
					(fill yes)
				)
			)
		)
		(pad "2" smd custom
			(at 0 0.4318)
			(size 0.127 0.127)
			(layers "F.Cu" "F.Mask" "F.Paste")
			(net "SMB_XDP_CLK_R")
			(options
				(clearance outline)
				(anchor circle)
			)
			(primitives
				(gr_poly
					(pts
						(arc
							(start -0.2032 -0.2794)
							(mid -0.239121 -0.264521)
							(end -0.254 -0.2286)
						)
						(arc
							(start -0.254 0.2286)
							(mid -0.239121 0.264521)
							(end -0.2032 0.2794)
						)
						(arc
							(start 0.2032 0.2794)
							(mid 0.239121 0.264521)
							(end 0.254 0.2286)
						)
						(arc
							(start 0.254 -0.2286)
							(mid 0.239121 -0.264521)
							(end 0.2032 -0.2794)
						)
					)
					(width 0)
					(fill yes)
				)
			)
		)
	)
	(footprint ""
		(layer "F.Cu")
		(at 36.068 -39.116)
		(property "Reference" "R244"
			(at 0 0 0)
			(layer "F.SilkS")
			(hide yes)
			(effects
				(font
					(size 1.27 1.27)
				)
			)
		)
		(property "Value" "1KR2F-3-GP"
			(at 0.064008 -3.993896 0)
			(unlocked yes)
			(layer "F.Fab")
			(hide yes)
			(effects
				(font
					(size 1.016 1.016)
					(thickness 0.1524)
				)
			)
		)
		(property "Device Type" "R402H16"
			(at 0.064008 -5.517896 0)
			(unlocked yes)
			(layer "F.Fab")
			(hide yes)
			(effects
				(font
					(size 1.016 1.016)
					(thickness 0.1524)
				)
			)
		)
		(duplicate_pad_numbers_are_jumpers no)
		(fp_rect
			(start -0.381 0.8382)
			(end 0.381 -0.8382)
			(stroke
				(width 0)
				(type default)
			)
			(fill no)
			(layer "F.CrtYd")
		)
		(fp_rect
			(start -0.381 0.8382)
			(end 0.381 -0.8382)
			(stroke
				(width 0)
				(type default)
			)
			(fill no)
			(layer "F.Fab")
		)
		(pad "1" smd custom
			(at 0 -0.4318)
			(size 0.127 0.127)
			(layers "F.Cu" "F.Mask" "F.Paste")
			(net "CORE_PWROK")
			(options
				(clearance outline)
				(anchor circle)
			)
			(primitives
				(gr_poly
					(pts
						(arc
							(start -0.2032 -0.2794)
							(mid -0.239121 -0.264521)
							(end -0.254 -0.2286)
						)
						(arc
							(start -0.254 0.2286)
							(mid -0.239121 0.264521)
							(end -0.2032 0.2794)
						)
						(arc
							(start 0.2032 0.2794)
							(mid 0.239121 0.264521)
							(end 0.254 0.2286)
						)
						(arc
							(start 0.254 -0.2286)
							(mid 0.239121 -0.264521)
							(end 0.2032 -0.2794)
						)
					)
					(width 0)
					(fill yes)
				)
			)
		)
		(pad "2" smd custom
			(at 0 0.4318)
			(size 0.127 0.127)
			(layers "F.Cu" "F.Mask" "F.Paste")
			(net "XDP_PWRGD_IN")
			(options
				(clearance outline)
				(anchor circle)
			)
			(primitives
				(gr_poly
					(pts
						(arc
							(start -0.2032 -0.2794)
							(mid -0.239121 -0.264521)
							(end -0.254 -0.2286)
						)
						(arc
							(start -0.254 0.2286)
							(mid -0.239121 0.264521)
							(end -0.2032 0.2794)
						)
						(arc
							(start 0.2032 0.2794)
							(mid 0.239121 0.264521)
							(end 0.254 0.2286)
						)
						(arc
							(start 0.254 -0.2286)
							(mid 0.239121 -0.264521)
							(end 0.2032 -0.2794)
						)
					)
					(width 0)
					(fill yes)
				)
			)
		)
	)
	(footprint ""
		(layer "F.Cu")
		(at 184.15 -48.26 -90)
		(property "Reference" "U26"
			(at 0 0 270)
			(layer "F.SilkS")
			(hide yes)
			(effects
				(font
					(size 1.27 1.27)
				)
			)
		)
		(property "Value" "ISL90727WIE627Z-TK-2-GP"
			(at -2.3622 -8.2042 270)
			(unlocked yes)
			(layer "F.Fab")
			(hide yes)
			(effects
				(font
					(size 1.016 1.016)
					(thickness 0.1524)
				)
			)
		)
		(property "Device Type" "SC70-6H44"
			(at -2.3622 -10.1092 270)
			(unlocked yes)
			(layer "F.Fab")
			(hide yes)
			(effects
				(font
					(size 1.016 1.016)
					(thickness 0.1524)
				)
			)
		)
		(duplicate_pad_numbers_are_jumpers no)
		(fp_line
			(start -1.0033 0.4699)
			(end 1.0033 0.4699)
			(stroke
				(width 0.1524)
				(type default)
			)
			(layer "F.SilkS")
		)
		(fp_line
			(start 1.0033 0.4699)
			(end 1.0033 -0.4699)
			(stroke
				(width 0.1524)
				(type default)
			)
			(layer "F.SilkS")
		)
		(fp_line
			(start -1.1811 0.1905)
			(end -1.1811 1.1938)
			(stroke
				(width 0.381)
				(type default)
			)
			(layer "F.SilkS")
		)
		(fp_line
			(start -1.0033 -0.4699)
			(end -1.0033 0.4699)
			(stroke
				(width 0.1524)
				(type default)
			)
			(layer "F.SilkS")
		)
		(fp_line
			(start 1.0033 -0.4699)
			(end -1.0033 -0.4699)
			(stroke
				(width 0.1524)
				(type default)
			)
			(layer "F.SilkS")
		)
		(fp_poly
			(pts
				(xy 1.2573 -0.8763) (xy 1.2573 0.8763) (xy 0.9779 0.8763) (xy 0.9779 1.4097) (xy -0.9779 1.4097)
				(xy -0.9779 0.8763) (xy -1.2573 0.8763) (xy -1.2573 -0.8763) (xy -0.9779 -0.8763) (xy -0.9779 -1.4097)
				(xy 0.9779 -1.4097) (xy 0.9779 -0.8763)
			)
			(stroke
				(width 0)
				(type default)
			)
			(fill no)
			(layer "F.CrtYd")
		)
		(fp_poly
			(pts
				(xy 1.2573 -0.8763) (xy 1.2573 0.8763) (xy 0.9779 0.8763) (xy 0.9779 1.4097) (xy -0.9779 1.4097)
				(xy -0.9779 0.8763) (xy -1.2573 0.8763) (xy -1.2573 -0.8763) (xy -0.9779 -0.8763) (xy -0.9779 -1.4097)
				(xy 0.9779 -1.4097) (xy 0.9779 -0.8763)
			)
			(stroke
				(width 0)
				(type default)
			)
			(fill no)
			(layer "F.Fab")
		)
		(pad "1" smd rect
			(at -0.65024 0.94996 270)
			(size 0.4064 0.6604)
			(layers "F.Cu" "F.Mask" "F.Paste")
			(net "P3V3_STBY")
		)
		(pad "2" smd rect
			(at 0 0.94996 270)
			(size 0.4064 0.6604)
			(layers "F.Cu" "F.Mask" "F.Paste")
			(net "GND")
		)
		(pad "3" smd rect
			(at 0.65024 0.94996 270)
			(size 0.4064 0.6604)
			(layers "F.Cu" "F.Mask" "F.Paste")
			(net "SMB_DPOT_CLK")
		)
		(pad "4" smd rect
			(at 0.65024 -0.94996 270)
			(size 0.4064 0.6604)
			(layers "F.Cu" "F.Mask" "F.Paste")
			(net "SMB_DPOT_DATA")
		)
		(pad "5" smd rect
			(at 0 -0.94996 270)
			(size 0.4064 0.6604)
			(layers "F.Cu" "F.Mask" "F.Paste")
			(net "PV_VDDR_VREF_RW")
		)
		(pad "6" smd rect
			(at -0.65024 -0.94996 270)
			(size 0.4064 0.6604)
			(layers "F.Cu" "F.Mask" "F.Paste")
			(net "PV_VDDR")
		)
	)
	(footprint ""
		(layer "F.Cu")
		(at 64.262 -32.258 -90)
		(property "Reference" "R240"
			(at 0 0 270)
			(layer "F.SilkS")
			(hide yes)
			(effects
				(font
					(size 1.27 1.27)
				)
			)
		)
		(property "Value" "1KR2F-3-GP"
			(at 0.064008 -3.993896 270)
			(unlocked yes)
			(layer "F.Fab")
			(hide yes)
			(effects
				(font
					(size 1.016 1.016)
					(thickness 0.1524)
				)
			)
		)
		(property "Device Type" "R402H16"
			(at 0.064008 -5.517896 270)
			(unlocked yes)
			(layer "F.Fab")
			(hide yes)
			(effects
				(font
					(size 1.016 1.016)
					(thickness 0.1524)
				)
			)
		)
		(duplicate_pad_numbers_are_jumpers no)
		(fp_rect
			(start -0.381 0.8382)
			(end 0.381 -0.8382)
			(stroke
				(width 0)
				(type default)
			)
			(fill no)
			(layer "F.CrtYd")
		)
		(fp_rect
			(start -0.381 0.8382)
			(end 0.381 -0.8382)
			(stroke
				(width 0)
				(type default)
			)
			(fill no)
			(layer "F.Fab")
		)
		(pad "1" smd custom
			(at 0 -0.4318 270)
			(size 0.127 0.127)
			(layers "F.Cu" "F.Mask" "F.Paste")
			(net "P1V8")
			(options
				(clearance outline)
				(anchor circle)
			)
			(primitives
				(gr_poly
					(pts
						(arc
							(start -0.2032 -0.2794)
							(mid -0.239121 -0.264521)
							(end -0.254 -0.2286)
						)
						(arc
							(start -0.254 0.2286)
							(mid -0.239121 0.264521)
							(end -0.2032 0.2794)
						)
						(arc
							(start 0.2032 0.2794)
							(mid 0.239121 0.264521)
							(end 0.254 0.2286)
						)
						(arc
							(start 0.254 -0.2286)
							(mid 0.239121 -0.264521)
							(end 0.2032 -0.2794)
						)
					)
					(width 0)
					(fill yes)
				)
			)
		)
		(pad "2" smd custom
			(at 0 0.4318 270)
			(size 0.127 0.127)
			(layers "F.Cu" "F.Mask" "F.Paste")
			(net "P1V8_B")
			(options
				(clearance outline)
				(anchor circle)
			)
			(primitives
				(gr_poly
					(pts
						(arc
							(start -0.2032 -0.2794)
							(mid -0.239121 -0.264521)
							(end -0.254 -0.2286)
						)
						(arc
							(start -0.254 0.2286)
							(mid -0.239121 0.264521)
							(end -0.2032 0.2794)
						)
						(arc
							(start 0.2032 0.2794)
							(mid 0.239121 0.264521)
							(end 0.254 0.2286)
						)
						(arc
							(start 0.254 -0.2286)
							(mid 0.239121 -0.264521)
							(end 0.2032 -0.2794)
						)
					)
					(width 0)
					(fill yes)
				)
			)
		)
	)
	(footprint ""
		(layer "F.Cu")
		(at 182.499 -52.9336)
		(property "Reference" "C92"
			(at 0 0 0)
			(layer "F.SilkS")
			(hide yes)
			(effects
				(font
					(size 1.27 1.27)
				)
			)
		)
		(property "Value" "SC1U6D3V2KX-GP"
			(at 1.1811 -2.7051 0)
			(unlocked yes)
			(layer "F.Fab")
			(hide yes)
			(effects
				(font
					(size 1.016 1.016)
					(thickness 0.1524)
				)
			)
		)
		(property "Device Type" "C402H22"
			(at 1.1811 -4.2291 0)
			(unlocked yes)
			(layer "F.Fab")
			(hide yes)
			(effects
				(font
					(size 1.016 1.016)
					(thickness 0.1524)
				)
			)
		)
		(duplicate_pad_numbers_are_jumpers no)
		(fp_rect
			(start -0.381 0.7366)
			(end 0.381 -0.7366)
			(stroke
				(width 0)
				(type default)
			)
			(fill no)
			(layer "F.CrtYd")
		)
		(fp_rect
			(start -0.381 0.7366)
			(end 0.381 -0.7366)
			(stroke
				(width 0)
				(type default)
			)
			(fill no)
			(layer "F.Fab")
		)
		(pad "1" smd custom
			(at 0 -0.4572)
			(size 0.1143 0.1143)
			(layers "F.Cu" "F.Mask" "F.Paste")
			(net "PV_VDDR_VREF_A")
			(options
				(clearance outline)
				(anchor circle)
			)
			(primitives
				(gr_poly
					(pts
						(arc
							(start -0.254 -0.1778)
							(mid -0.239121 -0.213721)
							(end -0.2032 -0.2286)
						)
						(arc
							(start 0.2032 -0.2286)
							(mid 0.239121 -0.213721)
							(end 0.254 -0.1778)
						)
						(arc
							(start 0.254 0.1778)
							(mid 0.239121 0.213721)
							(end 0.2032 0.2286)
						)
						(arc
							(start -0.2032 0.2286)
							(mid -0.239121 0.213721)
							(end -0.254 0.1778)
						)
					)
					(width 0)
					(fill yes)
				)
			)
		)
		(pad "2" smd custom
			(at 0 0.4572)
			(size 0.1143 0.1143)
			(layers "F.Cu" "F.Mask" "F.Paste")
			(net "GND")
			(options
				(clearance outline)
				(anchor circle)
			)
			(primitives
				(gr_poly
					(pts
						(arc
							(start -0.254 -0.1778)
							(mid -0.239121 -0.213721)
							(end -0.2032 -0.2286)
						)
						(arc
							(start 0.2032 -0.2286)
							(mid 0.239121 -0.213721)
							(end 0.254 -0.1778)
						)
						(arc
							(start 0.254 0.1778)
							(mid 0.239121 0.213721)
							(end 0.2032 0.2286)
						)
						(arc
							(start -0.2032 0.2286)
							(mid -0.239121 0.213721)
							(end -0.254 0.1778)
						)
					)
					(width 0)
					(fill yes)
				)
			)
		)
	)
	(footprint ""
		(layer "F.Cu")
		(at 29.083 -42.037 -90)
		(property "Reference" "PR194"
			(at 0 0 270)
			(layer "F.SilkS")
			(hide yes)
			(effects
				(font
					(size 1.27 1.27)
				)
			)
		)
		(property "Value" "0R6J-3-GP"
			(at 0.0127 -3.2766 270)
			(unlocked yes)
			(layer "F.Fab")
			(hide yes)
			(effects
				(font
					(size 1.016 1.016)
					(thickness 0.1524)
				)
			)
		)
		(property "Device Type" "R1206H28"
			(at 0.0127 -4.8006 270)
			(unlocked yes)
			(layer "F.Fab")
			(hide yes)
			(effects
				(font
					(size 1.016 1.016)
					(thickness 0.1524)
				)
			)
		)
		(duplicate_pad_numbers_are_jumpers no)
		(fp_line
			(start -0.7239 0.381)
			(end 0.7239 0.381)
			(stroke
				(width 0.1524)
				(type default)
			)
			(layer "F.SilkS")
		)
		(fp_line
			(start 0.7239 0.381)
			(end 0.7239 -0.381)
			(stroke
				(width 0.1524)
				(type default)
			)
			(layer "F.SilkS")
		)
		(fp_line
			(start -0.7239 -0.381)
			(end -0.7239 0.381)
			(stroke
				(width 0.1524)
				(type default)
			)
			(layer "F.SilkS")
		)
		(fp_line
			(start 0.7239 -0.381)
			(end -0.7239 -0.381)
			(stroke
				(width 0.1524)
				(type default)
			)
			(layer "F.SilkS")
		)
		(fp_poly
			(pts
				(xy -0.7239 0.381) (xy 0.7239 0.381) (xy 0.7239 -0.381) (xy -0.7239 -0.381)
			)
			(stroke
				(width 0)
				(type default)
			)
			(fill yes)
			(layer "F.SilkS")
		)
		(fp_rect
			(start -1.0541 1.9812)
			(end 1.0541 -1.9812)
			(stroke
				(width 0)
				(type default)
			)
			(fill no)
			(layer "F.CrtYd")
		)
		(fp_rect
			(start -1.0541 1.9812)
			(end 1.0541 -1.9812)
			(stroke
				(width 0)
				(type default)
			)
			(fill no)
			(layer "F.Fab")
		)
		(pad "1" smd rect
			(at 0 -1.3462 270)
			(size 1.8542 1.016)
			(layers "F.Cu" "F.Mask" "F.Paste")
			(net "P3V3_STBY")
		)
		(pad "2" smd rect
			(at 0 1.3462 270)
			(size 1.8542 1.016)
			(layers "F.Cu" "F.Mask" "F.Paste")
			(net "P3V3_STBY_OUT")
		)
	)
	(footprint ""
		(layer "F.Cu")
		(at 69.596 -31.496 90)
		(property "Reference" "R124"
			(at 0 0 90)
			(layer "F.SilkS")
			(hide yes)
			(effects
				(font
					(size 1.27 1.27)
				)
			)
		)
		(property "Value" "4K7R2F-GP"
			(at 0.064008 -3.993896 90)
			(unlocked yes)
			(layer "F.Fab")
			(hide yes)
			(effects
				(font
					(size 1.016 1.016)
					(thickness 0.1524)
				)
			)
		)
		(property "Device Type" "R402H16"
			(at 0.064008 -5.517896 90)
			(unlocked yes)
			(layer "F.Fab")
			(hide yes)
			(effects
				(font
					(size 1.016 1.016)
					(thickness 0.1524)
				)
			)
		)
		(duplicate_pad_numbers_are_jumpers no)
		(fp_rect
			(start -0.381 0.8382)
			(end 0.381 -0.8382)
			(stroke
				(width 0)
				(type default)
			)
			(fill no)
			(layer "F.CrtYd")
		)
		(fp_rect
			(start -0.381 0.8382)
			(end 0.381 -0.8382)
			(stroke
				(width 0)
				(type default)
			)
			(fill no)
			(layer "F.Fab")
		)
		(pad "1" smd custom
			(at 0 -0.4318 90)
			(size 0.127 0.127)
			(layers "F.Cu" "F.Mask" "F.Paste")
			(net "P3V3_CPU")
			(options
				(clearance outline)
				(anchor circle)
			)
			(primitives
				(gr_poly
					(pts
						(arc
							(start -0.2032 -0.2794)
							(mid -0.239121 -0.264521)
							(end -0.254 -0.2286)
						)
						(arc
							(start -0.254 0.2286)
							(mid -0.239121 0.264521)
							(end -0.2032 0.2794)
						)
						(arc
							(start 0.2032 0.2794)
							(mid 0.239121 0.264521)
							(end 0.254 0.2286)
						)
						(arc
							(start 0.254 -0.2286)
							(mid 0.239121 -0.264521)
							(end 0.2032 -0.2794)
						)
					)
					(width 0)
					(fill yes)
				)
			)
		)
		(pad "2" smd custom
			(at 0 0.4318 90)
			(size 0.127 0.127)
			(layers "F.Cu" "F.Mask" "F.Paste")
			(net "BD_ID_2")
			(options
				(clearance outline)
				(anchor circle)
			)
			(primitives
				(gr_poly
					(pts
						(arc
							(start -0.2032 -0.2794)
							(mid -0.239121 -0.264521)
							(end -0.254 -0.2286)
						)
						(arc
							(start -0.254 0.2286)
							(mid -0.239121 0.264521)
							(end -0.2032 0.2794)
						)
						(arc
							(start 0.2032 0.2794)
							(mid 0.239121 0.264521)
							(end 0.254 0.2286)
						)
						(arc
							(start 0.254 -0.2286)
							(mid 0.239121 -0.264521)
							(end 0.2032 -0.2794)
						)
					)
					(width 0)
					(fill yes)
				)
			)
		)
	)
	(footprint ""
		(layer "F.Cu")
		(at 79.883 -61.595)
		(property "Reference" "C69"
			(at 0 0 0)
			(layer "F.SilkS")
			(hide yes)
			(effects
				(font
					(size 1.27 1.27)
				)
			)
		)
		(property "Value" "SCD1U16V2KX-3GP"
			(at 1.1811 -2.7051 0)
			(unlocked yes)
			(layer "F.Fab")
			(hide yes)
			(effects
				(font
					(size 1.016 1.016)
					(thickness 0.1524)
				)
			)
		)
		(property "Device Type" "C402H22"
			(at 1.1811 -4.2291 0)
			(unlocked yes)
			(layer "F.Fab")
			(hide yes)
			(effects
				(font
					(size 1.016 1.016)
					(thickness 0.1524)
				)
			)
		)
		(duplicate_pad_numbers_are_jumpers no)
		(fp_rect
			(start -0.381 0.7366)
			(end 0.381 -0.7366)
			(stroke
				(width 0)
				(type default)
			)
			(fill no)
			(layer "F.CrtYd")
		)
		(fp_rect
			(start -0.381 0.7366)
			(end 0.381 -0.7366)
			(stroke
				(width 0)
				(type default)
			)
			(fill no)
			(layer "F.Fab")
		)
		(pad "1" smd custom
			(at 0 -0.4572)
			(size 0.1143 0.1143)
			(layers "F.Cu" "F.Mask" "F.Paste")
			(net "PV_VDDR_SENSE")
			(options
				(clearance outline)
				(anchor circle)
			)
			(primitives
				(gr_poly
					(pts
						(arc
							(start -0.254 -0.1778)
							(mid -0.239121 -0.213721)
							(end -0.2032 -0.2286)
						)
						(arc
							(start 0.2032 -0.2286)
							(mid 0.239121 -0.213721)
							(end 0.254 -0.1778)
						)
						(arc
							(start 0.254 0.1778)
							(mid 0.239121 0.213721)
							(end 0.2032 0.2286)
						)
						(arc
							(start -0.2032 0.2286)
							(mid -0.239121 0.213721)
							(end -0.254 0.1778)
						)
					)
					(width 0)
					(fill yes)
				)
			)
		)
		(pad "2" smd custom
			(at 0 0.4572)
			(size 0.1143 0.1143)
			(layers "F.Cu" "F.Mask" "F.Paste")
			(net "GND")
			(options
				(clearance outline)
				(anchor circle)
			)
			(primitives
				(gr_poly
					(pts
						(arc
							(start -0.254 -0.1778)
							(mid -0.239121 -0.213721)
							(end -0.2032 -0.2286)
						)
						(arc
							(start 0.2032 -0.2286)
							(mid 0.239121 -0.213721)
							(end 0.254 -0.1778)
						)
						(arc
							(start 0.254 0.1778)
							(mid 0.239121 0.213721)
							(end 0.2032 0.2286)
						)
						(arc
							(start -0.2032 0.2286)
							(mid -0.239121 0.213721)
							(end -0.254 0.1778)
						)
					)
					(width 0)
					(fill yes)
				)
			)
		)
	)
	(footprint ""
		(layer "F.Cu")
		(at 128.143 -34.29 90)
		(property "Reference" "R27"
			(at 0 0 90)
			(layer "F.SilkS")
			(hide yes)
			(effects
				(font
					(size 1.27 1.27)
				)
			)
		)
		(property "Value" "4K7R2F-GP"
			(at 0.064008 -3.993896 90)
			(unlocked yes)
			(layer "F.Fab")
			(hide yes)
			(effects
				(font
					(size 1.016 1.016)
					(thickness 0.1524)
				)
			)
		)
		(property "Device Type" "R402H16"
			(at 0.064008 -5.517896 90)
			(unlocked yes)
			(layer "F.Fab")
			(hide yes)
			(effects
				(font
					(size 1.016 1.016)
					(thickness 0.1524)
				)
			)
		)
		(duplicate_pad_numbers_are_jumpers no)
		(fp_rect
			(start -0.381 0.8382)
			(end 0.381 -0.8382)
			(stroke
				(width 0)
				(type default)
			)
			(fill no)
			(layer "F.CrtYd")
		)
		(fp_rect
			(start -0.381 0.8382)
			(end 0.381 -0.8382)
			(stroke
				(width 0)
				(type default)
			)
			(fill no)
			(layer "F.Fab")
		)
		(pad "1" smd custom
			(at 0 -0.4318 90)
			(size 0.127 0.127)
			(layers "F.Cu" "F.Mask" "F.Paste")
			(net "P3V3_STBY")
			(options
				(clearance outline)
				(anchor circle)
			)
			(primitives
				(gr_poly
					(pts
						(arc
							(start -0.2032 -0.2794)
							(mid -0.239121 -0.264521)
							(end -0.254 -0.2286)
						)
						(arc
							(start -0.254 0.2286)
							(mid -0.239121 0.264521)
							(end -0.2032 0.2794)
						)
						(arc
							(start 0.2032 0.2794)
							(mid 0.239121 0.264521)
							(end 0.254 0.2286)
						)
						(arc
							(start 0.254 -0.2286)
							(mid 0.239121 -0.264521)
							(end 0.2032 -0.2794)
						)
					)
					(width 0)
					(fill yes)
				)
			)
		)
		(pad "2" smd custom
			(at 0 0.4318 90)
			(size 0.127 0.127)
			(layers "F.Cu" "F.Mask" "F.Paste")
			(net "SMB_PECI_LV_DATA")
			(options
				(clearance outline)
				(anchor circle)
			)
			(primitives
				(gr_poly
					(pts
						(arc
							(start -0.2032 -0.2794)
							(mid -0.239121 -0.264521)
							(end -0.254 -0.2286)
						)
						(arc
							(start -0.254 0.2286)
							(mid -0.239121 0.264521)
							(end -0.2032 0.2794)
						)
						(arc
							(start 0.2032 0.2794)
							(mid 0.239121 0.264521)
							(end 0.254 0.2286)
						)
						(arc
							(start 0.254 -0.2286)
							(mid 0.239121 -0.264521)
							(end 0.2032 -0.2794)
						)
					)
					(width 0)
					(fill yes)
				)
			)
		)
	)
	(footprint ""
		(layer "F.Cu")
		(at 11.557 -32.004 -90)
		(property "Reference" "PG6"
			(at 0 0 270)
			(layer "F.SilkS")
			(hide yes)
			(effects
				(font
					(size 1.27 1.27)
				)
			)
		)
		(property "Value" "COPPER-CLOSE-GP-U"
			(at 0.0762 -2.8702 270)
			(unlocked yes)
			(layer "F.Fab")
			(hide yes)
			(effects
				(font
					(size 1.016 1.016)
					(thickness 0.1524)
				)
			)
		)
		(property "Device Type" "CON2C-U"
			(at 0.0762 -4.3942 270)
			(unlocked yes)
			(layer "F.Fab")
			(hide yes)
			(effects
				(font
					(size 1.016 1.016)
					(thickness 0.1524)
				)
			)
		)
		(duplicate_pad_numbers_are_jumpers no)
		(fp_rect
			(start -0.9398 0.9652)
			(end 0.9398 -0.9652)
			(stroke
				(width 0)
				(type default)
			)
			(fill no)
			(layer "F.CrtYd")
		)
		(fp_rect
			(start -0.9398 0.9652)
			(end 0.9398 -0.9652)
			(stroke
				(width 0)
				(type default)
			)
			(fill no)
			(layer "F.Fab")
		)
		(pad "1" smd custom
			(at 0 -0.5334 270)
			(size 0.17145 0.17145)
			(layers "F.Cu" "F.Mask" "F.Paste")
			(net "AGND_P3V3_STBY")
			(options
				(clearance outline)
				(anchor circle)
			)
			(primitives
				(gr_poly
					(pts
						(xy -0.127 0.3429) (xy -0.127 0.1651) (xy -0.635 -0.3429) (xy 0.635 -0.3429) (xy 0.127 0.1651)
						(xy 0.127 0.3429)
					)
					(width 0)
					(fill yes)
				)
			)
		)
		(pad "2" smd custom
			(at 0 0.5334 270)
			(size 0.17145 0.17145)
			(layers "F.Cu" "F.Mask" "F.Paste")
			(net "GND")
			(options
				(clearance outline)
				(anchor circle)
			)
			(primitives
				(gr_poly
					(pts
						(xy -0.635 0.3429) (xy -0.127 -0.1651) (xy -0.127 -0.3429) (xy 0.127 -0.3429) (xy 0.127 -0.1651)
						(xy 0.635 0.3429)
					)
					(width 0)
					(fill yes)
				)
			)
		)
	)
	(footprint ""
		(layer "F.Cu")
		(at 38.227 -52.07 -90)
		(property "Reference" "R138"
			(at 0 0 270)
			(layer "F.SilkS")
			(hide yes)
			(effects
				(font
					(size 1.27 1.27)
				)
			)
		)
		(property "Value" "10KR2F-2-GP"
			(at 1.7907 -1.1176 270)
			(unlocked yes)
			(layer "F.Fab")
			(hide yes)
			(effects
				(font
					(size 1.016 1.016)
					(thickness 0.1524)
				)
			)
		)
		(property "Device Type" "R402H16"
			(at 1.7907 -2.6416 270)
			(unlocked yes)
			(layer "F.Fab")
			(hide yes)
			(effects
				(font
					(size 1.016 1.016)
					(thickness 0.1524)
				)
			)
		)
		(duplicate_pad_numbers_are_jumpers no)
		(fp_rect
			(start -0.381 0.8382)
			(end 0.381 -0.8382)
			(stroke
				(width 0)
				(type default)
			)
			(fill no)
			(layer "F.CrtYd")
		)
		(fp_rect
			(start -0.381 0.8382)
			(end 0.381 -0.8382)
			(stroke
				(width 0)
				(type default)
			)
			(fill no)
			(layer "F.Fab")
		)
		(pad "1" smd custom
			(at 0 -0.4318 270)
			(size 0.127 0.127)
			(layers "F.Cu" "F.Mask" "F.Paste")
			(net "GND")
			(options
				(clearance outline)
				(anchor circle)
			)
			(primitives
				(gr_poly
					(pts
						(arc
							(start -0.2032 -0.2794)
							(mid -0.239121 -0.264521)
							(end -0.254 -0.2286)
						)
						(arc
							(start -0.254 0.2286)
							(mid -0.239121 0.264521)
							(end -0.2032 0.2794)
						)
						(arc
							(start 0.2032 0.2794)
							(mid 0.239121 0.264521)
							(end 0.254 0.2286)
						)
						(arc
							(start 0.254 -0.2286)
							(mid 0.239121 -0.264521)
							(end 0.2032 -0.2794)
						)
					)
					(width 0)
					(fill yes)
				)
			)
		)
		(pad "2" smd custom
			(at 0 0.4318 270)
			(size 0.127 0.127)
			(layers "F.Cu" "F.Mask" "F.Paste")
			(net "CLK_14M_CPU")
			(options
				(clearance outline)
				(anchor circle)
			)
			(primitives
				(gr_poly
					(pts
						(arc
							(start -0.2032 -0.2794)
							(mid -0.239121 -0.264521)
							(end -0.254 -0.2286)
						)
						(arc
							(start -0.254 0.2286)
							(mid -0.239121 0.264521)
							(end -0.2032 0.2794)
						)
						(arc
							(start 0.2032 0.2794)
							(mid 0.239121 0.264521)
							(end 0.254 0.2286)
						)
						(arc
							(start 0.254 -0.2286)
							(mid 0.239121 -0.264521)
							(end 0.2032 -0.2794)
						)
					)
					(width 0)
					(fill yes)
				)
			)
		)
	)
	(footprint ""
		(layer "F.Cu")
		(at 52.451 -45.466)
		(property "Reference" "U8"
			(at 0 0 0)
			(layer "F.SilkS")
			(hide yes)
			(effects
				(font
					(size 1.27 1.27)
				)
			)
		)
		(property "Value" "2N7002DW-7F-GP"
			(at -2.3622 -8.2042 0)
			(unlocked yes)
			(layer "F.Fab")
			(hide yes)
			(effects
				(font
					(size 1.016 1.016)
					(thickness 0.1524)
				)
			)
		)
		(property "Device Type" "SOT-363H44"
			(at -2.3622 -10.1092 0)
			(unlocked yes)
			(layer "F.Fab")
			(hide yes)
			(effects
				(font
					(size 1.016 1.016)
					(thickness 0.1524)
				)
			)
		)
		(duplicate_pad_numbers_are_jumpers no)
		(fp_poly
			(pts
				(xy -0.6731 1.4351) (xy -0.9779 1.7399) (xy -0.381 1.7399) (xy -0.3683 1.7399) (xy -0.381 1.7272)
			)
			(stroke
				(width 0)
				(type default)
			)
			(fill yes)
			(layer "F.SilkS")
		)
		(fp_poly
			(pts
				(xy 1.2573 0.8763) (xy 1.2573 -0.8763) (xy 0.9525 -0.8763) (xy 0.9525 -1.4351) (xy -0.9525 -1.4351)
				(xy -0.9525 -0.8763) (xy -1.2573 -0.8763) (xy -1.2573 0.8763) (xy -0.9525 0.8763) (xy -0.9525 1.4351)
				(xy 0.9525 1.4351) (xy 0.9525 0.8763)
			)
			(stroke
				(width 0)
				(type default)
			)
			(fill no)
			(layer "F.CrtYd")
		)
		(fp_poly
			(pts
				(xy 1.2573 0.8763) (xy 1.2573 -0.8763) (xy 0.9525 -0.8763) (xy 0.9525 -1.4351) (xy -0.9525 -1.4351)
				(xy -0.9525 -0.8763) (xy -1.2573 -0.8763) (xy -1.2573 0.8763) (xy -0.9525 0.8763) (xy -0.9525 1.4351)
				(xy 0.9525 1.4351) (xy 0.9525 0.8763)
			)
			(stroke
				(width 0)
				(type default)
			)
			(fill no)
			(layer "F.Fab")
		)
		(pad "1" smd rect
			(at -0.65024 0.8255)
			(size 0.3556 0.9652)
			(layers "F.Cu" "F.Mask" "F.Paste")
			(net "GND")
		)
		(pad "2" smd rect
			(at 0 0.8255)
			(size 0.3556 0.9652)
			(layers "F.Cu" "F.Mask" "F.Paste")
			(net "SW_P3V3_CPU_LV_G2")
		)
		(pad "3" smd rect
			(at 0.65024 0.8255)
			(size 0.3556 0.9652)
			(layers "F.Cu" "F.Mask" "F.Paste")
			(net "SW_P3V3_CPU_EN_LV_D")
		)
		(pad "4" smd rect
			(at 0.65024 -0.8255)
			(size 0.3556 0.9652)
			(layers "F.Cu" "F.Mask" "F.Paste")
			(net "GND")
		)
		(pad "5" smd rect
			(at 0 -0.8255)
			(size 0.3556 0.9652)
			(layers "F.Cu" "F.Mask" "F.Paste")
			(net "SW_P3V3_CPU_LV_G5")
		)
		(pad "6" smd rect
			(at -0.65024 -0.8255)
			(size 0.3556 0.9652)
			(layers "F.Cu" "F.Mask" "F.Paste")
			(net "SW_P3V3_CPU_LV_G5")
		)
	)
	(footprint ""
		(layer "F.Cu")
		(at 21.1328 -67.183)
		(property "Reference" "PR18"
			(at 0 0 0)
			(layer "F.SilkS")
			(hide yes)
			(effects
				(font
					(size 1.27 1.27)
				)
			)
		)
		(property "Value" "10R2F-L-GP"
			(at 1.7907 -1.1176 0)
			(unlocked yes)
			(layer "F.Fab")
			(hide yes)
			(effects
				(font
					(size 1.016 1.016)
					(thickness 0.1524)
				)
			)
		)
		(property "Device Type" "R402H14"
			(at 1.7907 -2.6416 0)
			(unlocked yes)
			(layer "F.Fab")
			(hide yes)
			(effects
				(font
					(size 1.016 1.016)
					(thickness 0.1524)
				)
			)
		)
		(duplicate_pad_numbers_are_jumpers no)
		(fp_rect
			(start -0.381 0.8382)
			(end 0.381 -0.8382)
			(stroke
				(width 0)
				(type default)
			)
			(fill no)
			(layer "F.CrtYd")
		)
		(fp_rect
			(start -0.381 0.8382)
			(end 0.381 -0.8382)
			(stroke
				(width 0)
				(type default)
			)
			(fill no)
			(layer "F.Fab")
		)
		(pad "1" smd custom
			(at 0 -0.4318)
			(size 0.127 0.127)
			(layers "F.Cu" "F.Mask" "F.Paste")
			(net "VR_PVNN_ISUMN_R2")
			(options
				(clearance outline)
				(anchor circle)
			)
			(primitives
				(gr_poly
					(pts
						(arc
							(start -0.2032 -0.2794)
							(mid -0.239121 -0.264521)
							(end -0.254 -0.2286)
						)
						(arc
							(start -0.254 0.2286)
							(mid -0.239121 0.264521)
							(end -0.2032 0.2794)
						)
						(arc
							(start 0.2032 0.2794)
							(mid 0.239121 0.264521)
							(end 0.254 0.2286)
						)
						(arc
							(start 0.254 -0.2286)
							(mid 0.239121 -0.264521)
							(end 0.2032 -0.2794)
						)
					)
					(width 0)
					(fill yes)
				)
			)
		)
		(pad "2" smd custom
			(at 0 0.4318)
			(size 0.127 0.127)
			(layers "F.Cu" "F.Mask" "F.Paste")
			(net "VR_PVNN_ISUMN")
			(options
				(clearance outline)
				(anchor circle)
			)
			(primitives
				(gr_poly
					(pts
						(arc
							(start -0.2032 -0.2794)
							(mid -0.239121 -0.264521)
							(end -0.254 -0.2286)
						)
						(arc
							(start -0.254 0.2286)
							(mid -0.239121 0.264521)
							(end -0.2032 0.2794)
						)
						(arc
							(start 0.2032 0.2794)
							(mid 0.239121 0.264521)
							(end 0.254 0.2286)
						)
						(arc
							(start 0.254 -0.2286)
							(mid 0.239121 -0.264521)
							(end 0.2032 -0.2794)
						)
					)
					(width 0)
					(fill yes)
				)
			)
		)
	)
	(footprint ""
		(layer "F.Cu")
		(at 43.8404 -51.6382 -90)
		(property "Reference" "C53"
			(at 0 0 270)
			(layer "F.SilkS")
			(hide yes)
			(effects
				(font
					(size 1.27 1.27)
				)
			)
		)
		(property "Value" "SC10U6D3V3MX-GP"
			(at -0.0254 -2.0193 270)
			(unlocked yes)
			(layer "F.Fab")
			(hide yes)
			(effects
				(font
					(size 1.016 1.016)
					(thickness 0.1524)
				)
			)
		)
		(property "Device Type" "C603H38"
			(at -0.0254 -3.5433 270)
			(unlocked yes)
			(layer "F.Fab")
			(hide yes)
			(effects
				(font
					(size 1.016 1.016)
					(thickness 0.1524)
				)
			)
		)
		(duplicate_pad_numbers_are_jumpers no)
		(fp_line
			(start -0.4064 0)
			(end 0.4064 0)
			(stroke
				(width 0.2286)
				(type default)
			)
			(layer "F.SilkS")
		)
		(fp_rect
			(start -0.635 1.1811)
			(end 0.635 -1.1811)
			(stroke
				(width 0)
				(type default)
			)
			(fill no)
			(layer "F.CrtYd")
		)
		(fp_rect
			(start -0.635 1.1811)
			(end 0.635 -1.1811)
			(stroke
				(width 0)
				(type default)
			)
			(fill no)
			(layer "F.Fab")
		)
		(pad "1" smd custom
			(at 0 -0.6604 270)
			(size 0.19685 0.19685)
			(layers "F.Cu" "F.Mask" "F.Paste")
			(net "P3V3_CLK_VDD25")
			(options
				(clearance outline)
				(anchor circle)
			)
			(primitives
				(gr_poly
					(pts
						(arc
							(start 0.508 -0.2921)
							(mid 0.478242 -0.363942)
							(end 0.4064 -0.3937)
						)
						(arc
							(start -0.4064 -0.3937)
							(mid -0.478242 -0.363942)
							(end -0.508 -0.2921)
						)
						(arc
							(start -0.508 0.2921)
							(mid -0.478242 0.363942)
							(end -0.4064 0.3937)
						)
						(arc
							(start 0.4064 0.3937)
							(mid 0.478242 0.363942)
							(end 0.508 0.2921)
						)
					)
					(width 0)
					(fill yes)
				)
			)
		)
		(pad "2" smd custom
			(at 0 0.6604 270)
			(size 0.19685 0.19685)
			(layers "F.Cu" "F.Mask" "F.Paste")
			(net "GND")
			(options
				(clearance outline)
				(anchor circle)
			)
			(primitives
				(gr_poly
					(pts
						(arc
							(start 0.508 -0.2921)
							(mid 0.478242 -0.363942)
							(end 0.4064 -0.3937)
						)
						(arc
							(start -0.4064 -0.3937)
							(mid -0.478242 -0.363942)
							(end -0.508 -0.2921)
						)
						(arc
							(start -0.508 0.2921)
							(mid -0.478242 0.363942)
							(end -0.4064 0.3937)
						)
						(arc
							(start 0.4064 0.3937)
							(mid 0.478242 0.363942)
							(end 0.508 0.2921)
						)
					)
					(width 0)
					(fill yes)
				)
			)
		)
	)
	(footprint ""
		(layer "F.Cu")
		(at 109.728 -70.612 90)
		(property "Reference" "R19"
			(at 0 0 90)
			(layer "F.SilkS")
			(hide yes)
			(effects
				(font
					(size 1.27 1.27)
				)
			)
		)
		(property "Value" "1KR2F-3-GP"
			(at 0.064008 -3.993896 90)
			(unlocked yes)
			(layer "F.Fab")
			(hide yes)
			(effects
				(font
					(size 1.016 1.016)
					(thickness 0.1524)
				)
			)
		)
		(property "Device Type" "R402H16"
			(at 0.064008 -5.517896 90)
			(unlocked yes)
			(layer "F.Fab")
			(hide yes)
			(effects
				(font
					(size 1.016 1.016)
					(thickness 0.1524)
				)
			)
		)
		(duplicate_pad_numbers_are_jumpers no)
		(fp_rect
			(start -0.381 0.8382)
			(end 0.381 -0.8382)
			(stroke
				(width 0)
				(type default)
			)
			(fill no)
			(layer "F.CrtYd")
		)
		(fp_rect
			(start -0.381 0.8382)
			(end 0.381 -0.8382)
			(stroke
				(width 0)
				(type default)
			)
			(fill no)
			(layer "F.Fab")
		)
		(pad "1" smd custom
			(at 0 -0.4318 90)
			(size 0.127 0.127)
			(layers "F.Cu" "F.Mask" "F.Paste")
			(net "P3V3_STBY")
			(options
				(clearance outline)
				(anchor circle)
			)
			(primitives
				(gr_poly
					(pts
						(arc
							(start -0.2032 -0.2794)
							(mid -0.239121 -0.264521)
							(end -0.254 -0.2286)
						)
						(arc
							(start -0.254 0.2286)
							(mid -0.239121 0.264521)
							(end -0.2032 0.2794)
						)
						(arc
							(start 0.2032 0.2794)
							(mid 0.239121 0.264521)
							(end 0.254 0.2286)
						)
						(arc
							(start 0.254 -0.2286)
							(mid 0.239121 -0.264521)
							(end 0.2032 -0.2794)
						)
					)
					(width 0)
					(fill yes)
				)
			)
		)
		(pad "2" smd custom
			(at 0 0.4318 90)
			(size 0.127 0.127)
			(layers "F.Cu" "F.Mask" "F.Paste")
			(net "CLK_GEN_OUT_R")
			(options
				(clearance outline)
				(anchor circle)
			)
			(primitives
				(gr_poly
					(pts
						(arc
							(start -0.2032 -0.2794)
							(mid -0.239121 -0.264521)
							(end -0.254 -0.2286)
						)
						(arc
							(start -0.254 0.2286)
							(mid -0.239121 0.264521)
							(end -0.2032 0.2794)
						)
						(arc
							(start 0.2032 0.2794)
							(mid 0.239121 0.264521)
							(end 0.254 0.2286)
						)
						(arc
							(start 0.254 -0.2286)
							(mid 0.239121 -0.264521)
							(end 0.2032 -0.2794)
						)
					)
					(width 0)
					(fill yes)
				)
			)
		)
	)
	(footprint ""
		(layer "F.Cu")
		(at 181.102 -37.338 -90)
		(property "Reference" "R143"
			(at 0 0 270)
			(layer "F.SilkS")
			(hide yes)
			(effects
				(font
					(size 1.27 1.27)
				)
			)
		)
		(property "Value" "56D2R2F-GP"
			(at 0.064008 -3.993896 270)
			(unlocked yes)
			(layer "F.Fab")
			(hide yes)
			(effects
				(font
					(size 1.016 1.016)
					(thickness 0.1524)
				)
			)
		)
		(property "Device Type" "R402H16"
			(at 0.064008 -5.517896 270)
			(unlocked yes)
			(layer "F.Fab")
			(hide yes)
			(effects
				(font
					(size 1.016 1.016)
					(thickness 0.1524)
				)
			)
		)
		(duplicate_pad_numbers_are_jumpers no)
		(fp_rect
			(start -0.381 0.8382)
			(end 0.381 -0.8382)
			(stroke
				(width 0)
				(type default)
			)
			(fill no)
			(layer "F.CrtYd")
		)
		(fp_rect
			(start -0.381 0.8382)
			(end 0.381 -0.8382)
			(stroke
				(width 0)
				(type default)
			)
			(fill no)
			(layer "F.Fab")
		)
		(pad "1" smd custom
			(at 0 -0.4318 270)
			(size 0.127 0.127)
			(layers "F.Cu" "F.Mask" "F.Paste")
			(net "SVID_CPU_CLK")
			(options
				(clearance outline)
				(anchor circle)
			)
			(primitives
				(gr_poly
					(pts
						(arc
							(start -0.2032 -0.2794)
							(mid -0.239121 -0.264521)
							(end -0.254 -0.2286)
						)
						(arc
							(start -0.254 0.2286)
							(mid -0.239121 0.264521)
							(end -0.2032 0.2794)
						)
						(arc
							(start 0.2032 0.2794)
							(mid 0.239121 0.264521)
							(end 0.254 0.2286)
						)
						(arc
							(start 0.254 -0.2286)
							(mid 0.239121 -0.264521)
							(end 0.2032 -0.2794)
						)
					)
					(width 0)
					(fill yes)
				)
			)
		)
		(pad "2" smd custom
			(at 0 0.4318 270)
			(size 0.127 0.127)
			(layers "F.Cu" "F.Mask" "F.Paste")
			(net "P1V0")
			(options
				(clearance outline)
				(anchor circle)
			)
			(primitives
				(gr_poly
					(pts
						(arc
							(start -0.2032 -0.2794)
							(mid -0.239121 -0.264521)
							(end -0.254 -0.2286)
						)
						(arc
							(start -0.254 0.2286)
							(mid -0.239121 0.264521)
							(end -0.2032 0.2794)
						)
						(arc
							(start 0.2032 0.2794)
							(mid 0.239121 0.264521)
							(end 0.254 0.2286)
						)
						(arc
							(start 0.254 -0.2286)
							(mid 0.239121 -0.264521)
							(end 0.2032 -0.2794)
						)
					)
					(width 0)
					(fill yes)
				)
			)
		)
	)
	(footprint ""
		(layer "F.Cu")
		(at 160.274 -48.768 -90)
		(property "Reference" "R205"
			(at 0 0 270)
			(layer "F.SilkS")
			(hide yes)
			(effects
				(font
					(size 1.27 1.27)
				)
			)
		)
		(property "Value" "0R2J-2-GP"
			(at 1.7907 -1.1176 270)
			(unlocked yes)
			(layer "F.Fab")
			(hide yes)
			(effects
				(font
					(size 1.016 1.016)
					(thickness 0.1524)
				)
			)
		)
		(property "Device Type" "R402H16"
			(at 1.7907 -2.6416 270)
			(unlocked yes)
			(layer "F.Fab")
			(hide yes)
			(effects
				(font
					(size 1.016 1.016)
					(thickness 0.1524)
				)
			)
		)
		(duplicate_pad_numbers_are_jumpers no)
		(fp_rect
			(start -0.381 0.8382)
			(end 0.381 -0.8382)
			(stroke
				(width 0)
				(type default)
			)
			(fill no)
			(layer "F.CrtYd")
		)
		(fp_rect
			(start -0.381 0.8382)
			(end 0.381 -0.8382)
			(stroke
				(width 0)
				(type default)
			)
			(fill no)
			(layer "F.Fab")
		)
		(pad "1" smd custom
			(at 0 -0.4318 270)
			(size 0.127 0.127)
			(layers "F.Cu" "F.Mask" "F.Paste")
			(net "XDP_SOC_CPU_TDO")
			(options
				(clearance outline)
				(anchor circle)
			)
			(primitives
				(gr_poly
					(pts
						(arc
							(start -0.2032 -0.2794)
							(mid -0.239121 -0.264521)
							(end -0.254 -0.2286)
						)
						(arc
							(start -0.254 0.2286)
							(mid -0.239121 0.264521)
							(end -0.2032 0.2794)
						)
						(arc
							(start 0.2032 0.2794)
							(mid 0.239121 0.264521)
							(end 0.254 0.2286)
						)
						(arc
							(start 0.254 -0.2286)
							(mid 0.239121 -0.264521)
							(end 0.2032 -0.2794)
						)
					)
					(width 0)
					(fill yes)
				)
			)
		)
		(pad "2" smd custom
			(at 0 0.4318 270)
			(size 0.127 0.127)
			(layers "F.Cu" "F.Mask" "F.Paste")
			(net "XDP_SOC_CPU_TDO_S")
			(options
				(clearance outline)
				(anchor circle)
			)
			(primitives
				(gr_poly
					(pts
						(arc
							(start -0.2032 -0.2794)
							(mid -0.239121 -0.264521)
							(end -0.254 -0.2286)
						)
						(arc
							(start -0.254 0.2286)
							(mid -0.239121 0.264521)
							(end -0.2032 0.2794)
						)
						(arc
							(start 0.2032 0.2794)
							(mid 0.239121 0.264521)
							(end 0.254 0.2286)
						)
						(arc
							(start 0.254 -0.2286)
							(mid 0.239121 -0.264521)
							(end 0.2032 -0.2794)
						)
					)
					(width 0)
					(fill yes)
				)
			)
		)
	)
	(footprint ""
		(layer "F.Cu")
		(at 46.609 -47.498)
		(property "Reference" "C17"
			(at 0 0 0)
			(layer "F.SilkS")
			(hide yes)
			(effects
				(font
					(size 1.27 1.27)
				)
			)
		)
		(property "Value" "SCD47U25V2KX-GP"
			(at 1.8923 -1.2065 0)
			(unlocked yes)
			(layer "F.Fab")
			(hide yes)
			(effects
				(font
					(size 1.016 1.016)
					(thickness 0.1524)
				)
			)
		)
		(property "Device Type" "C402H24"
			(at 1.8923 -2.7305 0)
			(unlocked yes)
			(layer "F.Fab")
			(hide yes)
			(effects
				(font
					(size 1.016 1.016)
					(thickness 0.1524)
				)
			)
		)
		(duplicate_pad_numbers_are_jumpers no)
		(fp_rect
			(start -0.381 0.7366)
			(end 0.381 -0.7366)
			(stroke
				(width 0)
				(type default)
			)
			(fill no)
			(layer "F.CrtYd")
		)
		(fp_rect
			(start -0.381 0.7366)
			(end 0.381 -0.7366)
			(stroke
				(width 0)
				(type default)
			)
			(fill no)
			(layer "F.Fab")
		)
		(pad "1" smd custom
			(at 0 -0.4572)
			(size 0.1143 0.1143)
			(layers "F.Cu" "F.Mask" "F.Paste")
			(net "SW_P3V3_CPU_EN_LV_D")
			(options
				(clearance outline)
				(anchor circle)
			)
			(primitives
				(gr_poly
					(pts
						(arc
							(start -0.254 -0.1778)
							(mid -0.239121 -0.213721)
							(end -0.2032 -0.2286)
						)
						(arc
							(start 0.2032 -0.2286)
							(mid 0.239121 -0.213721)
							(end 0.254 -0.1778)
						)
						(arc
							(start 0.254 0.1778)
							(mid 0.239121 0.213721)
							(end 0.2032 0.2286)
						)
						(arc
							(start -0.2032 0.2286)
							(mid -0.239121 0.213721)
							(end -0.254 0.1778)
						)
					)
					(width 0)
					(fill yes)
				)
			)
		)
		(pad "2" smd custom
			(at 0 0.4572)
			(size 0.1143 0.1143)
			(layers "F.Cu" "F.Mask" "F.Paste")
			(net "P3V3_CPU")
			(options
				(clearance outline)
				(anchor circle)
			)
			(primitives
				(gr_poly
					(pts
						(arc
							(start -0.254 -0.1778)
							(mid -0.239121 -0.213721)
							(end -0.2032 -0.2286)
						)
						(arc
							(start 0.2032 -0.2286)
							(mid 0.239121 -0.213721)
							(end 0.254 -0.1778)
						)
						(arc
							(start 0.254 0.1778)
							(mid 0.239121 0.213721)
							(end 0.2032 0.2286)
						)
						(arc
							(start -0.2032 0.2286)
							(mid -0.239121 0.213721)
							(end -0.254 0.1778)
						)
					)
					(width 0)
					(fill yes)
				)
			)
		)
	)
	(footprint ""
		(layer "F.Cu")
		(at 55.499 -54.356 180)
		(property "Reference" "PC104"
			(at 0 0 180)
			(layer "F.SilkS")
			(hide yes)
			(effects
				(font
					(size 1.27 1.27)
				)
			)
		)
		(property "Value" "SC5P50V2CN-2GP"
			(at 1.8923 -1.2065 180)
			(unlocked yes)
			(layer "F.Fab")
			(hide yes)
			(effects
				(font
					(size 1.016 1.016)
					(thickness 0.1524)
				)
			)
		)
		(property "Device Type" "C402H22"
			(at 1.8923 -2.7305 180)
			(unlocked yes)
			(layer "F.Fab")
			(hide yes)
			(effects
				(font
					(size 1.016 1.016)
					(thickness 0.1524)
				)
			)
		)
		(duplicate_pad_numbers_are_jumpers no)
		(fp_rect
			(start -0.381 0.7366)
			(end 0.381 -0.7366)
			(stroke
				(width 0)
				(type default)
			)
			(fill no)
			(layer "F.CrtYd")
		)
		(fp_rect
			(start -0.381 0.7366)
			(end 0.381 -0.7366)
			(stroke
				(width 0)
				(type default)
			)
			(fill no)
			(layer "F.Fab")
		)
		(pad "1" smd custom
			(at 0 -0.4572 180)
			(size 0.1143 0.1143)
			(layers "F.Cu" "F.Mask" "F.Paste")
			(net "VR_FB_R_P1V0_STBY")
			(options
				(clearance outline)
				(anchor circle)
			)
			(primitives
				(gr_poly
					(pts
						(arc
							(start -0.254 -0.1778)
							(mid -0.239121 -0.213721)
							(end -0.2032 -0.2286)
						)
						(arc
							(start 0.2032 -0.2286)
							(mid 0.239121 -0.213721)
							(end 0.254 -0.1778)
						)
						(arc
							(start 0.254 0.1778)
							(mid 0.239121 0.213721)
							(end 0.2032 0.2286)
						)
						(arc
							(start -0.2032 0.2286)
							(mid -0.239121 0.213721)
							(end -0.254 0.1778)
						)
					)
					(width 0)
					(fill yes)
				)
			)
		)
		(pad "2" smd custom
			(at 0 0.4572 180)
			(size 0.1143 0.1143)
			(layers "F.Cu" "F.Mask" "F.Paste")
			(net "VR_FB_P1V0_STBY")
			(options
				(clearance outline)
				(anchor circle)
			)
			(primitives
				(gr_poly
					(pts
						(arc
							(start -0.254 -0.1778)
							(mid -0.239121 -0.213721)
							(end -0.2032 -0.2286)
						)
						(arc
							(start 0.2032 -0.2286)
							(mid 0.239121 -0.213721)
							(end 0.254 -0.1778)
						)
						(arc
							(start 0.254 0.1778)
							(mid 0.239121 0.213721)
							(end 0.2032 0.2286)
						)
						(arc
							(start -0.2032 0.2286)
							(mid -0.239121 0.213721)
							(end -0.254 0.1778)
						)
					)
					(width 0)
					(fill yes)
				)
			)
		)
	)
	(footprint ""
		(layer "F.Cu")
		(at 43.688 -61.214 -90)
		(property "Reference" "PR51"
			(at 0 0 270)
			(layer "F.SilkS")
			(hide yes)
			(effects
				(font
					(size 1.27 1.27)
				)
			)
		)
		(property "Value" "10KR2F-2-GP"
			(at 1.7907 -1.1176 270)
			(unlocked yes)
			(layer "F.Fab")
			(hide yes)
			(effects
				(font
					(size 1.016 1.016)
					(thickness 0.1524)
				)
			)
		)
		(property "Device Type" "R402H16"
			(at 1.7907 -2.6416 270)
			(unlocked yes)
			(layer "F.Fab")
			(hide yes)
			(effects
				(font
					(size 1.016 1.016)
					(thickness 0.1524)
				)
			)
		)
		(duplicate_pad_numbers_are_jumpers no)
		(fp_rect
			(start -0.381 0.8382)
			(end 0.381 -0.8382)
			(stroke
				(width 0)
				(type default)
			)
			(fill no)
			(layer "F.CrtYd")
		)
		(fp_rect
			(start -0.381 0.8382)
			(end 0.381 -0.8382)
			(stroke
				(width 0)
				(type default)
			)
			(fill no)
			(layer "F.Fab")
		)
		(pad "1" smd custom
			(at 0 -0.4318 270)
			(size 0.127 0.127)
			(layers "F.Cu" "F.Mask" "F.Paste")
			(net "GND")
			(options
				(clearance outline)
				(anchor circle)
			)
			(primitives
				(gr_poly
					(pts
						(arc
							(start -0.2032 -0.2794)
							(mid -0.239121 -0.264521)
							(end -0.254 -0.2286)
						)
						(arc
							(start -0.254 0.2286)
							(mid -0.239121 0.264521)
							(end -0.2032 0.2794)
						)
						(arc
							(start 0.2032 0.2794)
							(mid 0.239121 0.264521)
							(end 0.254 0.2286)
						)
						(arc
							(start 0.254 -0.2286)
							(mid 0.239121 -0.264521)
							(end 0.2032 -0.2794)
						)
					)
					(width 0)
					(fill yes)
				)
			)
		)
		(pad "2" smd custom
			(at 0 0.4318 270)
			(size 0.127 0.127)
			(layers "F.Cu" "F.Mask" "F.Paste")
			(net "VR_PVCCP_LH_R")
			(options
				(clearance outline)
				(anchor circle)
			)
			(primitives
				(gr_poly
					(pts
						(arc
							(start -0.2032 -0.2794)
							(mid -0.239121 -0.264521)
							(end -0.254 -0.2286)
						)
						(arc
							(start -0.254 0.2286)
							(mid -0.239121 0.264521)
							(end -0.2032 0.2794)
						)
						(arc
							(start 0.2032 0.2794)
							(mid 0.239121 0.264521)
							(end 0.254 0.2286)
						)
						(arc
							(start 0.254 -0.2286)
							(mid 0.239121 -0.264521)
							(end 0.2032 -0.2794)
						)
					)
					(width 0)
					(fill yes)
				)
			)
		)
	)
	(footprint ""
		(layer "F.Cu")
		(at 44.323 -46.99 180)
		(property "Reference" "Q3"
			(at 0 0 180)
			(layer "F.SilkS")
			(hide yes)
			(effects
				(font
					(size 1.27 1.27)
				)
			)
		)
		(property "Value" "FDN359BN-GP-U"
			(at -3.175 0.254 180)
			(unlocked yes)
			(layer "F.Fab")
			(hide yes)
			(effects
				(font
					(size 1.016 1.016)
					(thickness 0.1524)
				)
			)
		)
		(property "Device Type" "SOT23DGS2D6H45"
			(at -3.175 -1.27 180)
			(unlocked yes)
			(layer "F.Fab")
			(hide yes)
			(effects
				(font
					(size 1.016 1.016)
					(thickness 0.1524)
				)
			)
		)
		(duplicate_pad_numbers_are_jumpers no)
		(fp_line
			(start 1.7145 0.2794)
			(end 1.7145 -0.2794)
			(stroke
				(width 0.1524)
				(type default)
			)
			(layer "F.SilkS")
		)
		(fp_line
			(start 1.7145 -0.2794)
			(end -1.7145 -0.2794)
			(stroke
				(width 0.1524)
				(type default)
			)
			(layer "F.SilkS")
		)
		(fp_line
			(start -1.7145 0.2794)
			(end 1.7145 0.2794)
			(stroke
				(width 0.1524)
				(type default)
			)
			(layer "F.SilkS")
		)
		(fp_line
			(start -1.7145 -0.2794)
			(end -1.7145 0.2794)
			(stroke
				(width 0.1524)
				(type default)
			)
			(layer "F.SilkS")
		)
		(fp_rect
			(start -1.7145 1.651)
			(end 1.7145 -1.651)
			(stroke
				(width 0)
				(type default)
			)
			(fill no)
			(layer "F.CrtYd")
		)
		(fp_rect
			(start -1.7145 1.651)
			(end 1.7145 -1.651)
			(stroke
				(width 0)
				(type default)
			)
			(fill no)
			(layer "F.Fab")
		)
		(pad "D" smd custom
			(at 0 -1.016 180)
			(size 0.1651 0.1651)
			(layers "F.Cu" "F.Mask" "F.Paste")
			(net "P3V3_STBY")
			(options
				(clearance outline)
				(anchor circle)
			)
			(primitives
				(gr_poly
					(pts
						(arc
							(start -0.127 0.508)
							(mid -0.270684 0.448484)
							(end -0.3302 0.3048)
						)
						(arc
							(start -0.3302 -0.3048)
							(mid -0.270684 -0.448484)
							(end -0.127 -0.508)
						)
						(arc
							(start 0.127 -0.508)
							(mid 0.270684 -0.448484)
							(end 0.3302 -0.3048)
						)
						(arc
							(start 0.3302 0.3048)
							(mid 0.270684 0.448484)
							(end 0.127 0.508)
						)
					)
					(width 0)
					(fill yes)
				)
			)
		)
		(pad "G" smd custom
			(at -0.94996 1.016 180)
			(size 0.1651 0.1651)
			(layers "F.Cu" "F.Mask" "F.Paste")
			(net "SW_P3V3_CPU_EN_LV_D")
			(options
				(clearance outline)
				(anchor circle)
			)
			(primitives
				(gr_poly
					(pts
						(arc
							(start -0.127 0.508)
							(mid -0.270684 0.448484)
							(end -0.3302 0.3048)
						)
						(arc
							(start -0.3302 -0.3048)
							(mid -0.270684 -0.448484)
							(end -0.127 -0.508)
						)
						(arc
							(start 0.127 -0.508)
							(mid 0.270684 -0.448484)
							(end 0.3302 -0.3048)
						)
						(arc
							(start 0.3302 0.3048)
							(mid 0.270684 0.448484)
							(end 0.127 0.508)
						)
					)
					(width 0)
					(fill yes)
				)
			)
		)
		(pad "S" smd custom
			(at 0.94996 1.016 180)
			(size 0.1651 0.1651)
			(layers "F.Cu" "F.Mask" "F.Paste")
			(net "P3V3_CPU")
			(options
				(clearance outline)
				(anchor circle)
			)
			(primitives
				(gr_poly
					(pts
						(arc
							(start -0.127 0.508)
							(mid -0.270684 0.448484)
							(end -0.3302 0.3048)
						)
						(arc
							(start -0.3302 -0.3048)
							(mid -0.270684 -0.448484)
							(end -0.127 -0.508)
						)
						(arc
							(start 0.127 -0.508)
							(mid 0.270684 -0.448484)
							(end 0.3302 -0.3048)
						)
						(arc
							(start 0.3302 0.3048)
							(mid 0.270684 0.448484)
							(end 0.127 0.508)
						)
					)
					(width 0)
					(fill yes)
				)
			)
		)
	)
	(footprint ""
		(layer "F.Cu")
		(at 50.3428 -50.800254)
		(property "Reference" "L14"
			(at 0 0 0)
			(layer "F.SilkS")
			(hide yes)
			(effects
				(font
					(size 1.27 1.27)
				)
			)
		)
		(property "Value" "BLM18PG330SN1D-GP"
			(at -0.0254 -2.0193 0)
			(unlocked yes)
			(layer "F.Fab")
			(hide yes)
			(effects
				(font
					(size 1.016 1.016)
					(thickness 0.1524)
				)
			)
		)
		(property "Device Type" "L1608-UH38"
			(at -0.0254 -3.5433 0)
			(unlocked yes)
			(layer "F.Fab")
			(hide yes)
			(effects
				(font
					(size 1.016 1.016)
					(thickness 0.1524)
				)
			)
		)
		(duplicate_pad_numbers_are_jumpers no)
		(fp_line
			(start -0.4064 0)
			(end 0.4064 0)
			(stroke
				(width 0.2032)
				(type default)
			)
			(layer "F.SilkS")
		)
		(fp_rect
			(start -0.635 1.1811)
			(end 0.635 -1.1811)
			(stroke
				(width 0)
				(type default)
			)
			(fill no)
			(layer "F.CrtYd")
		)
		(fp_rect
			(start -0.635 1.1811)
			(end 0.635 -1.1811)
			(stroke
				(width 0)
				(type default)
			)
			(fill no)
			(layer "F.Fab")
		)
		(pad "1" smd custom
			(at 0 -0.6604)
			(size 0.19685 0.19685)
			(layers "F.Cu" "F.Mask" "F.Paste")
			(net "P1V5_STBY")
			(options
				(clearance outline)
				(anchor circle)
			)
			(primitives
				(gr_poly
					(pts
						(arc
							(start 0.508 -0.2921)
							(mid 0.478242 -0.363942)
							(end 0.4064 -0.3937)
						)
						(arc
							(start -0.4064 -0.3937)
							(mid -0.478242 -0.363942)
							(end -0.508 -0.2921)
						)
						(arc
							(start -0.508 0.2921)
							(mid -0.478242 0.363942)
							(end -0.4064 0.3937)
						)
						(arc
							(start 0.4064 0.3937)
							(mid 0.478242 0.363942)
							(end 0.508 0.2921)
						)
					)
					(width 0)
					(fill yes)
				)
			)
		)
		(pad "2" smd custom
			(at 0 0.6604)
			(size 0.19685 0.19685)
			(layers "F.Cu" "F.Mask" "F.Paste")
			(net "P1V5_CLK_SCR_LVIO")
			(options
				(clearance outline)
				(anchor circle)
			)
			(primitives
				(gr_poly
					(pts
						(arc
							(start 0.508 -0.2921)
							(mid 0.478242 -0.363942)
							(end 0.4064 -0.3937)
						)
						(arc
							(start -0.4064 -0.3937)
							(mid -0.478242 -0.363942)
							(end -0.508 -0.2921)
						)
						(arc
							(start -0.508 0.2921)
							(mid -0.478242 0.363942)
							(end -0.4064 0.3937)
						)
						(arc
							(start 0.4064 0.3937)
							(mid 0.478242 0.363942)
							(end 0.508 0.2921)
						)
					)
					(width 0)
					(fill yes)
				)
			)
		)
	)
	(footprint ""
		(layer "F.Cu")
		(at 68.58 -43.18 90)
		(property "Reference" "R50"
			(at 0 0 90)
			(layer "F.SilkS")
			(hide yes)
			(effects
				(font
					(size 1.27 1.27)
				)
			)
		)
		(property "Value" "0R2J-2-GP"
			(at 0.064008 -3.993896 90)
			(unlocked yes)
			(layer "F.Fab")
			(hide yes)
			(effects
				(font
					(size 1.016 1.016)
					(thickness 0.1524)
				)
			)
		)
		(property "Device Type" "R402H16"
			(at 0.064008 -5.517896 90)
			(unlocked yes)
			(layer "F.Fab")
			(hide yes)
			(effects
				(font
					(size 1.016 1.016)
					(thickness 0.1524)
				)
			)
		)
		(duplicate_pad_numbers_are_jumpers no)
		(fp_rect
			(start -0.381 0.8382)
			(end 0.381 -0.8382)
			(stroke
				(width 0)
				(type default)
			)
			(fill no)
			(layer "F.CrtYd")
		)
		(fp_rect
			(start -0.381 0.8382)
			(end 0.381 -0.8382)
			(stroke
				(width 0)
				(type default)
			)
			(fill no)
			(layer "F.Fab")
		)
		(pad "1" smd custom
			(at 0 -0.4318 90)
			(size 0.127 0.127)
			(layers "F.Cu" "F.Mask" "F.Paste")
			(net "SMBUS_PECI_R_DATA")
			(options
				(clearance outline)
				(anchor circle)
			)
			(primitives
				(gr_poly
					(pts
						(arc
							(start -0.2032 -0.2794)
							(mid -0.239121 -0.264521)
							(end -0.254 -0.2286)
						)
						(arc
							(start -0.254 0.2286)
							(mid -0.239121 0.264521)
							(end -0.2032 0.2794)
						)
						(arc
							(start 0.2032 0.2794)
							(mid 0.239121 0.264521)
							(end 0.254 0.2286)
						)
						(arc
							(start 0.254 -0.2286)
							(mid 0.239121 -0.264521)
							(end 0.2032 -0.2794)
						)
					)
					(width 0)
					(fill yes)
				)
			)
		)
		(pad "2" smd custom
			(at 0 0.4318 90)
			(size 0.127 0.127)
			(layers "F.Cu" "F.Mask" "F.Paste")
			(net "SMBUS_PECI_DATA")
			(options
				(clearance outline)
				(anchor circle)
			)
			(primitives
				(gr_poly
					(pts
						(arc
							(start -0.2032 -0.2794)
							(mid -0.239121 -0.264521)
							(end -0.254 -0.2286)
						)
						(arc
							(start -0.254 0.2286)
							(mid -0.239121 0.264521)
							(end -0.2032 0.2794)
						)
						(arc
							(start 0.2032 0.2794)
							(mid 0.239121 0.264521)
							(end 0.254 0.2286)
						)
						(arc
							(start 0.254 -0.2286)
							(mid 0.239121 -0.264521)
							(end 0.2032 -0.2794)
						)
					)
					(width 0)
					(fill yes)
				)
			)
		)
	)
	(footprint ""
		(layer "F.Cu")
		(at 151.765 -59.309)
		(property "Reference" "C326"
			(at 0 0 0)
			(layer "F.SilkS")
			(hide yes)
			(effects
				(font
					(size 1.27 1.27)
				)
			)
		)
		(property "Value" "SCD1U16V2KX-3GP"
			(at 1.8923 -1.2065 0)
			(unlocked yes)
			(layer "F.Fab")
			(hide yes)
			(effects
				(font
					(size 1.016 1.016)
					(thickness 0.1524)
				)
			)
		)
		(property "Device Type" "C402H22"
			(at 1.8923 -2.7305 0)
			(unlocked yes)
			(layer "F.Fab")
			(hide yes)
			(effects
				(font
					(size 1.016 1.016)
					(thickness 0.1524)
				)
			)
		)
		(duplicate_pad_numbers_are_jumpers no)
		(fp_rect
			(start -0.381 0.7366)
			(end 0.381 -0.7366)
			(stroke
				(width 0)
				(type default)
			)
			(fill no)
			(layer "F.CrtYd")
		)
		(fp_rect
			(start -0.381 0.7366)
			(end 0.381 -0.7366)
			(stroke
				(width 0)
				(type default)
			)
			(fill no)
			(layer "F.Fab")
		)
		(pad "1" smd custom
			(at 0 -0.4572)
			(size 0.1143 0.1143)
			(layers "F.Cu" "F.Mask" "F.Paste")
			(net "PV_VDDR")
			(options
				(clearance outline)
				(anchor circle)
			)
			(primitives
				(gr_poly
					(pts
						(arc
							(start -0.254 -0.1778)
							(mid -0.239121 -0.213721)
							(end -0.2032 -0.2286)
						)
						(arc
							(start 0.2032 -0.2286)
							(mid 0.239121 -0.213721)
							(end 0.254 -0.1778)
						)
						(arc
							(start 0.254 0.1778)
							(mid 0.239121 0.213721)
							(end 0.2032 0.2286)
						)
						(arc
							(start -0.2032 0.2286)
							(mid -0.239121 0.213721)
							(end -0.254 0.1778)
						)
					)
					(width 0)
					(fill yes)
				)
			)
		)
		(pad "2" smd custom
			(at 0 0.4572)
			(size 0.1143 0.1143)
			(layers "F.Cu" "F.Mask" "F.Paste")
			(net "GND")
			(options
				(clearance outline)
				(anchor circle)
			)
			(primitives
				(gr_poly
					(pts
						(arc
							(start -0.254 -0.1778)
							(mid -0.239121 -0.213721)
							(end -0.2032 -0.2286)
						)
						(arc
							(start 0.2032 -0.2286)
							(mid 0.239121 -0.213721)
							(end 0.254 -0.1778)
						)
						(arc
							(start 0.254 0.1778)
							(mid 0.239121 0.213721)
							(end 0.2032 0.2286)
						)
						(arc
							(start -0.2032 0.2286)
							(mid -0.239121 0.213721)
							(end -0.254 0.1778)
						)
					)
					(width 0)
					(fill yes)
				)
			)
		)
	)
	(footprint ""
		(layer "F.Cu")
		(at 53.213 -23.495 90)
		(property "Reference" "R455"
			(at 0 0 90)
			(layer "F.SilkS")
			(hide yes)
			(effects
				(font
					(size 1.27 1.27)
				)
			)
		)
		(property "Value" "4K7R2F-GP"
			(at 1.7907 -1.1176 90)
			(unlocked yes)
			(layer "F.Fab")
			(hide yes)
			(effects
				(font
					(size 1.016 1.016)
					(thickness 0.1524)
				)
			)
		)
		(property "Device Type" "R402H16"
			(at 1.7907 -2.6416 90)
			(unlocked yes)
			(layer "F.Fab")
			(hide yes)
			(effects
				(font
					(size 1.016 1.016)
					(thickness 0.1524)
				)
			)
		)
		(duplicate_pad_numbers_are_jumpers no)
		(fp_rect
			(start -0.381 0.8382)
			(end 0.381 -0.8382)
			(stroke
				(width 0)
				(type default)
			)
			(fill no)
			(layer "F.CrtYd")
		)
		(fp_rect
			(start -0.381 0.8382)
			(end 0.381 -0.8382)
			(stroke
				(width 0)
				(type default)
			)
			(fill no)
			(layer "F.Fab")
		)
		(pad "1" smd custom
			(at 0 -0.4318 90)
			(size 0.127 0.127)
			(layers "F.Cu" "F.Mask" "F.Paste")
			(net "CLKBUFF_OE4#")
			(options
				(clearance outline)
				(anchor circle)
			)
			(primitives
				(gr_poly
					(pts
						(arc
							(start -0.2032 -0.2794)
							(mid -0.239121 -0.264521)
							(end -0.254 -0.2286)
						)
						(arc
							(start -0.254 0.2286)
							(mid -0.239121 0.264521)
							(end -0.2032 0.2794)
						)
						(arc
							(start 0.2032 0.2794)
							(mid 0.239121 0.264521)
							(end 0.254 0.2286)
						)
						(arc
							(start 0.254 -0.2286)
							(mid 0.239121 -0.264521)
							(end 0.2032 -0.2794)
						)
					)
					(width 0)
					(fill yes)
				)
			)
		)
		(pad "2" smd custom
			(at 0 0.4318 90)
			(size 0.127 0.127)
			(layers "F.Cu" "F.Mask" "F.Paste")
			(net "GND")
			(options
				(clearance outline)
				(anchor circle)
			)
			(primitives
				(gr_poly
					(pts
						(arc
							(start -0.2032 -0.2794)
							(mid -0.239121 -0.264521)
							(end -0.254 -0.2286)
						)
						(arc
							(start -0.254 0.2286)
							(mid -0.239121 0.264521)
							(end -0.2032 0.2794)
						)
						(arc
							(start 0.2032 0.2794)
							(mid 0.239121 0.264521)
							(end 0.254 0.2286)
						)
						(arc
							(start 0.254 -0.2286)
							(mid 0.239121 -0.264521)
							(end 0.2032 -0.2794)
						)
					)
					(width 0)
					(fill yes)
				)
			)
		)
	)
	(footprint ""
		(layer "F.Cu")
		(at 158.5214 -45.339 90)
		(property "Reference" "R214"
			(at 0 0 90)
			(layer "F.SilkS")
			(hide yes)
			(effects
				(font
					(size 1.27 1.27)
				)
			)
		)
		(property "Value" "10KR2F-2-GP"
			(at 1.7907 -1.1176 90)
			(unlocked yes)
			(layer "F.Fab")
			(hide yes)
			(effects
				(font
					(size 1.016 1.016)
					(thickness 0.1524)
				)
			)
		)
		(property "Device Type" "R402H16"
			(at 1.7907 -2.6416 90)
			(unlocked yes)
			(layer "F.Fab")
			(hide yes)
			(effects
				(font
					(size 1.016 1.016)
					(thickness 0.1524)
				)
			)
		)
		(duplicate_pad_numbers_are_jumpers no)
		(fp_rect
			(start -0.381 0.8382)
			(end 0.381 -0.8382)
			(stroke
				(width 0)
				(type default)
			)
			(fill no)
			(layer "F.CrtYd")
		)
		(fp_rect
			(start -0.381 0.8382)
			(end 0.381 -0.8382)
			(stroke
				(width 0)
				(type default)
			)
			(fill no)
			(layer "F.Fab")
		)
		(pad "1" smd custom
			(at 0 -0.4318 90)
			(size 0.127 0.127)
			(layers "F.Cu" "F.Mask" "F.Paste")
			(net "P3V3_CPU")
			(options
				(clearance outline)
				(anchor circle)
			)
			(primitives
				(gr_poly
					(pts
						(arc
							(start -0.2032 -0.2794)
							(mid -0.239121 -0.264521)
							(end -0.254 -0.2286)
						)
						(arc
							(start -0.254 0.2286)
							(mid -0.239121 0.264521)
							(end -0.2032 0.2794)
						)
						(arc
							(start 0.2032 0.2794)
							(mid 0.239121 0.264521)
							(end 0.254 0.2286)
						)
						(arc
							(start 0.254 -0.2286)
							(mid 0.239121 -0.264521)
							(end 0.2032 -0.2794)
						)
					)
					(width 0)
					(fill yes)
				)
			)
		)
		(pad "2" smd custom
			(at 0 0.4318 90)
			(size 0.127 0.127)
			(layers "F.Cu" "F.Mask" "F.Paste")
			(net "JTAG_CHAIN_EN")
			(options
				(clearance outline)
				(anchor circle)
			)
			(primitives
				(gr_poly
					(pts
						(arc
							(start -0.2032 -0.2794)
							(mid -0.239121 -0.264521)
							(end -0.254 -0.2286)
						)
						(arc
							(start -0.254 0.2286)
							(mid -0.239121 0.264521)
							(end -0.2032 0.2794)
						)
						(arc
							(start 0.2032 0.2794)
							(mid 0.239121 0.264521)
							(end 0.254 0.2286)
						)
						(arc
							(start 0.254 -0.2286)
							(mid 0.239121 -0.264521)
							(end 0.2032 -0.2794)
						)
					)
					(width 0)
					(fill yes)
				)
			)
		)
	)
	(footprint ""
		(layer "F.Cu")
		(at 184.912 -39.878 180)
		(property "Reference" "PR121"
			(at 0 0 180)
			(layer "F.SilkS")
			(hide yes)
			(effects
				(font
					(size 1.27 1.27)
				)
			)
		)
		(property "Value" "787R2F-GP"
			(at 1.7907 -1.1176 180)
			(unlocked yes)
			(layer "F.Fab")
			(hide yes)
			(effects
				(font
					(size 1.016 1.016)
					(thickness 0.1524)
				)
			)
		)
		(property "Device Type" "R402H16"
			(at 1.7907 -2.6416 180)
			(unlocked yes)
			(layer "F.Fab")
			(hide yes)
			(effects
				(font
					(size 1.016 1.016)
					(thickness 0.1524)
				)
			)
		)
		(duplicate_pad_numbers_are_jumpers no)
		(fp_rect
			(start -0.381 0.8382)
			(end 0.381 -0.8382)
			(stroke
				(width 0)
				(type default)
			)
			(fill no)
			(layer "F.CrtYd")
		)
		(fp_rect
			(start -0.381 0.8382)
			(end 0.381 -0.8382)
			(stroke
				(width 0)
				(type default)
			)
			(fill no)
			(layer "F.Fab")
		)
		(pad "1" smd custom
			(at 0 -0.4318 180)
			(size 0.127 0.127)
			(layers "F.Cu" "F.Mask" "F.Paste")
			(net "VR_PVDDR_A_SVID_ADDR")
			(options
				(clearance outline)
				(anchor circle)
			)
			(primitives
				(gr_poly
					(pts
						(arc
							(start -0.2032 -0.2794)
							(mid -0.239121 -0.264521)
							(end -0.254 -0.2286)
						)
						(arc
							(start -0.254 0.2286)
							(mid -0.239121 0.264521)
							(end -0.2032 0.2794)
						)
						(arc
							(start 0.2032 0.2794)
							(mid 0.239121 0.264521)
							(end 0.254 0.2286)
						)
						(arc
							(start 0.254 -0.2286)
							(mid 0.239121 -0.264521)
							(end 0.2032 -0.2794)
						)
					)
					(width 0)
					(fill yes)
				)
			)
		)
		(pad "2" smd custom
			(at 0 0.4318 180)
			(size 0.127 0.127)
			(layers "F.Cu" "F.Mask" "F.Paste")
			(net "GND")
			(options
				(clearance outline)
				(anchor circle)
			)
			(primitives
				(gr_poly
					(pts
						(arc
							(start -0.2032 -0.2794)
							(mid -0.239121 -0.264521)
							(end -0.254 -0.2286)
						)
						(arc
							(start -0.254 0.2286)
							(mid -0.239121 0.264521)
							(end -0.2032 0.2794)
						)
						(arc
							(start 0.2032 0.2794)
							(mid 0.239121 0.264521)
							(end 0.254 0.2286)
						)
						(arc
							(start 0.254 -0.2286)
							(mid 0.239121 -0.264521)
							(end 0.2032 -0.2794)
						)
					)
					(width 0)
					(fill yes)
				)
			)
		)
	)
	(footprint ""
		(layer "F.Cu")
		(at 62.738 -23.241 -90)
		(property "Reference" "R256"
			(at 0 0 270)
			(layer "F.SilkS")
			(hide yes)
			(effects
				(font
					(size 1.27 1.27)
				)
			)
		)
		(property "Value" "4K02R2F-GP"
			(at 0.064008 -3.993896 270)
			(unlocked yes)
			(layer "F.Fab")
			(hide yes)
			(effects
				(font
					(size 1.016 1.016)
					(thickness 0.1524)
				)
			)
		)
		(property "Device Type" "R402H16"
			(at 0.064008 -5.517896 270)
			(unlocked yes)
			(layer "F.Fab")
			(hide yes)
			(effects
				(font
					(size 1.016 1.016)
					(thickness 0.1524)
				)
			)
		)
		(duplicate_pad_numbers_are_jumpers no)
		(fp_rect
			(start -0.381 0.8382)
			(end 0.381 -0.8382)
			(stroke
				(width 0)
				(type default)
			)
			(fill no)
			(layer "F.CrtYd")
		)
		(fp_rect
			(start -0.381 0.8382)
			(end 0.381 -0.8382)
			(stroke
				(width 0)
				(type default)
			)
			(fill no)
			(layer "F.Fab")
		)
		(pad "1" smd custom
			(at 0 -0.4318 270)
			(size 0.127 0.127)
			(layers "F.Cu" "F.Mask" "F.Paste")
			(net "SW_P1V8_EN_S")
			(options
				(clearance outline)
				(anchor circle)
			)
			(primitives
				(gr_poly
					(pts
						(arc
							(start -0.2032 -0.2794)
							(mid -0.239121 -0.264521)
							(end -0.254 -0.2286)
						)
						(arc
							(start -0.254 0.2286)
							(mid -0.239121 0.264521)
							(end -0.2032 0.2794)
						)
						(arc
							(start 0.2032 0.2794)
							(mid 0.239121 0.264521)
							(end 0.254 0.2286)
						)
						(arc
							(start 0.254 -0.2286)
							(mid 0.239121 -0.264521)
							(end 0.2032 -0.2794)
						)
					)
					(width 0)
					(fill yes)
				)
			)
		)
		(pad "2" smd custom
			(at 0 0.4318 270)
			(size 0.127 0.127)
			(layers "F.Cu" "F.Mask" "F.Paste")
			(net "P3V3_STBY")
			(options
				(clearance outline)
				(anchor circle)
			)
			(primitives
				(gr_poly
					(pts
						(arc
							(start -0.2032 -0.2794)
							(mid -0.239121 -0.264521)
							(end -0.254 -0.2286)
						)
						(arc
							(start -0.254 0.2286)
							(mid -0.239121 0.264521)
							(end -0.2032 0.2794)
						)
						(arc
							(start 0.2032 0.2794)
							(mid 0.239121 0.264521)
							(end 0.254 0.2286)
						)
						(arc
							(start 0.254 -0.2286)
							(mid 0.239121 -0.264521)
							(end 0.2032 -0.2794)
						)
					)
					(width 0)
					(fill yes)
				)
			)
		)
	)
	(footprint ""
		(layer "F.Cu")
		(at 39.751 -15.494 -90)
		(property "Reference" "C39"
			(at 0 0 270)
			(layer "F.SilkS")
			(hide yes)
			(effects
				(font
					(size 1.27 1.27)
				)
			)
		)
		(property "Value" "SC10U25V5KX-GP"
			(at 0 -4.9022 270)
			(unlocked yes)
			(layer "F.Fab")
			(hide yes)
			(effects
				(font
					(size 1.016 1.016)
					(thickness 0.1524)
				)
			)
		)
		(property "Device Type" "C805H56"
			(at 0 -6.8072 270)
			(unlocked yes)
			(layer "F.Fab")
			(hide yes)
			(effects
				(font
					(size 1.016 1.016)
					(thickness 0.1524)
				)
			)
		)
		(duplicate_pad_numbers_are_jumpers no)
		(fp_line
			(start 0.6096 0)
			(end -0.6096 0)
			(stroke
				(width 0.3048)
				(type default)
			)
			(layer "F.SilkS")
		)
		(fp_poly
			(pts
				(xy -0.9017 1.4351) (xy 0.9017 1.4351) (xy 0.9017 -1.4351) (xy -0.9017 -1.4351)
			)
			(stroke
				(width 0)
				(type default)
			)
			(fill no)
			(layer "F.CrtYd")
		)
		(fp_poly
			(pts
				(xy 0.9017 1.4351) (xy 0.9017 -1.4351) (xy -0.9017 -1.4351) (xy -0.9017 1.4351)
			)
			(stroke
				(width 0)
				(type default)
			)
			(fill no)
			(layer "F.Fab")
		)
		(pad "1" smd rect
			(at 0 -0.8382 270)
			(size 1.5494 0.9398)
			(layers "F.Cu" "F.Mask" "F.Paste")
			(net "P3V3_VDD_CLKBUFF")
		)
		(pad "2" smd rect
			(at 0 0.8382 270)
			(size 1.5494 0.9398)
			(layers "F.Cu" "F.Mask" "F.Paste")
			(net "GND")
		)
	)
	(footprint ""
		(layer "F.Cu")
		(at 62.738 -22.479 -90)
		(property "Reference" "R257"
			(at 0 0 270)
			(layer "F.SilkS")
			(hide yes)
			(effects
				(font
					(size 1.27 1.27)
				)
			)
		)
		(property "Value" "0R2J-2-GP"
			(at 0.064008 -3.993896 270)
			(unlocked yes)
			(layer "F.Fab")
			(hide yes)
			(effects
				(font
					(size 1.016 1.016)
					(thickness 0.1524)
				)
			)
		)
		(property "Device Type" "R402H16"
			(at 0.064008 -5.517896 270)
			(unlocked yes)
			(layer "F.Fab")
			(hide yes)
			(effects
				(font
					(size 1.016 1.016)
					(thickness 0.1524)
				)
			)
		)
		(duplicate_pad_numbers_are_jumpers no)
		(fp_rect
			(start -0.381 0.8382)
			(end 0.381 -0.8382)
			(stroke
				(width 0)
				(type default)
			)
			(fill no)
			(layer "F.CrtYd")
		)
		(fp_rect
			(start -0.381 0.8382)
			(end 0.381 -0.8382)
			(stroke
				(width 0)
				(type default)
			)
			(fill no)
			(layer "F.Fab")
		)
		(pad "1" smd custom
			(at 0 -0.4318 270)
			(size 0.127 0.127)
			(layers "F.Cu" "F.Mask" "F.Paste")
			(net "SW_P1V8_EN_S")
			(options
				(clearance outline)
				(anchor circle)
			)
			(primitives
				(gr_poly
					(pts
						(arc
							(start -0.2032 -0.2794)
							(mid -0.239121 -0.264521)
							(end -0.254 -0.2286)
						)
						(arc
							(start -0.254 0.2286)
							(mid -0.239121 0.264521)
							(end -0.2032 0.2794)
						)
						(arc
							(start 0.2032 0.2794)
							(mid 0.239121 0.264521)
							(end 0.254 0.2286)
						)
						(arc
							(start 0.254 -0.2286)
							(mid 0.239121 -0.264521)
							(end 0.2032 -0.2794)
						)
					)
					(width 0)
					(fill yes)
				)
			)
		)
		(pad "2" smd custom
			(at 0 0.4318 270)
			(size 0.127 0.127)
			(layers "F.Cu" "F.Mask" "F.Paste")
			(net "PWRGD_P1V0_PG")
			(options
				(clearance outline)
				(anchor circle)
			)
			(primitives
				(gr_poly
					(pts
						(arc
							(start -0.2032 -0.2794)
							(mid -0.239121 -0.264521)
							(end -0.254 -0.2286)
						)
						(arc
							(start -0.254 0.2286)
							(mid -0.239121 0.264521)
							(end -0.2032 0.2794)
						)
						(arc
							(start 0.2032 0.2794)
							(mid 0.239121 0.264521)
							(end 0.254 0.2286)
						)
						(arc
							(start 0.254 -0.2286)
							(mid 0.239121 -0.264521)
							(end 0.2032 -0.2794)
						)
					)
					(width 0)
					(fill yes)
				)
			)
		)
	)
	(footprint ""
		(layer "F.Cu")
		(at 138.176 -20.574)
		(property "Reference" "TP12"
			(at 0 0 0)
			(layer "F.SilkS")
			(hide yes)
			(effects
				(font
					(size 1.27 1.27)
				)
			)
		)
		(property "Value" "TPAD28-1-GP-U"
			(at 0.0508 -1.9304 0)
			(unlocked yes)
			(layer "F.Fab")
			(hide yes)
			(effects
				(font
					(size 1.016 1.016)
					(thickness 0.1524)
				)
			)
		)
		(property "Device Type" "TPAD28-1-U"
			(at 0.0508 -3.4544 0)
			(unlocked yes)
			(layer "F.Fab")
			(hide yes)
			(effects
				(font
					(size 1.016 1.016)
					(thickness 0.1524)
				)
			)
		)
		(duplicate_pad_numbers_are_jumpers no)
		(fp_poly
			(pts
				(arc
					(start 0.3556 0)
					(mid -0.3556 0)
					(end 0.3556 0)
				)
			)
			(stroke
				(width 0)
				(type default)
			)
			(fill no)
			(layer "F.CrtYd")
		)
		(fp_poly
			(pts
				(arc
					(start 0.9525 0)
					(mid -0.9525 0)
					(end 0.9525 0)
				)
			)
			(stroke
				(width 0)
				(type default)
			)
			(fill no)
			(layer "F.Fab")
		)
		(pad "1" smd circle
			(at 0 0)
			(size 0.7112 0.7112)
			(layers "F.Cu" "F.Mask" "F.Paste")
			(net "TP_FPGA_P84")
		)
	)
	(footprint ""
		(layer "F.Cu")
		(at 64.897 -24.13 180)
		(property "Reference" "R250"
			(at 0 0 180)
			(layer "F.SilkS")
			(hide yes)
			(effects
				(font
					(size 1.27 1.27)
				)
			)
		)
		(property "Value" "10KR2F-2-GP"
			(at 0.064008 -3.993896 180)
			(unlocked yes)
			(layer "F.Fab")
			(hide yes)
			(effects
				(font
					(size 1.016 1.016)
					(thickness 0.1524)
				)
			)
		)
		(property "Device Type" "R402H16"
			(at 0.064008 -5.517896 180)
			(unlocked yes)
			(layer "F.Fab")
			(hide yes)
			(effects
				(font
					(size 1.016 1.016)
					(thickness 0.1524)
				)
			)
		)
		(duplicate_pad_numbers_are_jumpers no)
		(fp_rect
			(start -0.381 0.8382)
			(end 0.381 -0.8382)
			(stroke
				(width 0)
				(type default)
			)
			(fill no)
			(layer "F.CrtYd")
		)
		(fp_rect
			(start -0.381 0.8382)
			(end 0.381 -0.8382)
			(stroke
				(width 0)
				(type default)
			)
			(fill no)
			(layer "F.Fab")
		)
		(pad "1" smd custom
			(at 0 -0.4318 180)
			(size 0.127 0.127)
			(layers "F.Cu" "F.Mask" "F.Paste")
			(net "P12V")
			(options
				(clearance outline)
				(anchor circle)
			)
			(primitives
				(gr_poly
					(pts
						(arc
							(start -0.2032 -0.2794)
							(mid -0.239121 -0.264521)
							(end -0.254 -0.2286)
						)
						(arc
							(start -0.254 0.2286)
							(mid -0.239121 0.264521)
							(end -0.2032 0.2794)
						)
						(arc
							(start 0.2032 0.2794)
							(mid 0.239121 0.264521)
							(end 0.254 0.2286)
						)
						(arc
							(start 0.254 -0.2286)
							(mid 0.239121 -0.264521)
							(end 0.2032 -0.2794)
						)
					)
					(width 0)
					(fill yes)
				)
			)
		)
		(pad "2" smd custom
			(at 0 0.4318 180)
			(size 0.127 0.127)
			(layers "F.Cu" "F.Mask" "F.Paste")
			(net "SW_P1V8_EN_LV")
			(options
				(clearance outline)
				(anchor circle)
			)
			(primitives
				(gr_poly
					(pts
						(arc
							(start -0.2032 -0.2794)
							(mid -0.239121 -0.264521)
							(end -0.254 -0.2286)
						)
						(arc
							(start -0.254 0.2286)
							(mid -0.239121 0.264521)
							(end -0.2032 0.2794)
						)
						(arc
							(start 0.2032 0.2794)
							(mid 0.239121 0.264521)
							(end 0.254 0.2286)
						)
						(arc
							(start 0.254 -0.2286)
							(mid 0.239121 -0.264521)
							(end 0.2032 -0.2794)
						)
					)
					(width 0)
					(fill yes)
				)
			)
		)
	)
	(footprint ""
		(layer "F.Cu")
		(at 169.7228 -46.736 90)
		(property "Reference" "R401"
			(at 0 0 90)
			(layer "F.SilkS")
			(hide yes)
			(effects
				(font
					(size 1.27 1.27)
				)
			)
		)
		(property "Value" "10KR2F-2-GP"
			(at 1.7907 -1.1176 90)
			(unlocked yes)
			(layer "F.Fab")
			(hide yes)
			(effects
				(font
					(size 1.016 1.016)
					(thickness 0.1524)
				)
			)
		)
		(property "Device Type" "R402H16"
			(at 1.7907 -2.6416 90)
			(unlocked yes)
			(layer "F.Fab")
			(hide yes)
			(effects
				(font
					(size 1.016 1.016)
					(thickness 0.1524)
				)
			)
		)
		(duplicate_pad_numbers_are_jumpers no)
		(fp_rect
			(start -0.381 0.8382)
			(end 0.381 -0.8382)
			(stroke
				(width 0)
				(type default)
			)
			(fill no)
			(layer "F.CrtYd")
		)
		(fp_rect
			(start -0.381 0.8382)
			(end 0.381 -0.8382)
			(stroke
				(width 0)
				(type default)
			)
			(fill no)
			(layer "F.Fab")
		)
		(pad "1" smd custom
			(at 0 -0.4318 90)
			(size 0.127 0.127)
			(layers "F.Cu" "F.Mask" "F.Paste")
			(net "JTAG_CHAIN_EN")
			(options
				(clearance outline)
				(anchor circle)
			)
			(primitives
				(gr_poly
					(pts
						(arc
							(start -0.2032 -0.2794)
							(mid -0.239121 -0.264521)
							(end -0.254 -0.2286)
						)
						(arc
							(start -0.254 0.2286)
							(mid -0.239121 0.264521)
							(end -0.2032 0.2794)
						)
						(arc
							(start 0.2032 0.2794)
							(mid 0.239121 0.264521)
							(end 0.254 0.2286)
						)
						(arc
							(start 0.254 -0.2286)
							(mid 0.239121 -0.264521)
							(end 0.2032 -0.2794)
						)
					)
					(width 0)
					(fill yes)
				)
			)
		)
		(pad "2" smd custom
			(at 0 0.4318 90)
			(size 0.127 0.127)
			(layers "F.Cu" "F.Mask" "F.Paste")
			(net "GND")
			(options
				(clearance outline)
				(anchor circle)
			)
			(primitives
				(gr_poly
					(pts
						(arc
							(start -0.2032 -0.2794)
							(mid -0.239121 -0.264521)
							(end -0.254 -0.2286)
						)
						(arc
							(start -0.254 0.2286)
							(mid -0.239121 0.264521)
							(end -0.2032 0.2794)
						)
						(arc
							(start 0.2032 0.2794)
							(mid 0.239121 0.264521)
							(end 0.254 0.2286)
						)
						(arc
							(start 0.254 -0.2286)
							(mid 0.239121 -0.264521)
							(end 0.2032 -0.2794)
						)
					)
					(width 0)
					(fill yes)
				)
			)
		)
	)
	(footprint ""
		(layer "F.Cu")
		(at 141.0462 -54.8132 180)
		(property "Reference" "R123"
			(at 0 0 180)
			(layer "F.SilkS")
			(hide yes)
			(effects
				(font
					(size 1.27 1.27)
				)
			)
		)
		(property "Value" "10KR2F-2-GP"
			(at 1.7907 -1.1176 180)
			(unlocked yes)
			(layer "F.Fab")
			(hide yes)
			(effects
				(font
					(size 1.016 1.016)
					(thickness 0.1524)
				)
			)
		)
		(property "Device Type" "R402H16"
			(at 1.7907 -2.6416 180)
			(unlocked yes)
			(layer "F.Fab")
			(hide yes)
			(effects
				(font
					(size 1.016 1.016)
					(thickness 0.1524)
				)
			)
		)
		(duplicate_pad_numbers_are_jumpers no)
		(fp_rect
			(start -0.381 0.8382)
			(end 0.381 -0.8382)
			(stroke
				(width 0)
				(type default)
			)
			(fill no)
			(layer "F.CrtYd")
		)
		(fp_rect
			(start -0.381 0.8382)
			(end 0.381 -0.8382)
			(stroke
				(width 0)
				(type default)
			)
			(fill no)
			(layer "F.Fab")
		)
		(pad "1" smd custom
			(at 0 -0.4318 180)
			(size 0.127 0.127)
			(layers "F.Cu" "F.Mask" "F.Paste")
			(net "P3V3_STBY")
			(options
				(clearance outline)
				(anchor circle)
			)
			(primitives
				(gr_poly
					(pts
						(arc
							(start -0.2032 -0.2794)
							(mid -0.239121 -0.264521)
							(end -0.254 -0.2286)
						)
						(arc
							(start -0.254 0.2286)
							(mid -0.239121 0.264521)
							(end -0.2032 0.2794)
						)
						(arc
							(start 0.2032 0.2794)
							(mid 0.239121 0.264521)
							(end 0.254 0.2286)
						)
						(arc
							(start 0.254 -0.2286)
							(mid 0.239121 -0.264521)
							(end 0.2032 -0.2794)
						)
					)
					(width 0)
					(fill yes)
				)
			)
		)
		(pad "2" smd custom
			(at 0 0.4318 180)
			(size 0.127 0.127)
			(layers "F.Cu" "F.Mask" "F.Paste")
			(net "SPI_SW_INT#")
			(options
				(clearance outline)
				(anchor circle)
			)
			(primitives
				(gr_poly
					(pts
						(arc
							(start -0.2032 -0.2794)
							(mid -0.239121 -0.264521)
							(end -0.254 -0.2286)
						)
						(arc
							(start -0.254 0.2286)
							(mid -0.239121 0.264521)
							(end -0.2032 0.2794)
						)
						(arc
							(start 0.2032 0.2794)
							(mid 0.239121 0.264521)
							(end 0.254 0.2286)
						)
						(arc
							(start 0.254 -0.2286)
							(mid 0.239121 -0.264521)
							(end 0.2032 -0.2794)
						)
					)
					(width 0)
					(fill yes)
				)
			)
		)
	)
	(footprint ""
		(layer "F.Cu")
		(at 201.29881 -36.46424 180)
		(property "Reference" "PU6"
			(at 0 0 180)
			(layer "F.SilkS")
			(hide yes)
			(effects
				(font
					(size 1.27 1.27)
				)
			)
		)
		(property "Value" "IRFH4253DTRPBF-GP-U"
			(at -3.9116 -4.5085 180)
			(unlocked yes)
			(layer "F.Fab")
			(hide yes)
			(effects
				(font
					(size 1.016 1.016)
					(thickness 0.1524)
				)
			)
		)
		(property "Device Type" "DFN8A5060-G2PH40"
			(at -3.9116 -6.0325 180)
			(unlocked yes)
			(layer "F.Fab")
			(hide yes)
			(effects
				(font
					(size 1.016 1.016)
					(thickness 0.1524)
				)
			)
		)
		(duplicate_pad_numbers_are_jumpers no)
		(fp_rect
			(start -2.7559 3.3782)
			(end 2.7559 -3.3782)
			(stroke
				(width 0)
				(type default)
			)
			(fill no)
			(layer "F.CrtYd")
		)
		(fp_rect
			(start -2.7559 3.3782)
			(end 2.7559 -3.3782)
			(stroke
				(width 0)
				(type default)
			)
			(fill no)
			(layer "F.Fab")
		)
		(pad "1" smd rect
			(at 1.905 -2.796794 180)
			(size 0.6604 0.9144)
			(layers "F.Cu" "F.Mask" "F.Paste")
			(net "VR_PVDDR_A_GH1_R")
		)
		(pad "2" smd rect
			(at 0.635 -2.796794 180)
			(size 0.6604 0.9144)
			(layers "F.Cu" "F.Mask" "F.Paste")
			(net "VR_PVDDR_A_PHASE1")
		)
		(pad "3" smd rect
			(at -0.635 -2.796794 180)
			(size 0.6604 0.9144)
			(layers "F.Cu" "F.Mask" "F.Paste")
			(net "PVDDR_VIN")
		)
		(pad "4" smd rect
			(at -1.905 -2.796794 180)
			(size 0.6604 0.9144)
			(layers "F.Cu" "F.Mask" "F.Paste")
			(net "PVDDR_VIN")
		)
		(pad "5" smd rect
			(at -1.905 2.745994 180)
			(size 0.6604 1.016)
			(layers "F.Cu" "F.Mask" "F.Paste")
			(net "VR_PVDDR_A_VSW")
		)
		(pad "6" smd rect
			(at -0.635 2.745994 180)
			(size 0.6604 1.016)
			(layers "F.Cu" "F.Mask" "F.Paste")
			(net "VR_PVDDR_A_VSW")
		)
		(pad "7" smd rect
			(at 0.635 2.745994 180)
			(size 0.6604 1.016)
			(layers "F.Cu" "F.Mask" "F.Paste")
			(net "VR_PVDDR_A_VSW")
		)
		(pad "8" smd rect
			(at 1.905 2.174494 180)
			(size 0.6604 2.159)
			(layers "F.Cu" "F.Mask" "F.Paste")
			(net "VR_PVDDR_A_GL1_BG")
		)
		(pad "9" smd custom
			(at 0 0.635 180)
			(size 0.66675 0.66675)
			(layers "F.Cu" "F.Mask" "F.Paste")
			(net "GND")
			(options
				(clearance outline)
				(anchor circle)
			)
			(primitives
				(gr_poly
					(pts
						(xy -2.3241 1.3335) (xy -2.3241 -1.3335) (xy 2.3241 -1.3335) (xy 2.3241 0.1905) (xy 1.1049 0.1905)
						(xy 1.1049 1.3335)
					)
					(width 0)
					(fill yes)
				)
			)
		)
		(pad "10" smd rect
			(at 0 -1.59512 180)
			(size 4.2672 1.0414)
			(layers "F.Cu" "F.Mask" "F.Paste")
			(net "PVDDR_VIN")
		)
	)
	(footprint ""
		(layer "F.Cu")
		(at 114.427 -67.691 180)
		(property "Reference" "U2"
			(at 0 0 180)
			(layer "F.SilkS")
			(hide yes)
			(effects
				(font
					(size 1.27 1.27)
				)
			)
		)
		(property "Value" "SN74LVC1G14DCKR-GP"
			(at -2.3368 -8.6868 180)
			(unlocked yes)
			(layer "F.Fab")
			(hide yes)
			(effects
				(font
					(size 1.016 1.016)
					(thickness 0.1524)
				)
			)
		)
		(property "Device Type" "SC70-5H44"
			(at -2.3114 -10.414 180)
			(unlocked yes)
			(layer "F.Fab")
			(hide yes)
			(effects
				(font
					(size 1.016 1.016)
					(thickness 0.1524)
				)
			)
		)
		(duplicate_pad_numbers_are_jumpers no)
		(fp_line
			(start 1.0033 0.3302)
			(end -1.0033 0.3302)
			(stroke
				(width 0.1524)
				(type default)
			)
			(layer "F.SilkS")
		)
		(fp_line
			(start 1.0033 -0.3302)
			(end 1.0033 0.3302)
			(stroke
				(width 0.1524)
				(type default)
			)
			(layer "F.SilkS")
		)
		(fp_line
			(start -1.0033 0.3302)
			(end -1.0033 -0.3302)
			(stroke
				(width 0.1524)
				(type default)
			)
			(layer "F.SilkS")
		)
		(fp_line
			(start -1.0033 -0.3302)
			(end 1.0033 -0.3302)
			(stroke
				(width 0.1524)
				(type default)
			)
			(layer "F.SilkS")
		)
		(fp_poly
			(pts
				(xy -1.0033 1.4859) (xy -1.0033 0.8001) (xy -1.1811 0.8001) (xy -1.1811 -0.8001) (xy -1.0033 -0.8001)
				(xy -1.0033 -1.4859) (xy 1.0033 -1.4859) (xy 1.0033 -0.8001) (xy 1.1811 -0.8001) (xy 1.1811 0.8001)
				(xy 1.0033 0.8001) (xy 1.0033 1.4859) (xy 0.2921 1.4859) (xy 0.2921 0.8001) (xy -0.2921 0.8001)
				(xy -0.2921 1.4859)
			)
			(stroke
				(width 0)
				(type default)
			)
			(fill no)
			(layer "F.CrtYd")
		)
		(fp_poly
			(pts
				(xy -1.0033 1.4859) (xy -1.0033 0.8001) (xy -1.1811 0.8001) (xy -1.1811 -0.8001) (xy -1.0033 -0.8001)
				(xy -1.0033 -1.4859) (xy 1.0033 -1.4859) (xy 1.0033 -0.8001) (xy 1.1811 -0.8001) (xy 1.1811 0.8001)
				(xy 1.0033 0.8001) (xy 1.0033 1.4859) (xy 0.2921 1.4859) (xy 0.2921 0.8001) (xy -0.2921 0.8001)
				(xy -0.2921 1.4859)
			)
			(stroke
				(width 0)
				(type default)
			)
			(fill no)
			(layer "F.Fab")
		)
		(pad "1" smd rect
			(at 0.65024 -0.93472 180)
			(size 0.3556 0.762)
			(layers "F.Cu" "F.Mask" "F.Paste")
			(net "Net_444")
		)
		(pad "2" smd rect
			(at 0 -0.93472 180)
			(size 0.3556 0.762)
			(layers "F.Cu" "F.Mask" "F.Paste")
			(net "CLK_GEN_INA_PG")
		)
		(pad "3" smd rect
			(at -0.65024 -0.93472 180)
			(size 0.3556 0.762)
			(layers "F.Cu" "F.Mask" "F.Paste")
			(net "GND")
		)
		(pad "4" smd rect
			(at -0.65024 0.93472 180)
			(size 0.3556 0.762)
			(layers "F.Cu" "F.Mask" "F.Paste")
			(net "CLK_GEN_OUT")
		)
		(pad "5" smd rect
			(at 0.65024 0.93472 180)
			(size 0.3556 0.762)
			(layers "F.Cu" "F.Mask" "F.Paste")
			(net "P3V3_STBY")
		)
	)
	(footprint ""
		(layer "F.Cu")
		(at 200.914 -28.956 -90)
		(property "Reference" "PC175"
			(at 0 0 270)
			(layer "F.SilkS")
			(hide yes)
			(effects
				(font
					(size 1.27 1.27)
				)
			)
		)
		(property "Value" "SC10U25V5KX-GP"
			(at 0 -4.9022 270)
			(unlocked yes)
			(layer "F.Fab")
			(hide yes)
			(effects
				(font
					(size 1.016 1.016)
					(thickness 0.1524)
				)
			)
		)
		(property "Device Type" "C805H56"
			(at 0 -6.8072 270)
			(unlocked yes)
			(layer "F.Fab")
			(hide yes)
			(effects
				(font
					(size 1.016 1.016)
					(thickness 0.1524)
				)
			)
		)
		(duplicate_pad_numbers_are_jumpers no)
		(fp_line
			(start 0.6096 0)
			(end -0.6096 0)
			(stroke
				(width 0.3048)
				(type default)
			)
			(layer "F.SilkS")
		)
		(fp_poly
			(pts
				(xy -0.9017 1.4351) (xy 0.9017 1.4351) (xy 0.9017 -1.4351) (xy -0.9017 -1.4351)
			)
			(stroke
				(width 0)
				(type default)
			)
			(fill no)
			(layer "F.CrtYd")
		)
		(fp_poly
			(pts
				(xy 0.9017 1.4351) (xy 0.9017 -1.4351) (xy -0.9017 -1.4351) (xy -0.9017 1.4351)
			)
			(stroke
				(width 0)
				(type default)
			)
			(fill no)
			(layer "F.Fab")
		)
		(pad "1" smd rect
			(at 0 -0.8382 270)
			(size 1.5494 0.9398)
			(layers "F.Cu" "F.Mask" "F.Paste")
			(net "PVDDR_VIN")
		)
		(pad "2" smd rect
			(at 0 0.8382 270)
			(size 1.5494 0.9398)
			(layers "F.Cu" "F.Mask" "F.Paste")
			(net "GND")
		)
	)
	(footprint ""
		(layer "F.Cu")
		(at 63.6524 -63.754 180)
		(property "Reference" "PC135"
			(at 0 0 180)
			(layer "F.SilkS")
			(hide yes)
			(effects
				(font
					(size 1.27 1.27)
				)
			)
		)
		(property "Value" "SC47U6D3V5MX-1-GP"
			(at -0.0762 -6.1214 180)
			(unlocked yes)
			(layer "F.Fab")
			(hide yes)
			(effects
				(font
					(size 1.016 1.016)
					(thickness 0.1524)
				)
			)
		)
		(property "Device Type" "C805H54"
			(at -0.0762 -8.1534 180)
			(unlocked yes)
			(layer "F.Fab")
			(hide yes)
			(effects
				(font
					(size 1.016 1.016)
					(thickness 0.1524)
				)
			)
		)
		(duplicate_pad_numbers_are_jumpers no)
		(fp_line
			(start 0.6096 0)
			(end -0.6096 0)
			(stroke
				(width 0.3048)
				(type default)
			)
			(layer "F.SilkS")
		)
		(fp_poly
			(pts
				(xy -0.9017 1.4351) (xy 0.9017 1.4351) (xy 0.9017 -1.4351) (xy -0.9017 -1.4351)
			)
			(stroke
				(width 0)
				(type default)
			)
			(fill no)
			(layer "F.CrtYd")
		)
		(fp_poly
			(pts
				(xy 0.9017 1.4351) (xy 0.9017 -1.4351) (xy -0.9017 -1.4351) (xy -0.9017 1.4351)
			)
			(stroke
				(width 0)
				(type default)
			)
			(fill no)
			(layer "F.Fab")
		)
		(pad "1" smd rect
			(at 0 -0.8382 180)
			(size 1.5494 0.9398)
			(layers "F.Cu" "F.Mask" "F.Paste")
			(net "PVCCP")
		)
		(pad "2" smd rect
			(at 0 0.8382 180)
			(size 1.5494 0.9398)
			(layers "F.Cu" "F.Mask" "F.Paste")
			(net "GND")
		)
	)
	(footprint ""
		(layer "F.Cu")
		(at 27.0764 -54.3814 90)
		(property "Reference" "PC46"
			(at 0 0 90)
			(layer "F.SilkS")
			(hide yes)
			(effects
				(font
					(size 1.27 1.27)
				)
			)
		)
		(property "Value" "SCD22U16V3KX-2-GP"
			(at -0.0254 -2.0193 90)
			(unlocked yes)
			(layer "F.Fab")
			(hide yes)
			(effects
				(font
					(size 1.016 1.016)
					(thickness 0.1524)
				)
			)
		)
		(property "Device Type" "C603H36"
			(at -0.0254 -3.5433 90)
			(unlocked yes)
			(layer "F.Fab")
			(hide yes)
			(effects
				(font
					(size 1.016 1.016)
					(thickness 0.1524)
				)
			)
		)
		(duplicate_pad_numbers_are_jumpers no)
		(fp_line
			(start -0.4064 0)
			(end 0.4064 0)
			(stroke
				(width 0.2286)
				(type default)
			)
			(layer "F.SilkS")
		)
		(fp_rect
			(start -0.635 1.1811)
			(end 0.635 -1.1811)
			(stroke
				(width 0)
				(type default)
			)
			(fill no)
			(layer "F.CrtYd")
		)
		(fp_rect
			(start -0.635 1.1811)
			(end 0.635 -1.1811)
			(stroke
				(width 0)
				(type default)
			)
			(fill no)
			(layer "F.Fab")
		)
		(pad "1" smd custom
			(at 0 -0.6604 90)
			(size 0.19685 0.19685)
			(layers "F.Cu" "F.Mask" "F.Paste")
			(net "VR_PVCCP_BOOT")
			(options
				(clearance outline)
				(anchor circle)
			)
			(primitives
				(gr_poly
					(pts
						(arc
							(start 0.508 -0.2921)
							(mid 0.478242 -0.363942)
							(end 0.4064 -0.3937)
						)
						(arc
							(start -0.4064 -0.3937)
							(mid -0.478242 -0.363942)
							(end -0.508 -0.2921)
						)
						(arc
							(start -0.508 0.2921)
							(mid -0.478242 0.363942)
							(end -0.4064 0.3937)
						)
						(arc
							(start 0.4064 0.3937)
							(mid 0.478242 0.363942)
							(end 0.508 0.2921)
						)
					)
					(width 0)
					(fill yes)
				)
			)
		)
		(pad "2" smd custom
			(at 0 0.6604 90)
			(size 0.19685 0.19685)
			(layers "F.Cu" "F.Mask" "F.Paste")
			(net "VR_PVCCP_BOOT_R")
			(options
				(clearance outline)
				(anchor circle)
			)
			(primitives
				(gr_poly
					(pts
						(arc
							(start 0.508 -0.2921)
							(mid 0.478242 -0.363942)
							(end 0.4064 -0.3937)
						)
						(arc
							(start -0.4064 -0.3937)
							(mid -0.478242 -0.363942)
							(end -0.508 -0.2921)
						)
						(arc
							(start -0.508 0.2921)
							(mid -0.478242 0.363942)
							(end -0.4064 0.3937)
						)
						(arc
							(start 0.4064 0.3937)
							(mid 0.478242 0.363942)
							(end 0.508 0.2921)
						)
					)
					(width 0)
					(fill yes)
				)
			)
		)
	)
	(footprint ""
		(layer "F.Cu")
		(at 48.26 -20.955)
		(property "Reference" "R169"
			(at 0 0 0)
			(layer "F.SilkS")
			(hide yes)
			(effects
				(font
					(size 1.27 1.27)
				)
			)
		)
		(property "Value" "15R2F-2-GP"
			(at 0.064008 -3.993896 0)
			(unlocked yes)
			(layer "F.Fab")
			(hide yes)
			(effects
				(font
					(size 1.016 1.016)
					(thickness 0.1524)
				)
			)
		)
		(property "Device Type" "R402H16"
			(at 0.064008 -5.517896 0)
			(unlocked yes)
			(layer "F.Fab")
			(hide yes)
			(effects
				(font
					(size 1.016 1.016)
					(thickness 0.1524)
				)
			)
		)
		(duplicate_pad_numbers_are_jumpers no)
		(fp_rect
			(start -0.381 0.8382)
			(end 0.381 -0.8382)
			(stroke
				(width 0)
				(type default)
			)
			(fill no)
			(layer "F.CrtYd")
		)
		(fp_rect
			(start -0.381 0.8382)
			(end 0.381 -0.8382)
			(stroke
				(width 0)
				(type default)
			)
			(fill no)
			(layer "F.Fab")
		)
		(pad "1" smd custom
			(at 0 -0.4318)
			(size 0.127 0.127)
			(layers "F.Cu" "F.Mask" "F.Paste")
			(net "SPI_MISO_R_GBE")
			(options
				(clearance outline)
				(anchor circle)
			)
			(primitives
				(gr_poly
					(pts
						(arc
							(start -0.2032 -0.2794)
							(mid -0.239121 -0.264521)
							(end -0.254 -0.2286)
						)
						(arc
							(start -0.254 0.2286)
							(mid -0.239121 0.264521)
							(end -0.2032 0.2794)
						)
						(arc
							(start 0.2032 0.2794)
							(mid 0.239121 0.264521)
							(end 0.254 0.2286)
						)
						(arc
							(start 0.254 -0.2286)
							(mid 0.239121 -0.264521)
							(end 0.2032 -0.2794)
						)
					)
					(width 0)
					(fill yes)
				)
			)
		)
		(pad "2" smd custom
			(at 0 0.4318)
			(size 0.127 0.127)
			(layers "F.Cu" "F.Mask" "F.Paste")
			(net "SO_GBE")
			(options
				(clearance outline)
				(anchor circle)
			)
			(primitives
				(gr_poly
					(pts
						(arc
							(start -0.2032 -0.2794)
							(mid -0.239121 -0.264521)
							(end -0.254 -0.2286)
						)
						(arc
							(start -0.254 0.2286)
							(mid -0.239121 0.264521)
							(end -0.2032 0.2794)
						)
						(arc
							(start 0.2032 0.2794)
							(mid 0.239121 0.264521)
							(end 0.254 0.2286)
						)
						(arc
							(start 0.254 -0.2286)
							(mid 0.239121 -0.264521)
							(end 0.2032 -0.2794)
						)
					)
					(width 0)
					(fill yes)
				)
			)
		)
	)
	(footprint ""
		(layer "F.Cu")
		(at 74.9554 -38.481 -90)
		(property "Reference" "R487"
			(at 0 0 270)
			(layer "F.SilkS")
			(hide yes)
			(effects
				(font
					(size 1.27 1.27)
				)
			)
		)
		(property "Value" "51R2F-2-GP"
			(at 1.7907 -1.1176 270)
			(unlocked yes)
			(layer "F.Fab")
			(hide yes)
			(effects
				(font
					(size 1.016 1.016)
					(thickness 0.1524)
				)
			)
		)
		(property "Device Type" "R402H16"
			(at 1.7907 -2.6416 270)
			(unlocked yes)
			(layer "F.Fab")
			(hide yes)
			(effects
				(font
					(size 1.016 1.016)
					(thickness 0.1524)
				)
			)
		)
		(duplicate_pad_numbers_are_jumpers no)
		(fp_rect
			(start -0.381 0.8382)
			(end 0.381 -0.8382)
			(stroke
				(width 0)
				(type default)
			)
			(fill no)
			(layer "F.CrtYd")
		)
		(fp_rect
			(start -0.381 0.8382)
			(end 0.381 -0.8382)
			(stroke
				(width 0)
				(type default)
			)
			(fill no)
			(layer "F.Fab")
		)
		(pad "1" smd custom
			(at 0 -0.4318 270)
			(size 0.127 0.127)
			(layers "F.Cu" "F.Mask" "F.Paste")
			(net "XDP_SOC_CPU_TDO")
			(options
				(clearance outline)
				(anchor circle)
			)
			(primitives
				(gr_poly
					(pts
						(arc
							(start -0.2032 -0.2794)
							(mid -0.239121 -0.264521)
							(end -0.254 -0.2286)
						)
						(arc
							(start -0.254 0.2286)
							(mid -0.239121 0.264521)
							(end -0.2032 0.2794)
						)
						(arc
							(start 0.2032 0.2794)
							(mid 0.239121 0.264521)
							(end 0.254 0.2286)
						)
						(arc
							(start 0.254 -0.2286)
							(mid 0.239121 -0.264521)
							(end 0.2032 -0.2794)
						)
					)
					(width 0)
					(fill yes)
				)
			)
		)
		(pad "2" smd custom
			(at 0 0.4318 270)
			(size 0.127 0.127)
			(layers "F.Cu" "F.Mask" "F.Paste")
			(net "GND")
			(options
				(clearance outline)
				(anchor circle)
			)
			(primitives
				(gr_poly
					(pts
						(arc
							(start -0.2032 -0.2794)
							(mid -0.239121 -0.264521)
							(end -0.254 -0.2286)
						)
						(arc
							(start -0.254 0.2286)
							(mid -0.239121 0.264521)
							(end -0.2032 0.2794)
						)
						(arc
							(start 0.2032 0.2794)
							(mid 0.239121 0.264521)
							(end 0.254 0.2286)
						)
						(arc
							(start 0.254 -0.2286)
							(mid 0.239121 -0.264521)
							(end 0.2032 -0.2794)
						)
					)
					(width 0)
					(fill yes)
				)
			)
		)
	)
	(footprint ""
		(layer "F.Cu")
		(at 136.398 -59.4614 90)
		(property "Reference" "PC43"
			(at 0 0 90)
			(layer "F.SilkS")
			(hide yes)
			(effects
				(font
					(size 1.27 1.27)
				)
			)
		)
		(property "Value" "SC1KP50V2KX-1GP"
			(at 1.1811 -2.7051 90)
			(unlocked yes)
			(layer "F.Fab")
			(hide yes)
			(effects
				(font
					(size 1.016 1.016)
					(thickness 0.1524)
				)
			)
		)
		(property "Device Type" "C402H22"
			(at 1.1811 -4.2291 90)
			(unlocked yes)
			(layer "F.Fab")
			(hide yes)
			(effects
				(font
					(size 1.016 1.016)
					(thickness 0.1524)
				)
			)
		)
		(duplicate_pad_numbers_are_jumpers no)
		(fp_rect
			(start -0.381 0.7366)
			(end 0.381 -0.7366)
			(stroke
				(width 0)
				(type default)
			)
			(fill no)
			(layer "F.CrtYd")
		)
		(fp_rect
			(start -0.381 0.7366)
			(end 0.381 -0.7366)
			(stroke
				(width 0)
				(type default)
			)
			(fill no)
			(layer "F.Fab")
		)
		(pad "1" smd custom
			(at 0 -0.4572 90)
			(size 0.1143 0.1143)
			(layers "F.Cu" "F.Mask" "F.Paste")
			(net "PV_VTT_DDR_REFIN")
			(options
				(clearance outline)
				(anchor circle)
			)
			(primitives
				(gr_poly
					(pts
						(arc
							(start -0.254 -0.1778)
							(mid -0.239121 -0.213721)
							(end -0.2032 -0.2286)
						)
						(arc
							(start 0.2032 -0.2286)
							(mid 0.239121 -0.213721)
							(end 0.254 -0.1778)
						)
						(arc
							(start 0.254 0.1778)
							(mid 0.239121 0.213721)
							(end 0.2032 0.2286)
						)
						(arc
							(start -0.2032 0.2286)
							(mid -0.239121 0.213721)
							(end -0.254 0.1778)
						)
					)
					(width 0)
					(fill yes)
				)
			)
		)
		(pad "2" smd custom
			(at 0 0.4572 90)
			(size 0.1143 0.1143)
			(layers "F.Cu" "F.Mask" "F.Paste")
			(net "GND")
			(options
				(clearance outline)
				(anchor circle)
			)
			(primitives
				(gr_poly
					(pts
						(arc
							(start -0.254 -0.1778)
							(mid -0.239121 -0.213721)
							(end -0.2032 -0.2286)
						)
						(arc
							(start 0.2032 -0.2286)
							(mid 0.239121 -0.213721)
							(end 0.254 -0.1778)
						)
						(arc
							(start 0.254 0.1778)
							(mid 0.239121 0.213721)
							(end 0.2032 0.2286)
						)
						(arc
							(start -0.2032 0.2286)
							(mid -0.239121 0.213721)
							(end -0.254 0.1778)
						)
					)
					(width 0)
					(fill yes)
				)
			)
		)
	)
	(footprint ""
		(layer "F.Cu")
		(at 183.642 -38.1 -90)
		(property "Reference" "PR131"
			(at 0 0 270)
			(layer "F.SilkS")
			(hide yes)
			(effects
				(font
					(size 1.27 1.27)
				)
			)
		)
		(property "Value" "0R2J-2-GP"
			(at 1.7907 -1.1176 270)
			(unlocked yes)
			(layer "F.Fab")
			(hide yes)
			(effects
				(font
					(size 1.016 1.016)
					(thickness 0.1524)
				)
			)
		)
		(property "Device Type" "R402H16"
			(at 1.7907 -2.6416 270)
			(unlocked yes)
			(layer "F.Fab")
			(hide yes)
			(effects
				(font
					(size 1.016 1.016)
					(thickness 0.1524)
				)
			)
		)
		(duplicate_pad_numbers_are_jumpers no)
		(fp_rect
			(start -0.381 0.8382)
			(end 0.381 -0.8382)
			(stroke
				(width 0)
				(type default)
			)
			(fill no)
			(layer "F.CrtYd")
		)
		(fp_rect
			(start -0.381 0.8382)
			(end 0.381 -0.8382)
			(stroke
				(width 0)
				(type default)
			)
			(fill no)
			(layer "F.Fab")
		)
		(pad "1" smd custom
			(at 0 -0.4318 270)
			(size 0.127 0.127)
			(layers "F.Cu" "F.Mask" "F.Paste")
			(net "SVID_A_ALERT#")
			(options
				(clearance outline)
				(anchor circle)
			)
			(primitives
				(gr_poly
					(pts
						(arc
							(start -0.2032 -0.2794)
							(mid -0.239121 -0.264521)
							(end -0.254 -0.2286)
						)
						(arc
							(start -0.254 0.2286)
							(mid -0.239121 0.264521)
							(end -0.2032 0.2794)
						)
						(arc
							(start 0.2032 0.2794)
							(mid 0.239121 0.264521)
							(end 0.254 0.2286)
						)
						(arc
							(start 0.254 -0.2286)
							(mid 0.239121 -0.264521)
							(end 0.2032 -0.2794)
						)
					)
					(width 0)
					(fill yes)
				)
			)
		)
		(pad "2" smd custom
			(at 0 0.4318 270)
			(size 0.127 0.127)
			(layers "F.Cu" "F.Mask" "F.Paste")
			(net "SVID_CPU_ALERT#")
			(options
				(clearance outline)
				(anchor circle)
			)
			(primitives
				(gr_poly
					(pts
						(arc
							(start -0.2032 -0.2794)
							(mid -0.239121 -0.264521)
							(end -0.254 -0.2286)
						)
						(arc
							(start -0.254 0.2286)
							(mid -0.239121 0.264521)
							(end -0.2032 0.2794)
						)
						(arc
							(start 0.2032 0.2794)
							(mid 0.239121 0.264521)
							(end 0.254 0.2286)
						)
						(arc
							(start 0.254 -0.2286)
							(mid 0.239121 -0.264521)
							(end 0.2032 -0.2794)
						)
					)
					(width 0)
					(fill yes)
				)
			)
		)
	)
	(footprint ""
		(layer "F.Cu")
		(at 184.0738 -31.7246)
		(property "Reference" "PC103"
			(at 0 0 0)
			(layer "F.SilkS")
			(hide yes)
			(effects
				(font
					(size 1.27 1.27)
				)
			)
		)
		(property "Value" "SC1KP50V2KX-1GP"
			(at 1.8923 -1.2065 0)
			(unlocked yes)
			(layer "F.Fab")
			(hide yes)
			(effects
				(font
					(size 1.016 1.016)
					(thickness 0.1524)
				)
			)
		)
		(property "Device Type" "C402H22"
			(at 1.8923 -2.7305 0)
			(unlocked yes)
			(layer "F.Fab")
			(hide yes)
			(effects
				(font
					(size 1.016 1.016)
					(thickness 0.1524)
				)
			)
		)
		(duplicate_pad_numbers_are_jumpers no)
		(fp_rect
			(start -0.381 0.7366)
			(end 0.381 -0.7366)
			(stroke
				(width 0)
				(type default)
			)
			(fill no)
			(layer "F.CrtYd")
		)
		(fp_rect
			(start -0.381 0.7366)
			(end 0.381 -0.7366)
			(stroke
				(width 0)
				(type default)
			)
			(fill no)
			(layer "F.Fab")
		)
		(pad "1" smd custom
			(at 0 -0.4572)
			(size 0.1143 0.1143)
			(layers "F.Cu" "F.Mask" "F.Paste")
			(net "VR_PVDDR_A_VW")
			(options
				(clearance outline)
				(anchor circle)
			)
			(primitives
				(gr_poly
					(pts
						(arc
							(start -0.254 -0.1778)
							(mid -0.239121 -0.213721)
							(end -0.2032 -0.2286)
						)
						(arc
							(start 0.2032 -0.2286)
							(mid 0.239121 -0.213721)
							(end 0.254 -0.1778)
						)
						(arc
							(start 0.254 0.1778)
							(mid 0.239121 0.213721)
							(end 0.2032 0.2286)
						)
						(arc
							(start -0.2032 0.2286)
							(mid -0.239121 0.213721)
							(end -0.254 0.1778)
						)
					)
					(width 0)
					(fill yes)
				)
			)
		)
		(pad "2" smd custom
			(at 0 0.4572)
			(size 0.1143 0.1143)
			(layers "F.Cu" "F.Mask" "F.Paste")
			(net "VR_PVDDR_A_COMP")
			(options
				(clearance outline)
				(anchor circle)
			)
			(primitives
				(gr_poly
					(pts
						(arc
							(start -0.254 -0.1778)
							(mid -0.239121 -0.213721)
							(end -0.2032 -0.2286)
						)
						(arc
							(start 0.2032 -0.2286)
							(mid 0.239121 -0.213721)
							(end 0.254 -0.1778)
						)
						(arc
							(start 0.254 0.1778)
							(mid 0.239121 0.213721)
							(end 0.2032 0.2286)
						)
						(arc
							(start -0.2032 0.2286)
							(mid -0.239121 0.213721)
							(end -0.254 0.1778)
						)
					)
					(width 0)
					(fill yes)
				)
			)
		)
	)
	(footprint ""
		(layer "F.Cu")
		(at 6.6294 -25.527 180)
		(property "Reference" "PR114"
			(at 0 0 180)
			(layer "F.SilkS")
			(hide yes)
			(effects
				(font
					(size 1.27 1.27)
				)
			)
		)
		(property "Value" "0R3J-0-U-GP"
			(at -0.0254 -2.0193 180)
			(unlocked yes)
			(layer "F.Fab")
			(hide yes)
			(effects
				(font
					(size 1.016 1.016)
					(thickness 0.1524)
				)
			)
		)
		(property "Device Type" "R603H22"
			(at -0.0254 -3.5433 180)
			(unlocked yes)
			(layer "F.Fab")
			(hide yes)
			(effects
				(font
					(size 1.016 1.016)
					(thickness 0.1524)
				)
			)
		)
		(duplicate_pad_numbers_are_jumpers no)
		(fp_line
			(start 0.4318 0)
			(end 0.2032 0)
			(stroke
				(width 0.2032)
				(type default)
			)
			(layer "F.SilkS")
		)
		(fp_line
			(start -0.2032 0)
			(end -0.4191 0)
			(stroke
				(width 0.2032)
				(type default)
			)
			(layer "F.SilkS")
		)
		(fp_rect
			(start -0.635 1.1811)
			(end 0.635 -1.1811)
			(stroke
				(width 0)
				(type default)
			)
			(fill no)
			(layer "F.CrtYd")
		)
		(fp_rect
			(start -0.635 1.1811)
			(end 0.635 -1.1811)
			(stroke
				(width 0)
				(type default)
			)
			(fill no)
			(layer "F.Fab")
		)
		(pad "1" smd custom
			(at 0 -0.6604 180)
			(size 0.19685 0.19685)
			(layers "F.Cu" "F.Mask" "F.Paste")
			(net "P1V0_VDD")
			(options
				(clearance outline)
				(anchor circle)
			)
			(primitives
				(gr_poly
					(pts
						(arc
							(start 0.508 -0.2921)
							(mid 0.478242 -0.363942)
							(end 0.4064 -0.3937)
						)
						(arc
							(start -0.4064 -0.3937)
							(mid -0.478242 -0.363942)
							(end -0.508 -0.2921)
						)
						(arc
							(start -0.508 0.2921)
							(mid -0.478242 0.363942)
							(end -0.4064 0.3937)
						)
						(arc
							(start 0.4064 0.3937)
							(mid 0.478242 0.363942)
							(end 0.508 0.2921)
						)
					)
					(width 0)
					(fill yes)
				)
			)
		)
		(pad "2" smd custom
			(at 0 0.6604 180)
			(size 0.19685 0.19685)
			(layers "F.Cu" "F.Mask" "F.Paste")
			(net "P1V0_VIN")
			(options
				(clearance outline)
				(anchor circle)
			)
			(primitives
				(gr_poly
					(pts
						(arc
							(start 0.508 -0.2921)
							(mid 0.478242 -0.363942)
							(end 0.4064 -0.3937)
						)
						(arc
							(start -0.4064 -0.3937)
							(mid -0.478242 -0.363942)
							(end -0.508 -0.2921)
						)
						(arc
							(start -0.508 0.2921)
							(mid -0.478242 0.363942)
							(end -0.4064 0.3937)
						)
						(arc
							(start 0.4064 0.3937)
							(mid 0.478242 0.363942)
							(end 0.508 0.2921)
						)
					)
					(width 0)
					(fill yes)
				)
			)
		)
	)
	(footprint ""
		(layer "F.Cu")
		(at 95.849948 -39.200074 180)
		(property "Reference" "U13"
			(at 0 0 180)
			(layer "F.SilkS")
			(hide yes)
			(effects
				(font
					(size 1.27 1.27)
				)
			)
		)
		(property "Value" "AVOTON-GP"
			(at -25.0317 -2.4892 180)
			(unlocked yes)
			(layer "F.Fab")
			(hide yes)
			(effects
				(font
					(size 1.016 1.016)
					(thickness 0.1524)
				)
			)
		)
		(property "Device Type" "BGA1283M3428-3H197"
			(at -25.0317 -4.0132 180)
			(unlocked yes)
			(layer "F.Fab")
			(hide yes)
			(effects
				(font
					(size 1.016 1.016)
					(thickness 0.1524)
				)
			)
		)
		(duplicate_pad_numbers_are_jumpers no)
		(fp_line
			(start 17.0307 12.36218)
			(end 17.0307 13.5509)
			(stroke
				(width 0.1524)
				(type default)
			)
			(layer "F.SilkS")
		)
		(fp_line
			(start 17.0307 -11.42238)
			(end 17.0307 11.42238)
			(stroke
				(width 0.1524)
				(type default)
			)
			(layer "F.SilkS")
		)
		(fp_line
			(start 17.0307 -13.5509)
			(end 17.0307 -12.36218)
			(stroke
				(width 0.1524)
				(type default)
			)
			(layer "F.SilkS")
		)
		(fp_line
			(start 16.5608 14.0208)
			(end 15.36192 14.0208)
			(stroke
				(width 0.1524)
				(type default)
			)
			(layer "F.SilkS")
		)
		(fp_line
			(start 15.36192 -14.0208)
			(end 16.5608 -14.0208)
			(stroke
				(width 0.1524)
				(type default)
			)
			(layer "F.SilkS")
		)
		(fp_line
			(start 14.42212 14.0208)
			(end -14.42212 14.0208)
			(stroke
				(width 0.1524)
				(type default)
			)
			(layer "F.SilkS")
		)
		(fp_line
			(start -14.42212 -14.0208)
			(end 14.42212 -14.0208)
			(stroke
				(width 0.1524)
				(type default)
			)
			(layer "F.SilkS")
		)
		(fp_line
			(start -15.36192 14.0208)
			(end -16.5608 14.0208)
			(stroke
				(width 0.1524)
				(type default)
			)
			(layer "F.SilkS")
		)
		(fp_line
			(start -16.5608 -14.0208)
			(end -15.36192 -14.0208)
			(stroke
				(width 0.1524)
				(type default)
			)
			(layer "F.SilkS")
		)
		(fp_line
			(start -17.0307 13.5509)
			(end -17.0307 12.36218)
			(stroke
				(width 0.1524)
				(type default)
			)
			(layer "F.SilkS")
		)
		(fp_line
			(start -17.0307 11.42238)
			(end -17.0307 -11.42238)
			(stroke
				(width 0.1524)
				(type default)
			)
			(layer "F.SilkS")
		)
		(fp_line
			(start -17.0307 -12.36218)
			(end -17.0307 -13.5509)
			(stroke
				(width 0.1524)
				(type default)
			)
			(layer "F.SilkS")
		)
		(fp_circle
			(center 17.0307 14.0208)
			(end 16.5608 14.0208)
			(stroke
				(width 0.1524)
				(type default)
			)
			(fill no)
			(layer "F.SilkS")
		)
		(fp_circle
			(center 17.0307 11.89228)
			(end 16.5608 11.89228)
			(stroke
				(width 0.1524)
				(type default)
			)
			(fill no)
			(layer "F.SilkS")
		)
		(fp_circle
			(center 17.0307 -11.89228)
			(end 16.5608 -11.89228)
			(stroke
				(width 0.1524)
				(type default)
			)
			(fill no)
			(layer "F.SilkS")
		)
		(fp_circle
			(center 17.0307 -14.0208)
			(end 16.5608 -14.0208)
			(stroke
				(width 0.1524)
				(type default)
			)
			(fill no)
			(layer "F.SilkS")
		)
		(fp_circle
			(center 14.89202 14.0208)
			(end 14.42212 14.0208)
			(stroke
				(width 0.1524)
				(type default)
			)
			(fill no)
			(layer "F.SilkS")
		)
		(fp_circle
			(center 14.89202 -14.0208)
			(end 14.42212 -14.0208)
			(stroke
				(width 0.1524)
				(type default)
			)
			(fill no)
			(layer "F.SilkS")
		)
		(fp_circle
			(center -14.89202 14.0208)
			(end -15.36192 14.0208)
			(stroke
				(width 0.1524)
				(type default)
			)
			(fill no)
			(layer "F.SilkS")
		)
		(fp_circle
			(center -14.89202 -14.0208)
			(end -15.36192 -14.0208)
			(stroke
				(width 0.1524)
				(type default)
			)
			(fill no)
			(layer "F.SilkS")
		)
		(fp_circle
			(center -17.0307 14.0208)
			(end -17.5006 14.0208)
			(stroke
				(width 0.1524)
				(type default)
			)
			(fill no)
			(layer "F.SilkS")
		)
		(fp_circle
			(center -17.0307 11.89228)
			(end -17.5006 11.89228)
			(stroke
				(width 0.1524)
				(type default)
			)
			(fill no)
			(layer "F.SilkS")
		)
		(fp_circle
			(center -17.0307 -11.89228)
			(end -17.5006 -11.89228)
			(stroke
				(width 0.1524)
				(type default)
			)
			(fill no)
			(layer "F.SilkS")
		)
		(fp_circle
			(center -17.0307 -14.0208)
			(end -17.5006 -14.0208)
			(stroke
				(width 0.1524)
				(type default)
			)
			(fill no)
			(layer "F.SilkS")
		)
		(fp_poly
			(pts
				(xy -17.415002 -15.102586) (xy -18.099278 -14.41831) (xy -17.415002 -14.41831)
			)
			(stroke
				(width 0)
				(type default)
			)
			(fill yes)
			(layer "F.SilkS")
		)
		(fp_poly
			(pts
				(arc
					(start 16.5608 14.0208)
					(mid 17.5006 14.0208)
					(end 16.5608 14.0208)
				)
			)
			(stroke
				(width 0)
				(type default)
			)
			(fill yes)
			(layer "F.SilkS")
		)
		(fp_poly
			(pts
				(arc
					(start 16.5608 11.89228)
					(mid 17.5006 11.89228)
					(end 16.5608 11.89228)
				)
			)
			(stroke
				(width 0)
				(type default)
			)
			(fill yes)
			(layer "F.SilkS")
		)
		(fp_poly
			(pts
				(arc
					(start 16.5608 -11.89228)
					(mid 17.5006 -11.89228)
					(end 16.5608 -11.89228)
				)
			)
			(stroke
				(width 0)
				(type default)
			)
			(fill yes)
			(layer "F.SilkS")
		)
		(fp_poly
			(pts
				(arc
					(start 16.5608 -14.0208)
					(mid 17.5006 -14.0208)
					(end 16.5608 -14.0208)
				)
			)
			(stroke
				(width 0)
				(type default)
			)
			(fill yes)
			(layer "F.SilkS")
		)
		(fp_poly
			(pts
				(arc
					(start 14.42212 14.0208)
					(mid 15.36192 14.0208)
					(end 14.42212 14.0208)
				)
			)
			(stroke
				(width 0)
				(type default)
			)
			(fill yes)
			(layer "F.SilkS")
		)
		(fp_poly
			(pts
				(arc
					(start 14.42212 -14.0208)
					(mid 15.36192 -14.0208)
					(end 14.42212 -14.0208)
				)
			)
			(stroke
				(width 0)
				(type default)
			)
			(fill yes)
			(layer "F.SilkS")
		)
		(fp_poly
			(pts
				(arc
					(start -15.36192 14.0208)
					(mid -14.42212 14.0208)
					(end -15.36192 14.0208)
				)
			)
			(stroke
				(width 0)
				(type default)
			)
			(fill yes)
			(layer "F.SilkS")
		)
		(fp_poly
			(pts
				(arc
					(start -15.36192 -14.0208)
					(mid -14.42212 -14.0208)
					(end -15.36192 -14.0208)
				)
			)
			(stroke
				(width 0)
				(type default)
			)
			(fill yes)
			(layer "F.SilkS")
		)
		(fp_poly
			(pts
				(arc
					(start -17.5006 14.0208)
					(mid -16.5608 14.0208)
					(end -17.5006 14.0208)
				)
			)
			(stroke
				(width 0)
				(type default)
			)
			(fill yes)
			(layer "F.SilkS")
		)
		(fp_poly
			(pts
				(arc
					(start -17.5006 11.89228)
					(mid -16.5608 11.89228)
					(end -17.5006 11.89228)
				)
			)
			(stroke
				(width 0)
				(type default)
			)
			(fill yes)
			(layer "F.SilkS")
		)
		(fp_poly
			(pts
				(arc
					(start -17.5006 -11.89228)
					(mid -16.5608 -11.89228)
					(end -17.5006 -11.89228)
				)
			)
			(stroke
				(width 0)
				(type default)
			)
			(fill yes)
			(layer "F.SilkS")
		)
		(fp_poly
			(pts
				(arc
					(start -17.5006 -14.0208)
					(mid -16.5608 -14.0208)
					(end -17.5006 -14.0208)
				)
			)
			(stroke
				(width 0)
				(type default)
			)
			(fill yes)
			(layer "F.SilkS")
		)
		(fp_rect
			(start -17.0307 14.0208)
			(end 17.0307 -14.0208)
			(stroke
				(width 0)
				(type default)
			)
			(fill no)
			(layer "F.CrtYd")
		)
		(fp_poly
			(pts
				(xy -19.076924 16.067024) (xy -19.076924 9.845548) (xy -17.2847 9.845548) (xy -17.2847 -9.845548)
				(xy -19.076924 -9.845548) (xy -19.076924 -16.067024) (xy -12.845542 -16.067024) (xy -12.845542 -14.2748)
				(xy 12.845542 -14.2748) (xy 12.845542 -16.067024) (xy 19.076924 -16.067024) (xy 19.076924 -9.845548)
				(xy 17.2847 -9.845548) (xy 17.2847 1.016) (xy 17.0307 1.016) (xy 17.0307 -14.0208) (xy -17.0307 -14.0208)
				(xy -17.0307 14.0208) (xy 17.0307 14.0208) (xy 17.0307 1.0287) (xy 17.2847 1.0287) (xy 17.2847 9.845548)
				(xy 19.076924 9.845548) (xy 19.076924 16.067024) (xy 12.845542 16.067024) (xy 12.845542 14.2748)
				(xy -12.845542 14.2748) (xy -12.845542 16.067024)
			)
			(stroke
				(width 0)
				(type default)
			)
			(fill no)
			(layer "F.CrtYd")
		)
		(fp_poly
			(pts
				(xy -19.076924 16.067024) (xy -19.076924 9.845548) (xy -17.2847 9.845548) (xy -17.2847 -9.845548)
				(xy -19.076924 -9.845548) (xy -19.076924 -16.067024) (xy -12.845542 -16.067024) (xy -12.845542 -14.2748)
				(xy 12.845542 -14.2748) (xy 12.845542 -16.067024) (xy 19.076924 -16.067024) (xy 19.076924 -9.845548)
				(xy 17.2847 -9.845548) (xy 17.2847 9.845548) (xy 19.076924 9.845548) (xy 19.076924 16.067024) (xy 12.845542 16.067024)
				(xy 12.845542 14.2748) (xy -12.845542 14.2748) (xy -12.845542 16.067024)
			)
			(stroke
				(width 0)
				(type default)
			)
			(fill no)
			(layer "F.Fab")
		)
		(pad "A5" smd circle
			(at -14.48562 -13.11148 180)
			(size 0.5588 0.5588)
			(layers "F.Cu" "F.Mask" "F.Paste")
			(net "GND")
		)
		(pad "A6" smd circle
			(at -13.67282 -13.11148 180)
			(size 0.4064 0.4064)
			(layers "F.Cu" "F.Mask" "F.Paste")
			(net "M_B_MON2_N")
		)
		(pad "A8" smd circle
			(at -12.86002 -13.11148 180)
			(size 0.4064 0.4064)
			(layers "F.Cu" "F.Mask" "F.Paste")
			(net "M_B_MON2_P")
		)
		(pad "A9" smd oval
			(at -12.17422 -13.24864 180)
			(size 0.254 0.3429)
			(layers "F.Cu" "F.Mask" "F.Paste")
			(net "GND")
		)
		(pad "A12" smd oval
			(at -10.54862 -13.24864 180)
			(size 0.254 0.3429)
			(layers "F.Cu" "F.Mask" "F.Paste")
			(net "GND")
		)
		(pad "A15" smd oval
			(at -9.10844 -13.24864 180)
			(size 0.254 0.3429)
			(layers "F.Cu" "F.Mask" "F.Paste")
			(net "GND")
		)
		(pad "A18" smd oval
			(at -7.6708 -13.24864 180)
			(size 0.254 0.3429)
			(layers "F.Cu" "F.Mask" "F.Paste")
			(net "GND")
		)
		(pad "A21" smd oval
			(at -6.0452 -13.24864 180)
			(size 0.254 0.3429)
			(layers "F.Cu" "F.Mask" "F.Paste")
			(net "M_B_DQS_DP2")
		)
		(pad "A24" smd oval
			(at -4.60756 -13.24864 180)
			(size 0.254 0.3429)
			(layers "F.Cu" "F.Mask" "F.Paste")
			(net "GND")
		)
		(pad "A27" smd oval
			(at -3.16738 -13.24864 180)
			(size 0.254 0.3429)
			(layers "F.Cu" "F.Mask" "F.Paste")
			(net "M_B_DQ10")
		)
		(pad "A30" smd oval
			(at -1.54178 -13.24864 180)
			(size 0.254 0.3429)
			(layers "F.Cu" "F.Mask" "F.Paste")
			(net "GND")
		)
		(pad "A33" smd oval
			(at -0.10414 -13.24864 180)
			(size 0.254 0.3429)
			(layers "F.Cu" "F.Mask" "F.Paste")
			(net "GND")
		)
		(pad "A36" smd oval
			(at 1.33604 -13.24864 180)
			(size 0.254 0.3429)
			(layers "F.Cu" "F.Mask" "F.Paste")
			(net "M_B_DQ6")
		)
		(pad "A39" smd oval
			(at 2.96164 -13.24864 180)
			(size 0.254 0.3429)
			(layers "F.Cu" "F.Mask" "F.Paste")
			(net "M_B_DQ4")
		)
		(pad "A42" smd oval
			(at 4.39928 -13.24864 180)
			(size 0.254 0.3429)
			(layers "F.Cu" "F.Mask" "F.Paste")
			(net "Net_1361")
		)
		(pad "A45" smd oval
			(at 5.83692 -13.24864 180)
			(size 0.254 0.3429)
			(layers "F.Cu" "F.Mask" "F.Paste")
			(net "GND")
		)
		(pad "A48" smd oval
			(at 7.46252 -13.24864 180)
			(size 0.254 0.3429)
			(layers "F.Cu" "F.Mask" "F.Paste")
			(net "GND")
		)
		(pad "A51" smd oval
			(at 8.9027 -13.24864 180)
			(size 0.254 0.3429)
			(layers "F.Cu" "F.Mask" "F.Paste")
			(net "GND")
		)
		(pad "A54" smd oval
			(at 10.34034 -13.24864 180)
			(size 0.254 0.3429)
			(layers "F.Cu" "F.Mask" "F.Paste")
			(net "Net_1348")
		)
		(pad "A57" smd oval
			(at 11.96594 -13.24864 180)
			(size 0.254 0.3429)
			(layers "F.Cu" "F.Mask" "F.Paste")
			(net "GND")
		)
		(pad "A59" smd circle
			(at 12.86002 -13.11148 180)
			(size 0.4064 0.4064)
			(layers "F.Cu" "F.Mask" "F.Paste")
			(net "GND")
		)
		(pad "A61" smd circle
			(at 13.67282 -13.11148 180)
			(size 0.4064 0.4064)
			(layers "F.Cu" "F.Mask" "F.Paste")
			(net "GND")
		)
		(pad "A62" smd circle
			(at 14.48562 -13.11148 180)
			(size 0.4064 0.4064)
			(layers "F.Cu" "F.Mask" "F.Paste")
			(net "GND")
		)
		(pad "A64" smd circle
			(at 15.29842 -13.11148 180)
			(size 0.5588 0.5588)
			(layers "F.Cu" "F.Mask" "F.Paste")
			(net "GND")
		)
		(pad "A66" smd circle
			(at 16.11122 -13.11148 180)
			(size 0.5588 0.5588)
			(layers "F.Cu" "F.Mask" "F.Paste")
			(net "GND")
		)
		(pad "AA3" smd circle
			(at -15.24762 -3.21564 180)
			(size 0.3048 0.3048)
			(layers "F.Cu" "F.Mask" "F.Paste")
			(net "GND")
		)
		(pad "AA5" smd circle
			(at -14.01318 -3.18516 180)
			(size 0.3048 0.3048)
			(layers "F.Cu" "F.Mask" "F.Paste")
			(net "GND")
		)
		(pad "AA21" smd circle
			(at -5.99948 -3.2004 180)
			(size 0.381 0.381)
			(layers "F.Cu" "F.Mask" "F.Paste")
			(net "P1V0")
		)
		(pad "AA23" smd circle
			(at -5.20192 -3.2004 180)
			(size 0.381 0.381)
			(layers "F.Cu" "F.Mask" "F.Paste")
			(net "GND")
		)
		(pad "AA25" smd circle
			(at -4.39928 -3.2004 180)
			(size 0.381 0.381)
			(layers "F.Cu" "F.Mask" "F.Paste")
			(net "GND")
		)
		(pad "AA26" smd circle
			(at -3.60172 -3.2004 180)
			(size 0.381 0.381)
			(layers "F.Cu" "F.Mask" "F.Paste")
			(net "GND")
		)
		(pad "AA28" smd circle
			(at -2.79908 -3.2004 180)
			(size 0.381 0.381)
			(layers "F.Cu" "F.Mask" "F.Paste")
			(net "GND")
		)
		(pad "AA29" smd circle
			(at -2.00152 -3.2004 180)
			(size 0.381 0.381)
			(layers "F.Cu" "F.Mask" "F.Paste")
			(net "GND")
		)
		(pad "AA31" smd circle
			(at -1.19888 -3.2004 180)
			(size 0.381 0.381)
			(layers "F.Cu" "F.Mask" "F.Paste")
			(net "GND")
		)
		(pad "AA32" smd circle
			(at -0.40132 -3.2004 180)
			(size 0.381 0.381)
			(layers "F.Cu" "F.Mask" "F.Paste")
			(net "P1V35")
		)
		(pad "AA34" smd circle
			(at 0.40132 -3.2004 180)
			(size 0.381 0.381)
			(layers "F.Cu" "F.Mask" "F.Paste")
			(net "P1V35")
		)
		(pad "AA36" smd circle
			(at 1.19888 -3.2004 180)
			(size 0.381 0.381)
			(layers "F.Cu" "F.Mask" "F.Paste")
			(net "GND")
		)
		(pad "AA38" smd circle
			(at 2.00152 -3.2004 180)
			(size 0.381 0.381)
			(layers "F.Cu" "F.Mask" "F.Paste")
			(net "P1V0_STBY")
		)
		(pad "AA39" smd circle
			(at 2.79908 -3.2004 180)
			(size 0.381 0.381)
			(layers "F.Cu" "F.Mask" "F.Paste")
			(net "P1V0_STBY")
		)
		(pad "AA41" smd circle
			(at 3.60172 -3.2004 180)
			(size 0.381 0.381)
			(layers "F.Cu" "F.Mask" "F.Paste")
			(net "P1V0_STBY")
		)
		(pad "AA42" smd circle
			(at 4.39928 -3.2004 180)
			(size 0.381 0.381)
			(layers "F.Cu" "F.Mask" "F.Paste")
			(net "GND")
		)
		(pad "AA44" smd circle
			(at 5.20192 -3.2004 180)
			(size 0.381 0.381)
			(layers "F.Cu" "F.Mask" "F.Paste")
			(net "GND")
		)
		(pad "AA46" smd circle
			(at 5.99948 -3.2004 180)
			(size 0.381 0.381)
			(layers "F.Cu" "F.Mask" "F.Paste")
			(net "XDP_SOC_CPU_TRST#")
		)
		(pad "AA47" smd circle
			(at 6.84276 -3.15722 180)
			(size 0.3048 0.3048)
			(layers "F.Cu" "F.Mask" "F.Paste")
			(net "Net_167")
		)
		(pad "AA62" smd circle
			(at 14.08176 -3.38836 180)
			(size 0.3048 0.3048)
			(layers "F.Cu" "F.Mask" "F.Paste")
			(net "GND")
		)
		(pad "AA64" smd circle
			(at 15.24254 -3.39852 180)
			(size 0.3048 0.3048)
			(layers "F.Cu" "F.Mask" "F.Paste")
			(net "GND")
		)
		(pad "AA66" smd oval
			(at 16.24838 -3.16738 180)
			(size 0.3429 0.254)
			(layers "F.Cu" "F.Mask" "F.Paste")
			(net "GND")
		)
		(pad "AB1" smd oval
			(at -16.24838 -2.96164 180)
			(size 0.3429 0.254)
			(layers "F.Cu" "F.Mask" "F.Paste")
			(net "GND")
		)
		(pad "AB2" smd circle
			(at -15.64132 -2.61112 180)
			(size 0.3048 0.3048)
			(layers "F.Cu" "F.Mask" "F.Paste")
			(net "M_B_DQ42")
		)
		(pad "AB4" smd circle
			(at -14.89964 -2.60604 180)
			(size 0.3048 0.3048)
			(layers "F.Cu" "F.Mask" "F.Paste")
			(net "M_B_DQ43")
		)
		(pad "AB5" smd circle
			(at -14.20368 -2.50698 180)
			(size 0.3048 0.3048)
			(layers "F.Cu" "F.Mask" "F.Paste")
			(net "GND")
		)
		(pad "AB20" smd circle
			(at -6.84276 -2.91592 180)
			(size 0.3048 0.3048)
			(layers "F.Cu" "F.Mask" "F.Paste")
			(net "GND")
		)
		(pad "AB62" smd circle
			(at 14.20368 -2.69494 180)
			(size 0.3048 0.3048)
			(layers "F.Cu" "F.Mask" "F.Paste")
			(net "SPI_CPU_MOSI")
		)
		(pad "AB63" smd circle
			(at 14.89964 -2.78638 180)
			(size 0.3048 0.3048)
			(layers "F.Cu" "F.Mask" "F.Paste")
			(net "PU_PMU_GPE#")
		)
		(pad "AB65" smd circle
			(at 15.63878 -2.8194 180)
			(size 0.3048 0.3048)
			(layers "F.Cu" "F.Mask" "F.Paste")
			(net "SUS_STAT#")
		)
		(pad "AC8" smd circle
			(at -12.96416 -2.21742 180)
			(size 0.3048 0.3048)
			(layers "F.Cu" "F.Mask" "F.Paste")
			(net "M_B_DQ56")
		)
		(pad "AC9" smd circle
			(at -12.20216 -2.21742 180)
			(size 0.3048 0.3048)
			(layers "F.Cu" "F.Mask" "F.Paste")
			(net "M_B_DQ61")
		)
		(pad "AC11" smd circle
			(at -11.44016 -2.21742 180)
			(size 0.3048 0.3048)
			(layers "F.Cu" "F.Mask" "F.Paste")
			(net "M_B_DQ60")
		)
		(pad "AC12" smd circle
			(at -10.67816 -2.21742 180)
			(size 0.3048 0.3048)
			(layers "F.Cu" "F.Mask" "F.Paste")
			(net "GND")
		)
		(pad "AC14" smd circle
			(at -9.91616 -2.21742 180)
			(size 0.3048 0.3048)
			(layers "F.Cu" "F.Mask" "F.Paste")
			(net "M_B_DQ62")
		)
		(pad "AC15" smd circle
			(at -9.15416 -2.21742 180)
			(size 0.3048 0.3048)
			(layers "F.Cu" "F.Mask" "F.Paste")
			(net "M_B_DQ63")
		)
		(pad "AC17" smd circle
			(at -8.39216 -2.21742 180)
			(size 0.3048 0.3048)
			(layers "F.Cu" "F.Mask" "F.Paste")
			(net "M_B_DQ59")
		)
		(pad "AC18" smd circle
			(at -7.63016 -2.21742 180)
			(size 0.3048 0.3048)
			(layers "F.Cu" "F.Mask" "F.Paste")
			(net "GND")
		)
		(pad "AC20" smd circle
			(at -6.92912 -2.21742 180)
			(size 0.3048 0.3048)
			(layers "F.Cu" "F.Mask" "F.Paste")
			(net "GND")
		)
		(pad "AC21" smd circle
			(at -5.99948 -2.4003 180)
			(size 0.381 0.381)
			(layers "F.Cu" "F.Mask" "F.Paste")
			(net "GND")
		)
		(pad "AC23" smd circle
			(at -5.20192 -2.4003 180)
			(size 0.381 0.381)
			(layers "F.Cu" "F.Mask" "F.Paste")
			(net "GND")
		)
		(pad "AC25" smd circle
			(at -4.39928 -2.4003 180)
			(size 0.381 0.381)
			(layers "F.Cu" "F.Mask" "F.Paste")
			(net "TP_CPU_RSVD12")
		)
		(pad "AC26" smd circle
			(at -3.60172 -2.4003 180)
			(size 0.381 0.381)
			(layers "F.Cu" "F.Mask" "F.Paste")
			(net "TP_CPU_RSVD11")
		)
		(pad "AC28" smd circle
			(at -2.79908 -2.4003 180)
			(size 0.381 0.381)
			(layers "F.Cu" "F.Mask" "F.Paste")
			(net "GND")
		)
		(pad "AC29" smd circle
			(at -2.00152 -2.4003 180)
			(size 0.381 0.381)
			(layers "F.Cu" "F.Mask" "F.Paste")
			(net "GND")
		)
		(pad "AC31" smd circle
			(at -1.19888 -2.4003 180)
			(size 0.381 0.381)
			(layers "F.Cu" "F.Mask" "F.Paste")
			(net "GND")
		)
		(pad "AC32" smd circle
			(at -0.40132 -2.4003 180)
			(size 0.381 0.381)
			(layers "F.Cu" "F.Mask" "F.Paste")
			(net "GND")
		)
		(pad "AC34" smd circle
			(at 0.40132 -2.4003 180)
			(size 0.381 0.381)
			(layers "F.Cu" "F.Mask" "F.Paste")
			(net "GND")
		)
		(pad "AC36" smd circle
			(at 1.19888 -2.4003 180)
			(size 0.381 0.381)
			(layers "F.Cu" "F.Mask" "F.Paste")
			(net "GND")
		)
		(pad "AC38" smd circle
			(at 2.00152 -2.4003 180)
			(size 0.381 0.381)
			(layers "F.Cu" "F.Mask" "F.Paste")
			(net "P1V0_STBY")
		)
		(pad "AC39" smd circle
			(at 2.79908 -2.4003 180)
			(size 0.381 0.381)
			(layers "F.Cu" "F.Mask" "F.Paste")
			(net "P1V0_STBY")
		)
		(pad "AC41" smd circle
			(at 3.60172 -2.4003 180)
			(size 0.381 0.381)
			(layers "F.Cu" "F.Mask" "F.Paste")
			(net "P1V0_STBY")
		)
		(pad "AC42" smd circle
			(at 4.39928 -2.4003 180)
			(size 0.381 0.381)
			(layers "F.Cu" "F.Mask" "F.Paste")
			(net "P1V0_STBY")
		)
		(pad "AC44" smd circle
			(at 5.20192 -2.4003 180)
			(size 0.381 0.381)
			(layers "F.Cu" "F.Mask" "F.Paste")
			(net "P1V0_STBY")
		)
		(pad "AC46" smd circle
			(at 5.99948 -2.4003 180)
			(size 0.381 0.381)
			(layers "F.Cu" "F.Mask" "F.Paste")
			(net "GND")
		)
		(pad "AC47" smd circle
			(at 6.92912 -2.45618 180)
			(size 0.3048 0.3048)
			(layers "F.Cu" "F.Mask" "F.Paste")
			(net "CPU_RSMRST_R#")
		)
		(pad "AC49" smd circle
			(at 7.63016 -2.45618 180)
			(size 0.3048 0.3048)
			(layers "F.Cu" "F.Mask" "F.Paste")
			(net "PMU_PWRBTN_R#")
		)
		(pad "AC50" smd circle
			(at 8.39216 -2.45618 180)
			(size 0.3048 0.3048)
			(layers "F.Cu" "F.Mask" "F.Paste")
			(net "GND")
		)
		(pad "AC52" smd circle
			(at 9.15416 -2.45618 180)
			(size 0.3048 0.3048)
			(layers "F.Cu" "F.Mask" "F.Paste")
			(net "PMU_SLP_DDRVTT#")
		)
		(pad "AC53" smd circle
			(at 9.91616 -2.45618 180)
			(size 0.3048 0.3048)
			(layers "F.Cu" "F.Mask" "F.Paste")
			(net "XDP_SOC_CPU_TMS")
		)
		(pad "AC55" smd circle
			(at 10.67816 -2.45618 180)
			(size 0.3048 0.3048)
			(layers "F.Cu" "F.Mask" "F.Paste")
			(net "GND")
		)
		(pad "AC56" smd circle
			(at 11.44016 -2.45618 180)
			(size 0.3048 0.3048)
			(layers "F.Cu" "F.Mask" "F.Paste")
			(net "XDP_SOC_CPU_TDI")
		)
		(pad "AC58" smd circle
			(at 12.20216 -2.45618 180)
			(size 0.3048 0.3048)
			(layers "F.Cu" "F.Mask" "F.Paste")
			(net "CPU_FPGA_DISABLE")
		)
		(pad "AC59" smd circle
			(at 12.96416 -2.45618 180)
			(size 0.3048 0.3048)
			(layers "F.Cu" "F.Mask" "F.Paste")
			(net "GND")
		)
		(pad "AD2" smd circle
			(at -15.63878 -1.68402 180)
			(size 0.3048 0.3048)
			(layers "F.Cu" "F.Mask" "F.Paste")
			(net "GND")
		)
		(pad "AD4" smd circle
			(at -14.89964 -1.71704 180)
			(size 0.3048 0.3048)
			(layers "F.Cu" "F.Mask" "F.Paste")
			(net "GND")
		)
		(pad "AD5" smd circle
			(at -14.20368 -1.80848 180)
			(size 0.3048 0.3048)
			(layers "F.Cu" "F.Mask" "F.Paste")
			(net "GND")
		)
		(pad "AD8" smd circle
			(at -12.96416 -1.51638 180)
			(size 0.3048 0.3048)
			(layers "F.Cu" "F.Mask" "F.Paste")
			(net "M_B_DQ57")
		)
		(pad "AD9" smd circle
			(at -12.20216 -1.51638 180)
			(size 0.3048 0.3048)
			(layers "F.Cu" "F.Mask" "F.Paste")
			(net "GND")
		)
		(pad "AD11" smd circle
			(at -11.44016 -1.51638 180)
			(size 0.3048 0.3048)
			(layers "F.Cu" "F.Mask" "F.Paste")
			(net "M_B_DQS_DN7")
		)
		(pad "AD12" smd circle
			(at -10.67816 -1.51638 180)
			(size 0.3048 0.3048)
			(layers "F.Cu" "F.Mask" "F.Paste")
			(net "M_B_DQS_DP7")
		)
		(pad "AD14" smd circle
			(at -9.91616 -1.51638 180)
			(size 0.3048 0.3048)
			(layers "F.Cu" "F.Mask" "F.Paste")
			(net "GND")
		)
		(pad "AD15" smd circle
			(at -9.15416 -1.51638 180)
			(size 0.3048 0.3048)
			(layers "F.Cu" "F.Mask" "F.Paste")
			(net "M_B_DQ58")
		)
		(pad "AD17" smd circle
			(at -8.39216 -1.51638 180)
			(size 0.3048 0.3048)
			(layers "F.Cu" "F.Mask" "F.Paste")
			(net "GND")
		)
		(pad "AD18" smd circle
			(at -7.63016 -1.51638 180)
			(size 0.3048 0.3048)
			(layers "F.Cu" "F.Mask" "F.Paste")
			(net "GND")
		)
		(pad "AD20" smd circle
			(at -6.92912 -1.51638 180)
			(size 0.3048 0.3048)
			(layers "F.Cu" "F.Mask" "F.Paste")
			(net "GND")
		)
		(pad "AD21" smd circle
			(at -5.99948 -1.6002 180)
			(size 0.381 0.381)
			(layers "F.Cu" "F.Mask" "F.Paste")
			(net "PVCCP")
		)
		(pad "AD23" smd circle
			(at -5.20192 -1.6002 180)
			(size 0.381 0.381)
			(layers "F.Cu" "F.Mask" "F.Paste")
			(net "PVCCP")
		)
		(pad "AD25" smd circle
			(at -4.39928 -1.6002 180)
			(size 0.381 0.381)
			(layers "F.Cu" "F.Mask" "F.Paste")
			(net "PVCCP")
		)
		(pad "AD26" smd circle
			(at -3.60172 -1.6002 180)
			(size 0.381 0.381)
			(layers "F.Cu" "F.Mask" "F.Paste")
			(net "PVCCP")
		)
		(pad "AD28" smd circle
			(at -2.79908 -1.6002 180)
			(size 0.381 0.381)
			(layers "F.Cu" "F.Mask" "F.Paste")
			(net "P1V0")
		)
		(pad "AD29" smd circle
			(at -2.00152 -1.6002 180)
			(size 0.381 0.381)
			(layers "F.Cu" "F.Mask" "F.Paste")
			(net "P1V0")
		)
		(pad "AD31" smd circle
			(at -1.19888 -1.6002 180)
			(size 0.381 0.381)
			(layers "F.Cu" "F.Mask" "F.Paste")
			(net "P1V1")
		)
		(pad "AD32" smd circle
			(at -0.40132 -1.6002 180)
			(size 0.381 0.381)
			(layers "F.Cu" "F.Mask" "F.Paste")
			(net "P1V1")
		)
		(pad "AD34" smd circle
			(at 0.40132 -1.6002 180)
			(size 0.381 0.381)
			(layers "F.Cu" "F.Mask" "F.Paste")
			(net "GND")
		)
		(pad "AD36" smd circle
			(at 1.19888 -1.6002 180)
			(size 0.381 0.381)
			(layers "F.Cu" "F.Mask" "F.Paste")
			(net "PVNN")
		)
		(pad "AD38" smd circle
			(at 2.00152 -1.6002 180)
			(size 0.381 0.381)
			(layers "F.Cu" "F.Mask" "F.Paste")
			(net "P1V0")
		)
		(pad "AD39" smd circle
			(at 2.79908 -1.6002 180)
			(size 0.381 0.381)
			(layers "F.Cu" "F.Mask" "F.Paste")
			(net "PVNN")
		)
		(pad "AD41" smd circle
			(at 3.60172 -1.6002 180)
			(size 0.381 0.381)
			(layers "F.Cu" "F.Mask" "F.Paste")
			(net "GND")
		)
		(pad "AD42" smd circle
			(at 4.39928 -1.6002 180)
			(size 0.381 0.381)
			(layers "F.Cu" "F.Mask" "F.Paste")
			(net "P3V3_CPU")
		)
		(pad "AD44" smd circle
			(at 5.20192 -1.6002 180)
			(size 0.381 0.381)
			(layers "F.Cu" "F.Mask" "F.Paste")
			(net "P3V3_CPU")
		)
		(pad "AD46" smd circle
			(at 5.99948 -1.6002 180)
			(size 0.381 0.381)
			(layers "F.Cu" "F.Mask" "F.Paste")
			(net "GND")
		)
		(pad "AD47" smd circle
			(at 6.92912 -1.75514 180)
			(size 0.3048 0.3048)
			(layers "F.Cu" "F.Mask" "F.Paste")
			(net "GND")
		)
		(pad "AD49" smd circle
			(at 7.63016 -1.75514 180)
			(size 0.3048 0.3048)
			(layers "F.Cu" "F.Mask" "F.Paste")
			(net "SRTCRST_R#")
		)
		(pad "AD50" smd circle
			(at 8.39216 -1.75514 180)
			(size 0.3048 0.3048)
			(layers "F.Cu" "F.Mask" "F.Paste")
			(net "XDP_BUF_RTEST#")
		)
		(pad "AD52" smd circle
			(at 9.15416 -1.75514 180)
			(size 0.3048 0.3048)
			(layers "F.Cu" "F.Mask" "F.Paste")
			(net "GND")
		)
		(pad "AD53" smd circle
			(at 9.91616 -1.75514 180)
			(size 0.3048 0.3048)
			(layers "F.Cu" "F.Mask" "F.Paste")
			(net "PU_INTRUDER#")
		)
		(pad "AD55" smd circle
			(at 10.67816 -1.75514 180)
			(size 0.3048 0.3048)
			(layers "F.Cu" "F.Mask" "F.Paste")
			(net "RTC_EXTPAD")
		)
		(pad "AD56" smd circle
			(at 11.44016 -1.75514 180)
			(size 0.3048 0.3048)
			(layers "F.Cu" "F.Mask" "F.Paste")
			(net "GND")
		)
		(pad "AD58" smd circle
			(at 12.20216 -1.75514 180)
			(size 0.3048 0.3048)
			(layers "F.Cu" "F.Mask" "F.Paste")
			(net "PMU_SUS_CLK_CPU")
		)
		(pad "AD59" smd circle
			(at 12.96416 -1.75514 180)
			(size 0.3048 0.3048)
			(layers "F.Cu" "F.Mask" "F.Paste")
			(net "SPI_CPU_MISO")
		)
		(pad "AD62" smd circle
			(at 14.20368 -1.9939 180)
			(size 0.3048 0.3048)
			(layers "F.Cu" "F.Mask" "F.Paste")
			(net "GND")
		)
		(pad "AD63" smd circle
			(at 14.89964 -1.89738 180)
			(size 0.3048 0.3048)
			(layers "F.Cu" "F.Mask" "F.Paste")
			(net "USB_OC#")
		)
		(pad "AD65" smd circle
			(at 15.64132 -1.8923 180)
			(size 0.3048 0.3048)
			(layers "F.Cu" "F.Mask" "F.Paste")
			(net "XDP_SOC_CPU_TCK")
		)
		(pad "AD66" smd oval
			(at 16.24838 -1.54178 180)
			(size 0.3429 0.254)
			(layers "F.Cu" "F.Mask" "F.Paste")
			(net "PMU_WAKE#")
		)
		(pad "AE1" smd oval
			(at -16.24838 -1.33604 180)
			(size 0.3429 0.254)
			(layers "F.Cu" "F.Mask" "F.Paste")
			(net "PVCCP")
		)
		(pad "AE3" smd circle
			(at -15.24254 -1.1049 180)
			(size 0.3048 0.3048)
			(layers "F.Cu" "F.Mask" "F.Paste")
			(net "AVV_VCCCPUVIDSIO_1P03_SENSE")
		)
		(pad "AE5" smd circle
			(at -14.08176 -1.11506 180)
			(size 0.3048 0.3048)
			(layers "F.Cu" "F.Mask" "F.Paste")
			(net "PVCCP")
		)
		(pad "AE47" smd circle
			(at 6.84276 -1.05664 180)
			(size 0.3048 0.3048)
			(layers "F.Cu" "F.Mask" "F.Paste")
			(net "GND")
		)
		(pad "AE62" smd circle
			(at 14.01318 -1.31572 180)
			(size 0.3048 0.3048)
			(layers "F.Cu" "F.Mask" "F.Paste")
			(net "PMU_PLTRST_R#")
		)
		(pad "AE64" smd circle
			(at 15.24762 -1.28524 180)
			(size 0.3048 0.3048)
			(layers "F.Cu" "F.Mask" "F.Paste")
			(net "GND")
		)
		(pad "AF2" smd circle
			(at -15.75308 -0.61722 180)
			(size 0.3048 0.3048)
			(layers "F.Cu" "F.Mask" "F.Paste")
			(net "AVV_VSSCPUVIDSIO_1P03_SENSE")
		)
		(pad "AF4" smd circle
			(at -14.7955 -0.56388 180)
			(size 0.3048 0.3048)
			(layers "F.Cu" "F.Mask" "F.Paste")
			(net "PVCCP")
		)
		(pad "AF20" smd circle
			(at -6.84276 -0.81534 180)
			(size 0.3048 0.3048)
			(layers "F.Cu" "F.Mask" "F.Paste")
			(net "PVCCP")
		)
		(pad "AF21" smd circle
			(at -5.99948 -0.8001 180)
			(size 0.381 0.381)
			(layers "F.Cu" "F.Mask" "F.Paste")
			(net "PVCCP")
		)
		(pad "AF23" smd circle
			(at -5.20192 -0.8001 180)
			(size 0.381 0.381)
			(layers "F.Cu" "F.Mask" "F.Paste")
			(net "PVCCP")
		)
		(pad "AF25" smd circle
			(at -4.39928 -0.8001 180)
			(size 0.381 0.381)
			(layers "F.Cu" "F.Mask" "F.Paste")
			(net "PVCCP")
		)
		(pad "AF26" smd circle
			(at -3.60172 -0.8001 180)
			(size 0.381 0.381)
			(layers "F.Cu" "F.Mask" "F.Paste")
			(net "PVCCP")
		)
		(pad "AF28" smd circle
			(at -2.79908 -0.8001 180)
			(size 0.381 0.381)
			(layers "F.Cu" "F.Mask" "F.Paste")
			(net "GND")
		)
		(pad "AF29" smd circle
			(at -2.00152 -0.8001 180)
			(size 0.381 0.381)
			(layers "F.Cu" "F.Mask" "F.Paste")
			(net "P1V1")
		)
		(pad "AF31" smd circle
			(at -1.19888 -0.8001 180)
			(size 0.381 0.381)
			(layers "F.Cu" "F.Mask" "F.Paste")
			(net "P1V1")
		)
		(pad "AF32" smd circle
			(at -0.40132 -0.8001 180)
			(size 0.381 0.381)
			(layers "F.Cu" "F.Mask" "F.Paste")
			(net "VCCRAMCPUSI1_SENSE")
		)
		(pad "AF34" smd circle
			(at 0.40132 -0.8001 180)
			(size 0.381 0.381)
			(layers "F.Cu" "F.Mask" "F.Paste")
			(net "VSSRAMCPUSI1_SENSE")
		)
		(pad "AF36" smd circle
			(at 1.19888 -0.8001 180)
			(size 0.381 0.381)
			(layers "F.Cu" "F.Mask" "F.Paste")
			(net "PVNN")
		)
		(pad "AF38" smd circle
			(at 2.00152 -0.8001 180)
			(size 0.381 0.381)
			(layers "F.Cu" "F.Mask" "F.Paste")
			(net "P1V0")
		)
		(pad "AF39" smd circle
			(at 2.79908 -0.8001 180)
			(size 0.381 0.381)
			(layers "F.Cu" "F.Mask" "F.Paste")
			(net "PVNN")
		)
		(pad "AF41" smd circle
			(at 3.60172 -0.8001 180)
			(size 0.381 0.381)
			(layers "F.Cu" "F.Mask" "F.Paste")
			(net "P1V8_STBY")
		)
		(pad "AF42" smd circle
			(at 4.39928 -0.8001 180)
			(size 0.381 0.381)
			(layers "F.Cu" "F.Mask" "F.Paste")
			(net "P1V8_STBY")
		)
		(pad "AF44" smd circle
			(at 5.20192 -0.8001 180)
			(size 0.381 0.381)
			(layers "F.Cu" "F.Mask" "F.Paste")
			(net "GND")
		)
		(pad "AF46" smd circle
			(at 5.99948 -0.8001 180)
			(size 0.381 0.381)
			(layers "F.Cu" "F.Mask" "F.Paste")
			(net "SPI_CPU_SCLK")
		)
		(pad "AF62" smd circle
			(at 14.06398 -0.61468 180)
			(size 0.3048 0.3048)
			(layers "F.Cu" "F.Mask" "F.Paste")
			(net "GND")
		)
		(pad "AF63" smd circle
			(at 14.75232 -0.78232 180)
			(size 0.3048 0.3048)
			(layers "F.Cu" "F.Mask" "F.Paste")
			(net "XDP_SOC_CPU_TDO")
		)
		(pad "AF65" smd circle
			(at 15.80642 -0.8636 180)
			(size 0.3048 0.3048)
			(layers "F.Cu" "F.Mask" "F.Paste")
			(net "PMU_SLP_S3#")
		)
		(pad "AG5" smd circle
			(at -14.06398 -0.4064 180)
			(size 0.3048 0.3048)
			(layers "F.Cu" "F.Mask" "F.Paste")
			(net "GND")
		)
		(pad "AG7" smd circle
			(at -13.34516 -0.23114 180)
			(size 0.3048 0.3048)
			(layers "F.Cu" "F.Mask" "F.Paste")
			(net "PVCCP")
		)
		(pad "AG8" smd circle
			(at -12.58316 -0.23114 180)
			(size 0.3048 0.3048)
			(layers "F.Cu" "F.Mask" "F.Paste")
			(net "PVCCP")
		)
		(pad "AG10" smd circle
			(at -11.82116 -0.23114 180)
			(size 0.3048 0.3048)
			(layers "F.Cu" "F.Mask" "F.Paste")
			(net "GND")
		)
		(pad "AG11" smd circle
			(at -11.05916 -0.23114 180)
			(size 0.3048 0.3048)
			(layers "F.Cu" "F.Mask" "F.Paste")
			(net "PVCCP")
		)
		(pad "AG13" smd circle
			(at -10.29716 -0.23114 180)
			(size 0.3048 0.3048)
			(layers "F.Cu" "F.Mask" "F.Paste")
			(net "PVCCP")
		)
		(pad "AG14" smd circle
			(at -9.53516 -0.23114 180)
			(size 0.3048 0.3048)
			(layers "F.Cu" "F.Mask" "F.Paste")
			(net "PVCCP")
		)
		(pad "AG16" smd circle
			(at -8.77316 -0.23114 180)
			(size 0.3048 0.3048)
			(layers "F.Cu" "F.Mask" "F.Paste")
			(net "GND")
		)
		(pad "AG17" smd circle
			(at -8.01116 -0.23114 180)
			(size 0.3048 0.3048)
			(layers "F.Cu" "F.Mask" "F.Paste")
			(net "PVCCP")
		)
		(pad "AG19" smd circle
			(at -7.24916 -0.23114 180)
			(size 0.3048 0.3048)
			(layers "F.Cu" "F.Mask" "F.Paste")
			(net "PVCCP")
		)
		(pad "AG21" smd circle
			(at -5.99948 0 180)
			(size 0.381 0.381)
			(layers "F.Cu" "F.Mask" "F.Paste")
			(net "PVCCP")
		)
		(pad "AG23" smd circle
			(at -5.20192 0 180)
			(size 0.381 0.381)
			(layers "F.Cu" "F.Mask" "F.Paste")
			(net "GND")
		)
		(pad "AG25" smd circle
			(at -4.39928 0 180)
			(size 0.381 0.381)
			(layers "F.Cu" "F.Mask" "F.Paste")
			(net "GND")
		)
		(pad "AG26" smd circle
			(at -3.60172 0 180)
			(size 0.381 0.381)
			(layers "F.Cu" "F.Mask" "F.Paste")
			(net "GND")
		)
		(pad "AG28" smd circle
			(at -2.79908 0 180)
			(size 0.381 0.381)
			(layers "F.Cu" "F.Mask" "F.Paste")
			(net "GND")
		)
		(pad "AG29" smd circle
			(at -2.00152 0 180)
			(size 0.381 0.381)
			(layers "F.Cu" "F.Mask" "F.Paste")
			(net "P1V1")
		)
		(pad "AG31" smd circle
			(at -1.19888 0 180)
			(size 0.381 0.381)
			(layers "F.Cu" "F.Mask" "F.Paste")
			(net "P1V1")
		)
		(pad "AG32" smd circle
			(at -0.40132 0 180)
			(size 0.381 0.381)
			(layers "F.Cu" "F.Mask" "F.Paste")
			(net "P1V1")
		)
		(pad "AG34" smd circle
			(at 0.40132 0 180)
			(size 0.381 0.381)
			(layers "F.Cu" "F.Mask" "F.Paste")
			(net "GND")
		)
		(pad "AG36" smd circle
			(at 1.19888 0 180)
			(size 0.381 0.381)
			(layers "F.Cu" "F.Mask" "F.Paste")
			(net "PVNN")
		)
		(pad "AG38" smd circle
			(at 2.00152 0 180)
			(size 0.381 0.381)
			(layers "F.Cu" "F.Mask" "F.Paste")
			(net "P1V0")
		)
		(pad "AG39" smd circle
			(at 2.79908 0 180)
			(size 0.381 0.381)
			(layers "F.Cu" "F.Mask" "F.Paste")
			(net "PVNN")
		)
		(pad "AG41" smd circle
			(at 3.60172 0 180)
			(size 0.381 0.381)
			(layers "F.Cu" "F.Mask" "F.Paste")
			(net "GND")
		)
		(pad "AG42" smd circle
			(at 4.39928 0 180)
			(size 0.381 0.381)
			(layers "F.Cu" "F.Mask" "F.Paste")
			(net "P3V3_RTC")
		)
		(pad "AG44" smd circle
			(at 5.20192 0 180)
			(size 0.381 0.381)
			(layers "F.Cu" "F.Mask" "F.Paste")
			(net "GND")
		)
		(pad "AG46" smd circle
			(at 5.99948 0 180)
			(size 0.381 0.381)
			(layers "F.Cu" "F.Mask" "F.Paste")
			(net "RCOMP_CORE_LVT")
		)
		(pad "AG48" smd circle
			(at 7.24916 -0.4699 180)
			(size 0.3048 0.3048)
			(layers "F.Cu" "F.Mask" "F.Paste")
			(net "GND")
		)
		(pad "AG50" smd circle
			(at 8.01116 -0.4699 180)
			(size 0.3048 0.3048)
			(layers "F.Cu" "F.Mask" "F.Paste")
			(net "CPU_UART_RXD_R")
		)
		(pad "AG51" smd circle
			(at 8.77316 -0.4699 180)
			(size 0.3048 0.3048)
			(layers "F.Cu" "F.Mask" "F.Paste")
			(net "LPC_CPU_R_CLKOUT0")
		)
		(pad "AG53" smd circle
			(at 9.53516 -0.4699 180)
			(size 0.3048 0.3048)
			(layers "F.Cu" "F.Mask" "F.Paste")
			(net "GND")
		)
		(pad "AG54" smd circle
			(at 10.29716 -0.4699 180)
			(size 0.3048 0.3048)
			(layers "F.Cu" "F.Mask" "F.Paste")
			(net "LPC_CPU_LAD0")
		)
		(pad "AG56" smd circle
			(at 11.05916 -0.4699 180)
			(size 0.3048 0.3048)
			(layers "F.Cu" "F.Mask" "F.Paste")
			(net "FLEX_CLK_SE1")
		)
		(pad "AG57" smd circle
			(at 11.82116 -0.4699 180)
			(size 0.3048 0.3048)
			(layers "F.Cu" "F.Mask" "F.Paste")
			(net "GND")
		)
		(pad "AG59" smd circle
			(at 12.58316 -0.4699 180)
			(size 0.3048 0.3048)
			(layers "F.Cu" "F.Mask" "F.Paste")
			(net "LPC_CPU_LAD3")
		)
		(pad "AG60" smd circle
			(at 13.34516 -0.4699 180)
			(size 0.3048 0.3048)
			(layers "F.Cu" "F.Mask" "F.Paste")
			(net "CPU_RSVD10")
		)
		(pad "AG63" smd circle
			(at 14.5415 -0.10414 180)
			(size 0.3048 0.3048)
			(layers "F.Cu" "F.Mask" "F.Paste")
			(net "GND")
		)
		(pad "AG64" smd circle
			(at 15.3035 -0.05334 180)
			(size 0.3048 0.3048)
			(layers "F.Cu" "F.Mask" "F.Paste")
			(net "GND")
		)
		(pad "AG66" smd oval
			(at 16.24838 -0.10414 180)
			(size 0.3429 0.254)
			(layers "F.Cu" "F.Mask" "F.Paste")
			(net "GND")
		)
		(pad "AH1" smd oval
			(at -16.24838 0.10414 180)
			(size 0.3429 0.254)
			(layers "F.Cu" "F.Mask" "F.Paste")
			(net "PVCCP")
		)
		(pad "AH3" smd circle
			(at -15.3035 0.05334 180)
			(size 0.3048 0.3048)
			(layers "F.Cu" "F.Mask" "F.Paste")
			(net "PVCCP")
		)
		(pad "AH4" smd circle
			(at -14.5415 0.10414 180)
			(size 0.3048 0.3048)
			(layers "F.Cu" "F.Mask" "F.Paste")
			(net "PVCCP")
		)
		(pad "AH7" smd circle
			(at -13.34516 0.4699 180)
			(size 0.3048 0.3048)
			(layers "F.Cu" "F.Mask" "F.Paste")
			(net "PVCCP")
		)
		(pad "AH8" smd circle
			(at -12.58316 0.4699 180)
			(size 0.3048 0.3048)
			(layers "F.Cu" "F.Mask" "F.Paste")
			(net "PVCCP")
		)
		(pad "AH10" smd circle
			(at -11.82116 0.4699 180)
			(size 0.3048 0.3048)
			(layers "F.Cu" "F.Mask" "F.Paste")
			(net "PVCCP")
		)
		(pad "AH11" smd circle
			(at -11.05916 0.4699 180)
			(size 0.3048 0.3048)
			(layers "F.Cu" "F.Mask" "F.Paste")
			(net "GND")
		)
		(pad "AH13" smd circle
			(at -10.29716 0.4699 180)
			(size 0.3048 0.3048)
			(layers "F.Cu" "F.Mask" "F.Paste")
			(net "PVCCP")
		)
		(pad "AH14" smd circle
			(at -9.53516 0.4699 180)
			(size 0.3048 0.3048)
			(layers "F.Cu" "F.Mask" "F.Paste")
			(net "PVCCP")
		)
		(pad "AH16" smd circle
			(at -8.77316 0.4699 180)
			(size 0.3048 0.3048)
			(layers "F.Cu" "F.Mask" "F.Paste")
			(net "PVCCP")
		)
		(pad "AH17" smd circle
			(at -8.01116 0.4699 180)
			(size 0.3048 0.3048)
			(layers "F.Cu" "F.Mask" "F.Paste")
			(net "GND")
		)
		(pad "AH19" smd circle
			(at -7.24916 0.4699 180)
			(size 0.3048 0.3048)
			(layers "F.Cu" "F.Mask" "F.Paste")
			(net "PVCCP")
		)
		(pad "AH48" smd circle
			(at 7.24916 0.23114 180)
			(size 0.3048 0.3048)
			(layers "F.Cu" "F.Mask" "F.Paste")
			(net "LPC_CPU_CLKRUN#")
		)
		(pad "AH50" smd circle
			(at 8.01116 0.23114 180)
			(size 0.3048 0.3048)
			(layers "F.Cu" "F.Mask" "F.Paste")
			(net "CPU_UART_TXD_R")
		)
		(pad "AH51" smd circle
			(at 8.77316 0.23114 180)
			(size 0.3048 0.3048)
			(layers "F.Cu" "F.Mask" "F.Paste")
			(net "BD_ID_1")
		)
		(pad "AH53" smd circle
			(at 9.53516 0.23114 180)
			(size 0.3048 0.3048)
			(layers "F.Cu" "F.Mask" "F.Paste")
			(net "GND")
		)
		(pad "AH54" smd circle
			(at 10.29716 0.23114 180)
			(size 0.3048 0.3048)
			(layers "F.Cu" "F.Mask" "F.Paste")
			(net "CPU_DIAG_LED")
		)
		(pad "AH56" smd circle
			(at 11.05916 0.23114 180)
			(size 0.3048 0.3048)
			(layers "F.Cu" "F.Mask" "F.Paste")
			(net "LPC_CPU_FRAME#")
		)
		(pad "AH57" smd circle
			(at 11.82116 0.23114 180)
			(size 0.3048 0.3048)
			(layers "F.Cu" "F.Mask" "F.Paste")
			(net "GND")
		)
		(pad "AH59" smd circle
			(at 12.58316 0.23114 180)
			(size 0.3048 0.3048)
			(layers "F.Cu" "F.Mask" "F.Paste")
			(net "FLEX_CLK_SE0")
		)
		(pad "AH60" smd circle
			(at 13.34516 0.23114 180)
			(size 0.3048 0.3048)
			(layers "F.Cu" "F.Mask" "F.Paste")
			(net "CORE_PWROK_R")
		)
		(pad "AH62" smd circle
			(at 14.06398 0.4064 180)
			(size 0.3048 0.3048)
			(layers "F.Cu" "F.Mask" "F.Paste")
			(net "GND")
		)
		(pad "AJ2" smd circle
			(at -15.80642 0.8636 180)
			(size 0.3048 0.3048)
			(layers "F.Cu" "F.Mask" "F.Paste")
			(net "PVCCP")
		)
		(pad "AJ4" smd circle
			(at -14.75232 0.78232 180)
			(size 0.3048 0.3048)
			(layers "F.Cu" "F.Mask" "F.Paste")
			(net "PVCCP")
		)
		(pad "AJ5" smd circle
			(at -14.06398 0.61468 180)
			(size 0.3048 0.3048)
			(layers "F.Cu" "F.Mask" "F.Paste")
			(net "PVCCP")
		)
		(pad "AJ21" smd circle
			(at -5.99948 0.8001 180)
			(size 0.381 0.381)
			(layers "F.Cu" "F.Mask" "F.Paste")
			(net "PVCCP")
		)
		(pad "AJ23" smd circle
			(at -5.20192 0.8001 180)
			(size 0.381 0.381)
			(layers "F.Cu" "F.Mask" "F.Paste")
			(net "PVCCP")
		)
		(pad "AJ25" smd circle
			(at -4.39928 0.8001 180)
			(size 0.381 0.381)
			(layers "F.Cu" "F.Mask" "F.Paste")
			(net "PVCCP")
		)
		(pad "AJ26" smd circle
			(at -3.60172 0.8001 180)
			(size 0.381 0.381)
			(layers "F.Cu" "F.Mask" "F.Paste")
			(net "PVCCP")
		)
		(pad "AJ28" smd circle
			(at -2.79908 0.8001 180)
			(size 0.381 0.381)
			(layers "F.Cu" "F.Mask" "F.Paste")
			(net "GND")
		)
		(pad "AJ29" smd circle
			(at -2.00152 0.8001 180)
			(size 0.381 0.381)
			(layers "F.Cu" "F.Mask" "F.Paste")
			(net "P1V0")
		)
		(pad "AJ31" smd circle
			(at -1.19888 0.8001 180)
			(size 0.381 0.381)
			(layers "F.Cu" "F.Mask" "F.Paste")
			(net "VCCRAMCPUSI0GT_MOD3_1P03")
		)
		(pad "AJ32" smd circle
			(at -0.40132 0.8001 180)
			(size 0.381 0.381)
			(layers "F.Cu" "F.Mask" "F.Paste")
			(net "GND")
		)
		(pad "AJ34" smd circle
			(at 0.40132 0.8001 180)
			(size 0.381 0.381)
			(layers "F.Cu" "F.Mask" "F.Paste")
			(net "TP_CPU_RSVD9")
		)
		(pad "AJ36" smd circle
			(at 1.19888 0.8001 180)
			(size 0.381 0.381)
			(layers "F.Cu" "F.Mask" "F.Paste")
			(net "PVNN")
		)
		(pad "AJ38" smd circle
			(at 2.00152 0.8001 180)
			(size 0.381 0.381)
			(layers "F.Cu" "F.Mask" "F.Paste")
			(net "P1V0")
		)
		(pad "AJ39" smd circle
			(at 2.79908 0.8001 180)
			(size 0.381 0.381)
			(layers "F.Cu" "F.Mask" "F.Paste")
			(net "PVNN")
		)
		(pad "AJ41" smd circle
			(at 3.60172 0.8001 180)
			(size 0.381 0.381)
			(layers "F.Cu" "F.Mask" "F.Paste")
			(net "P1V8")
		)
		(pad "AJ42" smd circle
			(at 4.39928 0.8001 180)
			(size 0.381 0.381)
			(layers "F.Cu" "F.Mask" "F.Paste")
			(net "P3V3")
		)
		(pad "AJ44" smd circle
			(at 5.20192 0.8001 180)
			(size 0.381 0.381)
			(layers "F.Cu" "F.Mask" "F.Paste")
			(net "GND")
		)
		(pad "AJ46" smd circle
			(at 5.99948 0.8001 180)
			(size 0.381 0.381)
			(layers "F.Cu" "F.Mask" "F.Paste")
			(net "GND")
		)
		(pad "AJ47" smd circle
			(at 6.84276 0.81534 180)
			(size 0.3048 0.3048)
			(layers "F.Cu" "F.Mask" "F.Paste")
			(net "GND")
		)
		(pad "AJ63" smd circle
			(at 14.7955 0.56388 180)
			(size 0.3048 0.3048)
			(layers "F.Cu" "F.Mask" "F.Paste")
			(net "RTC_X2PAD")
		)
		(pad "AJ65" smd circle
			(at 15.75308 0.61722 180)
			(size 0.3048 0.3048)
			(layers "F.Cu" "F.Mask" "F.Paste")
			(net "RTC_X1PAD")
		)
		(pad "AK3" smd circle
			(at -15.24762 1.28524 180)
			(size 0.3048 0.3048)
			(layers "F.Cu" "F.Mask" "F.Paste")
			(net "GND")
		)
		(pad "AK5" smd circle
			(at -14.01318 1.31572 180)
			(size 0.3048 0.3048)
			(layers "F.Cu" "F.Mask" "F.Paste")
			(net "GND")
		)
		(pad "AK20" smd circle
			(at -6.84276 1.05664 180)
			(size 0.3048 0.3048)
			(layers "F.Cu" "F.Mask" "F.Paste")
			(net "PVCCP")
		)
		(pad "AK62" smd circle
			(at 14.08176 1.11506 180)
			(size 0.3048 0.3048)
			(layers "F.Cu" "F.Mask" "F.Paste")
			(net "GND")
		)
		(pad "AK64" smd circle
			(at 15.24254 1.1049 180)
			(size 0.3048 0.3048)
			(layers "F.Cu" "F.Mask" "F.Paste")
			(net "GND")
		)
		(pad "AK66" smd oval
			(at 16.24838 1.33604 180)
			(size 0.3429 0.254)
			(layers "F.Cu" "F.Mask" "F.Paste")
			(net "GND")
		)
		(pad "AL1" smd oval
			(at -16.24838 1.54178 180)
			(size 0.3429 0.254)
			(layers "F.Cu" "F.Mask" "F.Paste")
			(net "GND")
		)
		(pad "AL2" smd circle
			(at -15.64132 1.8923 180)
			(size 0.3048 0.3048)
			(layers "F.Cu" "F.Mask" "F.Paste")
			(net "M_A_DQ28")
		)
		(pad "AL4" smd circle
			(at -14.89964 1.89738 180)
			(size 0.3048 0.3048)
			(layers "F.Cu" "F.Mask" "F.Paste")
			(net "M_A_DQ29")
		)
		(pad "AL5" smd circle
			(at -14.20368 1.9939 180)
			(size 0.3048 0.3048)
			(layers "F.Cu" "F.Mask" "F.Paste")
			(net "GND")
		)
		(pad "AL8" smd circle
			(at -12.96416 1.75514 180)
			(size 0.3048 0.3048)
			(layers "F.Cu" "F.Mask" "F.Paste")
			(net "M_A_DQ2")
		)
		(pad "AL9" smd circle
			(at -12.20216 1.75514 180)
			(size 0.3048 0.3048)
			(layers "F.Cu" "F.Mask" "F.Paste")
			(net "GND")
		)
		(pad "AL11" smd circle
			(at -11.44016 1.75514 180)
			(size 0.3048 0.3048)
			(layers "F.Cu" "F.Mask" "F.Paste")
			(net "M_A_DQS_DP0")
		)
		(pad "AL12" smd circle
			(at -10.67816 1.75514 180)
			(size 0.3048 0.3048)
			(layers "F.Cu" "F.Mask" "F.Paste")
			(net "M_A_DQS_DN0")
		)
		(pad "AL14" smd circle
			(at -9.91616 1.75514 180)
			(size 0.3048 0.3048)
			(layers "F.Cu" "F.Mask" "F.Paste")
			(net "GND")
		)
		(pad "AL15" smd circle
			(at -9.15416 1.75514 180)
			(size 0.3048 0.3048)
			(layers "F.Cu" "F.Mask" "F.Paste")
			(net "M_A_DQ5")
		)
		(pad "AL17" smd circle
			(at -8.39216 1.75514 180)
			(size 0.3048 0.3048)
			(layers "F.Cu" "F.Mask" "F.Paste")
			(net "GND")
		)
		(pad "AL18" smd circle
			(at -7.63016 1.75514 180)
			(size 0.3048 0.3048)
			(layers "F.Cu" "F.Mask" "F.Paste")
			(net "GND")
		)
		(pad "AL20" smd circle
			(at -6.92912 1.75514 180)
			(size 0.3048 0.3048)
			(layers "F.Cu" "F.Mask" "F.Paste")
			(net "GND")
		)
		(pad "AL21" smd circle
			(at -5.99948 1.6002 180)
			(size 0.381 0.381)
			(layers "F.Cu" "F.Mask" "F.Paste")
			(net "PVCCP")
		)
		(pad "AL23" smd circle
			(at -5.20192 1.6002 180)
			(size 0.381 0.381)
			(layers "F.Cu" "F.Mask" "F.Paste")
			(net "PVCCP")
		)
		(pad "AL25" smd circle
			(at -4.39928 1.6002 180)
			(size 0.381 0.381)
			(layers "F.Cu" "F.Mask" "F.Paste")
			(net "PVCCP")
		)
		(pad "AL26" smd circle
			(at -3.60172 1.6002 180)
			(size 0.381 0.381)
			(layers "F.Cu" "F.Mask" "F.Paste")
			(net "PVCCP")
		)
		(pad "AL28" smd circle
			(at -2.79908 1.6002 180)
			(size 0.381 0.381)
			(layers "F.Cu" "F.Mask" "F.Paste")
			(net "P1V0")
		)
		(pad "AL29" smd circle
			(at -2.00152 1.6002 180)
			(size 0.381 0.381)
			(layers "F.Cu" "F.Mask" "F.Paste")
			(net "GND")
		)
		(pad "AL31" smd circle
			(at -1.19888 1.6002 180)
			(size 0.381 0.381)
			(layers "F.Cu" "F.Mask" "F.Paste")
			(net "VCCCORE7VIDSI0GT_1P03")
		)
		(pad "AL32" smd circle
			(at -0.40132 1.6002 180)
			(size 0.381 0.381)
			(layers "F.Cu" "F.Mask" "F.Paste")
			(net "VCCCORE6VIDSI0GT_1P03")
		)
		(pad "AL34" smd circle
			(at 0.40132 1.6002 180)
			(size 0.381 0.381)
			(layers "F.Cu" "F.Mask" "F.Paste")
			(net "TP_CPU_RSVD8")
		)
		(pad "AL36" smd circle
			(at 1.19888 1.6002 180)
			(size 0.381 0.381)
			(layers "F.Cu" "F.Mask" "F.Paste")
			(net "PVNN")
		)
		(pad "AL38" smd circle
			(at 2.00152 1.6002 180)
			(size 0.381 0.381)
			(layers "F.Cu" "F.Mask" "F.Paste")
			(net "GND")
		)
		(pad "AL39" smd circle
			(at 2.79908 1.6002 180)
			(size 0.381 0.381)
			(layers "F.Cu" "F.Mask" "F.Paste")
			(net "PVNN")
		)
		(pad "AL41" smd circle
			(at 3.60172 1.6002 180)
			(size 0.381 0.381)
			(layers "F.Cu" "F.Mask" "F.Paste")
			(net "P1V8")
		)
		(pad "AL42" smd circle
			(at 4.39928 1.6002 180)
			(size 0.381 0.381)
			(layers "F.Cu" "F.Mask" "F.Paste")
			(net "GND")
		)
		(pad "AL44" smd circle
			(at 5.20192 1.6002 180)
			(size 0.381 0.381)
			(layers "F.Cu" "F.Mask" "F.Paste")
			(net "GND")
		)
		(pad "AL46" smd circle
			(at 5.99948 1.6002 180)
			(size 0.381 0.381)
			(layers "F.Cu" "F.Mask" "F.Paste")
			(net "MEMORY_CPU_HOT#")
		)
		(pad "AL47" smd circle
			(at 6.92912 1.51638 180)
			(size 0.3048 0.3048)
			(layers "F.Cu" "F.Mask" "F.Paste")
			(net "CTBTRIGOUT")
		)
		(pad "AL49" smd circle
			(at 7.63016 1.51638 180)
			(size 0.3048 0.3048)
			(layers "F.Cu" "F.Mask" "F.Paste")
			(net "BIOS_POST_CMPLT#")
		)
		(pad "AL50" smd circle
			(at 8.39216 1.51638 180)
			(size 0.3048 0.3048)
			(layers "F.Cu" "F.Mask" "F.Paste")
			(net "GND")
		)
		(pad "AL52" smd circle
			(at 9.15416 1.51638 180)
			(size 0.3048 0.3048)
			(layers "F.Cu" "F.Mask" "F.Paste")
			(net "IRQ_MCERR_R#")
		)
		(pad "AL53" smd circle
			(at 9.91616 1.51638 180)
			(size 0.3048 0.3048)
			(layers "F.Cu" "F.Mask" "F.Paste")
			(net "LPC_CPU_LAD2")
		)
		(pad "AL55" smd circle
			(at 10.67816 1.51638 180)
			(size 0.3048 0.3048)
			(layers "F.Cu" "F.Mask" "F.Paste")
			(net "GND")
		)
		(pad "AL56" smd circle
			(at 11.44016 1.51638 180)
			(size 0.3048 0.3048)
			(layers "F.Cu" "F.Mask" "F.Paste")
			(net "IRQ_NMI_R")
		)
		(pad "AL58" smd circle
			(at 12.20216 1.51638 180)
			(size 0.3048 0.3048)
			(layers "F.Cu" "F.Mask" "F.Paste")
			(net "SMBUS_HOST_ALRT#")
		)
		(pad "AL59" smd circle
			(at 12.96416 1.51638 180)
			(size 0.3048 0.3048)
			(layers "F.Cu" "F.Mask" "F.Paste")
			(net "GND")
		)
		(pad "AL62" smd circle
			(at 14.20368 1.80848 180)
			(size 0.3048 0.3048)
			(layers "F.Cu" "F.Mask" "F.Paste")
			(net "CPU_ERR_N1")
		)
		(pad "AL63" smd circle
			(at 14.89964 1.71704 180)
			(size 0.3048 0.3048)
			(layers "F.Cu" "F.Mask" "F.Paste")
			(net "CPU_ERR_N2")
		)
		(pad "AL65" smd circle
			(at 15.63878 1.68402 180)
			(size 0.3048 0.3048)
			(layers "F.Cu" "F.Mask" "F.Paste")
			(net "CPU_ERR_N0")
		)
		(pad "AM8" smd circle
			(at -12.96416 2.45618 180)
			(size 0.3048 0.3048)
			(layers "F.Cu" "F.Mask" "F.Paste")
			(net "M_A_DQ3")
		)
		(pad "AM9" smd circle
			(at -12.20216 2.45618 180)
			(size 0.3048 0.3048)
			(layers "F.Cu" "F.Mask" "F.Paste")
			(net "M_A_DQ7")
		)
		(pad "AM11" smd circle
			(at -11.44016 2.45618 180)
			(size 0.3048 0.3048)
			(layers "F.Cu" "F.Mask" "F.Paste")
			(net "M_A_DQ6")
		)
		(pad "AM12" smd circle
			(at -10.67816 2.45618 180)
			(size 0.3048 0.3048)
			(layers "F.Cu" "F.Mask" "F.Paste")
			(net "GND")
		)
		(pad "AM14" smd circle
			(at -9.91616 2.45618 180)
			(size 0.3048 0.3048)
			(layers "F.Cu" "F.Mask" "F.Paste")
			(net "M_A_DQ1")
		)
		(pad "AM15" smd circle
			(at -9.15416 2.45618 180)
			(size 0.3048 0.3048)
			(layers "F.Cu" "F.Mask" "F.Paste")
			(net "M_A_DQ0")
		)
		(pad "AM17" smd circle
			(at -8.39216 2.45618 180)
			(size 0.3048 0.3048)
			(layers "F.Cu" "F.Mask" "F.Paste")
			(net "M_A_DQ4")
		)
		(pad "AM18" smd circle
			(at -7.63016 2.45618 180)
			(size 0.3048 0.3048)
			(layers "F.Cu" "F.Mask" "F.Paste")
			(net "GND")
		)
		(pad "AM20" smd circle
			(at -6.92912 2.45618 180)
			(size 0.3048 0.3048)
			(layers "F.Cu" "F.Mask" "F.Paste")
			(net "GND")
		)
		(pad "AM21" smd circle
			(at -5.99948 2.4003 180)
			(size 0.381 0.381)
			(layers "F.Cu" "F.Mask" "F.Paste")
			(net "GND")
		)
		(pad "AM23" smd circle
			(at -5.20192 2.4003 180)
			(size 0.381 0.381)
			(layers "F.Cu" "F.Mask" "F.Paste")
			(net "GND")
		)
		(pad "AM25" smd circle
			(at -4.39928 2.4003 180)
			(size 0.381 0.381)
			(layers "F.Cu" "F.Mask" "F.Paste")
			(net "PVNN")
		)
		(pad "AM26" smd circle
			(at -3.60172 2.4003 180)
			(size 0.381 0.381)
			(layers "F.Cu" "F.Mask" "F.Paste")
			(net "PVNN")
		)
		(pad "AM28" smd circle
			(at -2.79908 2.4003 180)
			(size 0.381 0.381)
			(layers "F.Cu" "F.Mask" "F.Paste")
			(net "PVNN")
		)
		(pad "AM29" smd circle
			(at -2.00152 2.4003 180)
			(size 0.381 0.381)
			(layers "F.Cu" "F.Mask" "F.Paste")
			(net "PVNN")
		)
		(pad "AM31" smd circle
			(at -1.19888 2.4003 180)
			(size 0.381 0.381)
			(layers "F.Cu" "F.Mask" "F.Paste")
			(net "PVNN")
		)
		(pad "AM32" smd circle
			(at -0.40132 2.4003 180)
			(size 0.381 0.381)
			(layers "F.Cu" "F.Mask" "F.Paste")
			(net "PVNN")
		)
		(pad "AM34" smd circle
			(at 0.40132 2.4003 180)
			(size 0.381 0.381)
			(layers "F.Cu" "F.Mask" "F.Paste")
			(net "PVNN")
		)
		(pad "AM36" smd circle
			(at 1.19888 2.4003 180)
			(size 0.381 0.381)
			(layers "F.Cu" "F.Mask" "F.Paste")
			(net "PVNN")
		)
		(pad "AM38" smd circle
			(at 2.00152 2.4003 180)
			(size 0.381 0.381)
			(layers "F.Cu" "F.Mask" "F.Paste")
			(net "PVNN")
		)
		(pad "AM39" smd circle
			(at 2.79908 2.4003 180)
			(size 0.381 0.381)
			(layers "F.Cu" "F.Mask" "F.Paste")
			(net "PVNN")
		)
		(pad "AM41" smd circle
			(at 3.60172 2.4003 180)
			(size 0.381 0.381)
			(layers "F.Cu" "F.Mask" "F.Paste")
			(net "PVNN")
		)
		(pad "AM42" smd circle
			(at 4.39928 2.4003 180)
			(size 0.381 0.381)
			(layers "F.Cu" "F.Mask" "F.Paste")
			(net "PVNN")
		)
		(pad "AM44" smd circle
			(at 5.20192 2.4003 180)
			(size 0.381 0.381)
			(layers "F.Cu" "F.Mask" "F.Paste")
			(net "GND")
		)
		(pad "AM46" smd circle
			(at 5.99948 2.4003 180)
			(size 0.381 0.381)
			(layers "F.Cu" "F.Mask" "F.Paste")
			(net "GND")
		)
		(pad "AM47" smd circle
			(at 6.92912 2.21742 180)
			(size 0.3048 0.3048)
			(layers "F.Cu" "F.Mask" "F.Paste")
			(net "CTBTRIGINOUT")
		)
		(pad "AM49" smd circle
			(at 7.63016 2.21742 180)
			(size 0.3048 0.3048)
			(layers "F.Cu" "F.Mask" "F.Paste")
			(net "LPC_CPU_R_CLKOUT1")
		)
		(pad "AM50" smd circle
			(at 8.39216 2.21742 180)
			(size 0.3048 0.3048)
			(layers "F.Cu" "F.Mask" "F.Paste")
			(net "GND")
		)
		(pad "AM52" smd circle
			(at 9.15416 2.21742 180)
			(size 0.3048 0.3048)
			(layers "F.Cu" "F.Mask" "F.Paste")
			(net "IRQ_CPU_IERR#")
		)
		(pad "AM53" smd circle
			(at 9.91616 2.21742 180)
			(size 0.3048 0.3048)
			(layers "F.Cu" "F.Mask" "F.Paste")
			(net "LPC_CPU_LAD1")
		)
		(pad "AM55" smd circle
			(at 10.67816 2.21742 180)
			(size 0.3048 0.3048)
			(layers "F.Cu" "F.Mask" "F.Paste")
			(net "GND")
		)
		(pad "AM56" smd circle
			(at 11.44016 2.21742 180)
			(size 0.3048 0.3048)
			(layers "F.Cu" "F.Mask" "F.Paste")
			(net "CLK_14M_CPU")
		)
		(pad "AM58" smd circle
			(at 12.20216 2.21742 180)
			(size 0.3048 0.3048)
			(layers "F.Cu" "F.Mask" "F.Paste")
			(net "PMU_RESETBUTTON_R#")
		)
		(pad "AM59" smd circle
			(at 12.96416 2.21742 180)
			(size 0.3048 0.3048)
			(layers "F.Cu" "F.Mask" "F.Paste")
			(net "GND")
		)
		(pad "AN2" smd circle
			(at -15.63878 2.8194 180)
			(size 0.3048 0.3048)
			(layers "F.Cu" "F.Mask" "F.Paste")
			(net "M_A_DQ25")
		)
		(pad "AN4" smd circle
			(at -14.89964 2.78638 180)
			(size 0.3048 0.3048)
			(layers "F.Cu" "F.Mask" "F.Paste")
			(net "M_A_DQ24")
		)
		(pad "AN5" smd circle
			(at -14.20368 2.69494 180)
			(size 0.3048 0.3048)
			(layers "F.Cu" "F.Mask" "F.Paste")
			(net "GND")
		)
		(pad "AN47" smd circle
			(at 6.84276 2.91592 180)
			(size 0.3048 0.3048)
			(layers "F.Cu" "F.Mask" "F.Paste")
			(net "GND")
		)
		(pad "AN62" smd circle
			(at 14.20368 2.50698 180)
			(size 0.3048 0.3048)
			(layers "F.Cu" "F.Mask" "F.Paste")
			(net "SMBUS_HOST_CLK")
		)
		(pad "AN63" smd circle
			(at 14.89964 2.60604 180)
			(size 0.3048 0.3048)
			(layers "F.Cu" "F.Mask" "F.Paste")
			(net "SMBUS_SW_R_EN")
		)
		(pad "AN65" smd circle
			(at 15.64132 2.61112 180)
			(size 0.3048 0.3048)
			(layers "F.Cu" "F.Mask" "F.Paste")
			(net "SMBUS_PECI_DATA")
		)
		(pad "AN66" smd oval
			(at 16.24838 2.96164 180)
			(size 0.3429 0.254)
			(layers "F.Cu" "F.Mask" "F.Paste")
			(net "GND")
		)
		(pad "AP1" smd oval
			(at -16.24838 3.16738 180)
			(size 0.3429 0.254)
			(layers "F.Cu" "F.Mask" "F.Paste")
			(net "M_A_DQS_DN3")
		)
		(pad "AP3" smd circle
			(at -15.24254 3.39852 180)
			(size 0.3048 0.3048)
			(layers "F.Cu" "F.Mask" "F.Paste")
			(net "M_A_DQS_DP3")
		)
		(pad "AP5" smd circle
			(at -14.08176 3.38836 180)
			(size 0.3048 0.3048)
			(layers "F.Cu" "F.Mask" "F.Paste")
			(net "GND")
		)
		(pad "AP20" smd circle
			(at -6.84276 3.15722 180)
			(size 0.3048 0.3048)
			(layers "F.Cu" "F.Mask" "F.Paste")
			(net "TP_CPU_RSVD7")
		)
		(pad "AP21" smd circle
			(at -5.99948 3.2004 180)
			(size 0.381 0.381)
			(layers "F.Cu" "F.Mask" "F.Paste")
			(net "TP_CPU_RSVD6")
		)
		(pad "AP23" smd circle
			(at -5.20192 3.2004 180)
			(size 0.381 0.381)
			(layers "F.Cu" "F.Mask" "F.Paste")
			(net "GND")
		)
		(pad "AP25" smd circle
			(at -4.39928 3.2004 180)
			(size 0.381 0.381)
			(layers "F.Cu" "F.Mask" "F.Paste")
			(net "GND")
		)
		(pad "AP26" smd circle
			(at -3.60172 3.2004 180)
			(size 0.381 0.381)
			(layers "F.Cu" "F.Mask" "F.Paste")
			(net "GND")
		)
		(pad "AP28" smd circle
			(at -2.79908 3.2004 180)
			(size 0.381 0.381)
			(layers "F.Cu" "F.Mask" "F.Paste")
			(net "GND")
		)
		(pad "AP29" smd circle
			(at -2.00152 3.2004 180)
			(size 0.381 0.381)
			(layers "F.Cu" "F.Mask" "F.Paste")
			(net "GND")
		)
		(pad "AP31" smd circle
			(at -1.19888 3.2004 180)
			(size 0.381 0.381)
			(layers "F.Cu" "F.Mask" "F.Paste")
			(net "GND")
		)
		(pad "AP32" smd circle
			(at -0.40132 3.2004 180)
			(size 0.381 0.381)
			(layers "F.Cu" "F.Mask" "F.Paste")
			(net "GND")
		)
		(pad "AP34" smd circle
			(at 0.40132 3.2004 180)
			(size 0.381 0.381)
			(layers "F.Cu" "F.Mask" "F.Paste")
			(net "GND")
		)
		(pad "AP36" smd circle
			(at 1.19888 3.2004 180)
			(size 0.381 0.381)
			(layers "F.Cu" "F.Mask" "F.Paste")
			(net "GND")
		)
		(pad "AP38" smd circle
			(at 2.00152 3.2004 180)
			(size 0.381 0.381)
			(layers "F.Cu" "F.Mask" "F.Paste")
			(net "GND")
		)
		(pad "AP39" smd circle
			(at 2.79908 3.2004 180)
			(size 0.381 0.381)
			(layers "F.Cu" "F.Mask" "F.Paste")
			(net "GND")
		)
		(pad "AP41" smd circle
			(at 3.60172 3.2004 180)
			(size 0.381 0.381)
			(layers "F.Cu" "F.Mask" "F.Paste")
			(net "GND")
		)
		(pad "AP42" smd circle
			(at 4.39928 3.2004 180)
			(size 0.381 0.381)
			(layers "F.Cu" "F.Mask" "F.Paste")
			(net "GND")
		)
		(pad "AP44" smd circle
			(at 5.20192 3.2004 180)
			(size 0.381 0.381)
			(layers "F.Cu" "F.Mask" "F.Paste")
			(net "GND")
		)
		(pad "AP46" smd circle
			(at 5.99948 3.2004 180)
			(size 0.381 0.381)
			(layers "F.Cu" "F.Mask" "F.Paste")
			(net "GND")
		)
		(pad "AP62" smd circle
			(at 14.01318 3.18516 180)
			(size 0.3048 0.3048)
			(layers "F.Cu" "F.Mask" "F.Paste")
			(net "SMBUS_HOST_DATA")
		)
		(pad "AP64" smd circle
			(at 15.24762 3.21564 180)
			(size 0.3048 0.3048)
			(layers "F.Cu" "F.Mask" "F.Paste")
			(net "GND")
		)
		(pad "AR2" smd circle
			(at -15.75308 3.8862 180)
			(size 0.3048 0.3048)
			(layers "F.Cu" "F.Mask" "F.Paste")
			(net "M_A_DQ30")
		)
		(pad "AR4" smd circle
			(at -14.7955 3.937 180)
			(size 0.3048 0.3048)
			(layers "F.Cu" "F.Mask" "F.Paste")
			(net "M_A_DQ31")
		)
		(pad "AR7" smd circle
			(at -13.34516 3.74142 180)
			(size 0.3048 0.3048)
			(layers "F.Cu" "F.Mask" "F.Paste")
			(net "M_A_DQS_DN1")
		)
		(pad "AR8" smd circle
			(at -12.58316 3.74142 180)
			(size 0.3048 0.3048)
			(layers "F.Cu" "F.Mask" "F.Paste")
			(net "GND")
		)
		(pad "AR10" smd circle
			(at -11.82116 3.74142 180)
			(size 0.3048 0.3048)
			(layers "F.Cu" "F.Mask" "F.Paste")
			(net "M_A_DQ15")
		)
		(pad "AR11" smd circle
			(at -11.05916 3.74142 180)
			(size 0.3048 0.3048)
			(layers "F.Cu" "F.Mask" "F.Paste")
			(net "M_A_DQ11")
		)
		(pad "AR13" smd circle
			(at -10.29716 3.74142 180)
			(size 0.3048 0.3048)
			(layers "F.Cu" "F.Mask" "F.Paste")
			(net "GND")
		)
		(pad "AR14" smd circle
			(at -9.53516 3.74142 180)
			(size 0.3048 0.3048)
			(layers "F.Cu" "F.Mask" "F.Paste")
			(net "M_A_DQ8")
		)
		(pad "AR16" smd circle
			(at -8.77316 3.74142 180)
			(size 0.3048 0.3048)
			(layers "F.Cu" "F.Mask" "F.Paste")
			(net "M_A_DQ12")
		)
		(pad "AR17" smd circle
			(at -8.01116 3.74142 180)
			(size 0.3048 0.3048)
			(layers "F.Cu" "F.Mask" "F.Paste")
			(net "GND")
		)
		(pad "AR19" smd circle
			(at -7.24916 3.74142 180)
			(size 0.3048 0.3048)
			(layers "F.Cu" "F.Mask" "F.Paste")
			(net "GND")
		)
		(pad "AR48" smd circle
			(at 7.24916 3.50266 180)
			(size 0.3048 0.3048)
			(layers "F.Cu" "F.Mask" "F.Paste")
			(net "PD_USB_OBSP")
		)
		(pad "AR50" smd circle
			(at 8.01116 3.50266 180)
			(size 0.3048 0.3048)
			(layers "F.Cu" "F.Mask" "F.Paste")
			(net "GND")
		)
		(pad "AR51" smd circle
			(at 8.77316 3.50266 180)
			(size 0.3048 0.3048)
			(layers "F.Cu" "F.Mask" "F.Paste")
			(net "Net_84")
		)
		(pad "AR53" smd circle
			(at 9.53516 3.50266 180)
			(size 0.3048 0.3048)
			(layers "F.Cu" "F.Mask" "F.Paste")
			(net "Net_83")
		)
		(pad "AR54" smd circle
			(at 10.29716 3.50266 180)
			(size 0.3048 0.3048)
			(layers "F.Cu" "F.Mask" "F.Paste")
			(net "Net_85")
		)
		(pad "AR56" smd circle
			(at 11.05916 3.50266 180)
			(size 0.3048 0.3048)
			(layers "F.Cu" "F.Mask" "F.Paste")
			(net "GND")
		)
		(pad "AR57" smd circle
			(at 11.82116 3.50266 180)
			(size 0.3048 0.3048)
			(layers "F.Cu" "F.Mask" "F.Paste")
			(net "XDP_DFX_PORT3")
		)
		(pad "AR59" smd circle
			(at 12.58316 3.50266 180)
			(size 0.3048 0.3048)
			(layers "F.Cu" "F.Mask" "F.Paste")
			(net "XDP_DFX_PORT15")
		)
		(pad "AR60" smd circle
			(at 13.34516 3.50266 180)
			(size 0.3048 0.3048)
			(layers "F.Cu" "F.Mask" "F.Paste")
			(net "GND")
		)
		(pad "AR62" smd circle
			(at 14.06398 3.88874 180)
			(size 0.3048 0.3048)
			(layers "F.Cu" "F.Mask" "F.Paste")
			(net "GND")
		)
		(pad "AR63" smd circle
			(at 14.75232 3.71856 180)
			(size 0.3048 0.3048)
			(layers "F.Cu" "F.Mask" "F.Paste")
			(net "SMB_CLK1_SPKR")
		)
		(pad "AR65" smd circle
			(at 15.80642 3.63982 180)
			(size 0.3048 0.3048)
			(layers "F.Cu" "F.Mask" "F.Paste")
			(net "SMBUS_PECI_CLK")
		)
		(pad "AT5" smd circle
			(at -14.06398 4.09448 180)
			(size 0.3048 0.3048)
			(layers "F.Cu" "F.Mask" "F.Paste")
			(net "GND")
		)
		(pad "AT7" smd circle
			(at -13.34516 4.44246 180)
			(size 0.3048 0.3048)
			(layers "F.Cu" "F.Mask" "F.Paste")
			(net "M_A_DQS_DP1")
		)
		(pad "AT8" smd circle
			(at -12.58316 4.44246 180)
			(size 0.3048 0.3048)
			(layers "F.Cu" "F.Mask" "F.Paste")
			(net "M_A_DQ14")
		)
		(pad "AT10" smd circle
			(at -11.82116 4.44246 180)
			(size 0.3048 0.3048)
			(layers "F.Cu" "F.Mask" "F.Paste")
			(net "M_A_DQ10")
		)
		(pad "AT11" smd circle
			(at -11.05916 4.44246 180)
			(size 0.3048 0.3048)
			(layers "F.Cu" "F.Mask" "F.Paste")
			(net "GND")
		)
		(pad "AT13" smd circle
			(at -10.29716 4.44246 180)
			(size 0.3048 0.3048)
			(layers "F.Cu" "F.Mask" "F.Paste")
			(net "M_A_DQ9")
		)
		(pad "AT14" smd circle
			(at -9.53516 4.44246 180)
			(size 0.3048 0.3048)
			(layers "F.Cu" "F.Mask" "F.Paste")
			(net "M_A_DQ13")
		)
		(pad "AT16" smd circle
			(at -8.77316 4.44246 180)
			(size 0.3048 0.3048)
			(layers "F.Cu" "F.Mask" "F.Paste")
			(net "GND")
		)
		(pad "AT17" smd circle
			(at -8.01116 4.44246 180)
			(size 0.3048 0.3048)
			(layers "F.Cu" "F.Mask" "F.Paste")
			(net "GND")
		)
		(pad "AT19" smd circle
			(at -7.24916 4.44246 180)
			(size 0.3048 0.3048)
			(layers "F.Cu" "F.Mask" "F.Paste")
			(net "GND")
		)
		(pad "AT21" smd circle
			(at -5.99948 4.0005 180)
			(size 0.381 0.381)
			(layers "F.Cu" "F.Mask" "F.Paste")
			(net "P1V0")
		)
		(pad "AT23" smd circle
			(at -5.20192 4.0005 180)
			(size 0.381 0.381)
			(layers "F.Cu" "F.Mask" "F.Paste")
			(net "P1V0")
		)
		(pad "AT25" smd circle
			(at -4.39928 4.0005 180)
			(size 0.381 0.381)
			(layers "F.Cu" "F.Mask" "F.Paste")
			(net "P1V0")
		)
		(pad "AT26" smd circle
			(at -3.60172 4.0005 180)
			(size 0.381 0.381)
			(layers "F.Cu" "F.Mask" "F.Paste")
			(net "P1V0")
		)
		(pad "AT28" smd circle
			(at -2.79908 4.0005 180)
			(size 0.381 0.381)
			(layers "F.Cu" "F.Mask" "F.Paste")
			(net "P1V0")
		)
		(pad "AT29" smd circle
			(at -2.00152 4.0005 180)
			(size 0.381 0.381)
			(layers "F.Cu" "F.Mask" "F.Paste")
			(net "VCCCLKDDR0")
		)
		(pad "AT31" smd circle
			(at -1.19888 4.0005 180)
			(size 0.381 0.381)
			(layers "F.Cu" "F.Mask" "F.Paste")
			(net "P1V35")
		)
		(pad "AT32" smd circle
			(at -0.40132 4.0005 180)
			(size 0.381 0.381)
			(layers "F.Cu" "F.Mask" "F.Paste")
			(net "VCCACKDDR0")
		)
		(pad "AT34" smd circle
			(at 0.40132 4.0005 180)
			(size 0.381 0.381)
			(layers "F.Cu" "F.Mask" "F.Paste")
			(net "TP_CPU_RSVD2")
		)
		(pad "AT36" smd circle
			(at 1.19888 4.0005 180)
			(size 0.381 0.381)
			(layers "F.Cu" "F.Mask" "F.Paste")
			(net "P1V0")
		)
		(pad "AT38" smd circle
			(at 2.00152 4.0005 180)
			(size 0.381 0.381)
			(layers "F.Cu" "F.Mask" "F.Paste")
			(net "P1V0")
		)
		(pad "AT39" smd circle
			(at 2.79908 4.0005 180)
			(size 0.381 0.381)
			(layers "F.Cu" "F.Mask" "F.Paste")
			(net "P1V0")
		)
		(pad "AT41" smd circle
			(at 3.60172 4.0005 180)
			(size 0.381 0.381)
			(layers "F.Cu" "F.Mask" "F.Paste")
			(net "P1V0_STBY")
		)
		(pad "AT42" smd circle
			(at 4.39928 4.0005 180)
			(size 0.381 0.381)
			(layers "F.Cu" "F.Mask" "F.Paste")
			(net "P1V0")
		)
		(pad "AT44" smd circle
			(at 5.20192 4.0005 180)
			(size 0.381 0.381)
			(layers "F.Cu" "F.Mask" "F.Paste")
			(net "GND")
		)
		(pad "AT46" smd circle
			(at 5.99948 4.0005 180)
			(size 0.381 0.381)
			(layers "F.Cu" "F.Mask" "F.Paste")
			(net "PD_USB_RCOMP")
		)
		(pad "AT48" smd circle
			(at 7.24916 4.2037 180)
			(size 0.3048 0.3048)
			(layers "F.Cu" "F.Mask" "F.Paste")
			(net "PD_USB_RCOMP")
		)
		(pad "AT50" smd circle
			(at 8.01116 4.2037 180)
			(size 0.3048 0.3048)
			(layers "F.Cu" "F.Mask" "F.Paste")
			(net "IRQ_CPU_SERIAL")
		)
		(pad "AT51" smd circle
			(at 8.77316 4.2037 180)
			(size 0.3048 0.3048)
			(layers "F.Cu" "F.Mask" "F.Paste")
			(net "TP_CPU_RSVD1")
		)
		(pad "AT53" smd circle
			(at 9.53516 4.2037 180)
			(size 0.3048 0.3048)
			(layers "F.Cu" "F.Mask" "F.Paste")
			(net "GND")
		)
		(pad "AT54" smd circle
			(at 10.29716 4.2037 180)
			(size 0.3048 0.3048)
			(layers "F.Cu" "F.Mask" "F.Paste")
			(net "XDP_DFX_PORT4")
		)
		(pad "AT56" smd circle
			(at 11.05916 4.2037 180)
			(size 0.3048 0.3048)
			(layers "F.Cu" "F.Mask" "F.Paste")
			(net "CPU_THERMTRIP#")
		)
		(pad "AT57" smd circle
			(at 11.82116 4.2037 180)
			(size 0.3048 0.3048)
			(layers "F.Cu" "F.Mask" "F.Paste")
			(net "GND")
		)
		(pad "AT59" smd circle
			(at 12.58316 4.2037 180)
			(size 0.3048 0.3048)
			(layers "F.Cu" "F.Mask" "F.Paste")
			(net "XDP_DFX_PORT11")
		)
		(pad "AT60" smd circle
			(at 13.34516 4.2037 180)
			(size 0.3048 0.3048)
			(layers "F.Cu" "F.Mask" "F.Paste")
			(net "XDP_DFX_PORT9")
		)
		(pad "AT63" smd circle
			(at 14.5415 4.39928 180)
			(size 0.3048 0.3048)
			(layers "F.Cu" "F.Mask" "F.Paste")
			(net "BD_ID_0")
		)
		(pad "AT64" smd circle
			(at 15.3035 4.45008 180)
			(size 0.3048 0.3048)
			(layers "F.Cu" "F.Mask" "F.Paste")
			(net "GND")
		)
		(pad "AT66" smd oval
			(at 16.24838 4.39928 180)
			(size 0.3429 0.254)
			(layers "F.Cu" "F.Mask" "F.Paste")
			(net "GND")
		)
		(pad "AU1" smd oval
			(at -16.24838 4.60756 180)
			(size 0.3429 0.254)
			(layers "F.Cu" "F.Mask" "F.Paste")
			(net "M_A_DQ26")
		)
		(pad "AU3" smd circle
			(at -15.3035 4.55676 180)
			(size 0.3048 0.3048)
			(layers "F.Cu" "F.Mask" "F.Paste")
			(net "M_A_DQ27")
		)
		(pad "AU4" smd circle
			(at -14.5415 4.60756 180)
			(size 0.3048 0.3048)
			(layers "F.Cu" "F.Mask" "F.Paste")
			(net "GND")
		)
		(pad "AU21" smd circle
			(at -5.99948 4.8006 180)
			(size 0.381 0.381)
			(layers "F.Cu" "F.Mask" "F.Paste")
			(net "P1V0")
		)
		(pad "AU23" smd circle
			(at -5.20192 4.8006 180)
			(size 0.381 0.381)
			(layers "F.Cu" "F.Mask" "F.Paste")
			(net "P1V0")
		)
		(pad "AU25" smd circle
			(at -4.39928 4.8006 180)
			(size 0.381 0.381)
			(layers "F.Cu" "F.Mask" "F.Paste")
			(net "P1V0")
		)
		(pad "AU26" smd circle
			(at -3.60172 4.8006 180)
			(size 0.381 0.381)
			(layers "F.Cu" "F.Mask" "F.Paste")
			(net "P1V0")
		)
		(pad "AU28" smd circle
			(at -2.79908 4.8006 180)
			(size 0.381 0.381)
			(layers "F.Cu" "F.Mask" "F.Paste")
			(net "P1V0")
		)
		(pad "AU29" smd circle
			(at -2.00152 4.8006 180)
			(size 0.381 0.381)
			(layers "F.Cu" "F.Mask" "F.Paste")
			(net "VCCCLKDDR0")
		)
		(pad "AU31" smd circle
			(at -1.19888 4.8006 180)
			(size 0.381 0.381)
			(layers "F.Cu" "F.Mask" "F.Paste")
			(net "VCCA_PLLDDR0_AVN")
		)
		(pad "AU32" smd circle
			(at -0.40132 4.8006 180)
			(size 0.381 0.381)
			(layers "F.Cu" "F.Mask" "F.Paste")
			(net "VCCACKDDR0")
		)
		(pad "AU34" smd circle
			(at 0.40132 4.8006 180)
			(size 0.381 0.381)
			(layers "F.Cu" "F.Mask" "F.Paste")
			(net "TP_CPU_RSVD0")
		)
		(pad "AU36" smd circle
			(at 1.19888 4.8006 180)
			(size 0.381 0.381)
			(layers "F.Cu" "F.Mask" "F.Paste")
			(net "P1V0")
		)
		(pad "AU38" smd circle
			(at 2.00152 4.8006 180)
			(size 0.381 0.381)
			(layers "F.Cu" "F.Mask" "F.Paste")
			(net "P1V0")
		)
		(pad "AU39" smd circle
			(at 2.79908 4.8006 180)
			(size 0.381 0.381)
			(layers "F.Cu" "F.Mask" "F.Paste")
			(net "P1V0")
		)
		(pad "AU41" smd circle
			(at 3.60172 4.8006 180)
			(size 0.381 0.381)
			(layers "F.Cu" "F.Mask" "F.Paste")
			(net "P1V0")
		)
		(pad "AU42" smd circle
			(at 4.39928 4.8006 180)
			(size 0.381 0.381)
			(layers "F.Cu" "F.Mask" "F.Paste")
			(net "P3V3_CPU")
		)
		(pad "AU44" smd circle
			(at 5.20192 4.8006 180)
			(size 0.381 0.381)
			(layers "F.Cu" "F.Mask" "F.Paste")
			(net "GND")
		)
		(pad "AU46" smd circle
			(at 5.99948 4.8006 180)
			(size 0.381 0.381)
			(layers "F.Cu" "F.Mask" "F.Paste")
			(net "P1V8_STBY")
		)
		(pad "AU47" smd circle
			(at 6.72592 4.8006 180)
			(size 0.3048 0.3048)
			(layers "F.Cu" "F.Mask" "F.Paste")
			(net "P1V8_STBY")
		)
		(pad "AU62" smd circle
			(at 14.06398 4.90982 180)
			(size 0.3048 0.3048)
			(layers "F.Cu" "F.Mask" "F.Paste")
			(net "GND")
		)
		(pad "AV2" smd circle
			(at -15.80642 5.36702 180)
			(size 0.3048 0.3048)
			(layers "F.Cu" "F.Mask" "F.Paste")
			(net "GND")
		)
		(pad "AV4" smd circle
			(at -14.75232 5.28574 180)
			(size 0.3048 0.3048)
			(layers "F.Cu" "F.Mask" "F.Paste")
			(net "GND")
		)
		(pad "AV5" smd circle
			(at -14.06398 5.1181 180)
			(size 0.3048 0.3048)
			(layers "F.Cu" "F.Mask" "F.Paste")
			(net "GND")
		)
		(pad "AV63" smd circle
			(at 14.7955 5.0673 180)
			(size 0.3048 0.3048)
			(layers "F.Cu" "F.Mask" "F.Paste")
			(net "XDP_DFX_PORT_CLK0")
		)
		(pad "AV65" smd circle
			(at 15.75308 5.12064 180)
			(size 0.3048 0.3048)
			(layers "F.Cu" "F.Mask" "F.Paste")
			(net "XDP_DFX_PORT_CLK1")
		)
		(pad "AW3" smd circle
			(at -15.24762 5.78866 180)
			(size 0.3048 0.3048)
			(layers "F.Cu" "F.Mask" "F.Paste")
			(net "M_A_ECC4")
		)
		(pad "AW5" smd circle
			(at -14.01318 5.81914 180)
			(size 0.3048 0.3048)
			(layers "F.Cu" "F.Mask" "F.Paste")
			(net "GND")
		)
		(pad "AW8" smd circle
			(at -12.96416 5.7277 180)
			(size 0.3048 0.3048)
			(layers "F.Cu" "F.Mask" "F.Paste")
			(net "M_A_DQ20")
		)
		(pad "AW9" smd circle
			(at -12.20216 5.7277 180)
			(size 0.3048 0.3048)
			(layers "F.Cu" "F.Mask" "F.Paste")
			(net "GND")
		)
		(pad "AW11" smd circle
			(at -11.44016 5.7277 180)
			(size 0.3048 0.3048)
			(layers "F.Cu" "F.Mask" "F.Paste")
			(net "M_A_DQS_DN2")
		)
		(pad "AW12" smd circle
			(at -10.67816 5.7277 180)
			(size 0.3048 0.3048)
			(layers "F.Cu" "F.Mask" "F.Paste")
			(net "M_A_DQS_DP2")
		)
		(pad "AW14" smd circle
			(at -9.91616 5.7277 180)
			(size 0.3048 0.3048)
			(layers "F.Cu" "F.Mask" "F.Paste")
			(net "GND")
		)
		(pad "AW15" smd circle
			(at -9.15416 5.7277 180)
			(size 0.3048 0.3048)
			(layers "F.Cu" "F.Mask" "F.Paste")
			(net "M_A_DQ23")
		)
		(pad "AW17" smd circle
			(at -8.17626 5.77342 180)
			(size 0.3048 0.3048)
			(layers "F.Cu" "F.Mask" "F.Paste")
			(net "M_A_DQ19")
		)
		(pad "AW19" smd circle
			(at -7.47522 5.77342 180)
			(size 0.3048 0.3048)
			(layers "F.Cu" "F.Mask" "F.Paste")
			(net "GND")
		)
		(pad "AW20" smd circle
			(at -6.80212 5.50164 180)
			(size 0.3048 0.3048)
			(layers "F.Cu" "F.Mask" "F.Paste")
			(net "M_A_ODTPU")
		)
		(pad "AW21" smd circle
			(at -5.90042 5.50164 180)
			(size 0.3048 0.3048)
			(layers "F.Cu" "F.Mask" "F.Paste")
			(net "M_A_DQPU")
		)
		(pad "AW23" smd circle
			(at -5.20192 5.50164 180)
			(size 0.381 0.381)
			(layers "F.Cu" "F.Mask" "F.Paste")
			(net "GND")
		)
		(pad "AW25" smd circle
			(at -4.2037 5.77342 180)
			(size 0.3048 0.3048)
			(layers "F.Cu" "F.Mask" "F.Paste")
			(net "GND")
		)
		(pad "AW26" smd circle
			(at -3.50266 5.77342 180)
			(size 0.3048 0.3048)
			(layers "F.Cu" "F.Mask" "F.Paste")
			(net "GND")
		)
		(pad "AW28" smd circle
			(at -2.79908 5.50164 180)
			(size 0.381 0.381)
			(layers "F.Cu" "F.Mask" "F.Paste")
			(net "GND")
		)
		(pad "AW30" smd circle
			(at -1.89992 5.50164 180)
			(size 0.381 0.381)
			(layers "F.Cu" "F.Mask" "F.Paste")
			(net "GND")
		)
		(pad "AW31" smd circle
			(at -1.19888 5.50164 180)
			(size 0.381 0.381)
			(layers "F.Cu" "F.Mask" "F.Paste")
			(net "GND")
		)
		(pad "AW32" smd circle
			(at -0.23114 5.77342 180)
			(size 0.3048 0.3048)
			(layers "F.Cu" "F.Mask" "F.Paste")
			(net "GND")
		)
		(pad "AW34" smd circle
			(at 0.4699 5.77342 180)
			(size 0.3048 0.3048)
			(layers "F.Cu" "F.Mask" "F.Paste")
			(net "GND")
		)
		(pad "AW36" smd circle
			(at 1.19888 5.50164 180)
			(size 0.381 0.381)
			(layers "F.Cu" "F.Mask" "F.Paste")
			(net "P1V0")
		)
		(pad "AW38" smd circle
			(at 2.10058 5.50164 180)
			(size 0.381 0.381)
			(layers "F.Cu" "F.Mask" "F.Paste")
			(net "P1V0")
		)
		(pad "AW39" smd circle
			(at 2.79908 5.50164 180)
			(size 0.381 0.381)
			(layers "F.Cu" "F.Mask" "F.Paste")
			(net "P1V0")
		)
		(pad "AW41" smd circle
			(at 3.74142 5.77342 180)
			(size 0.3048 0.3048)
			(layers "F.Cu" "F.Mask" "F.Paste")
			(net "P1V0")
		)
		(pad "AW42" smd circle
			(at 4.44246 5.77342 180)
			(size 0.3048 0.3048)
			(layers "F.Cu" "F.Mask" "F.Paste")
			(net "P3V3_CPU")
		)
		(pad "AW44" smd circle
			(at 5.20192 5.50164 180)
			(size 0.381 0.381)
			(layers "F.Cu" "F.Mask" "F.Paste")
			(net "GND")
		)
		(pad "AW46" smd circle
			(at 5.99948 5.50164 180)
			(size 0.3048 0.3048)
			(layers "F.Cu" "F.Mask" "F.Paste")
			(net "GND")
		)
		(pad "AW47" smd circle
			(at 6.70052 5.50164 180)
			(size 0.3048 0.3048)
			(layers "F.Cu" "F.Mask" "F.Paste")
			(net "GND")
		)
		(pad "AW49" smd circle
			(at 7.71398 5.77342 180)
			(size 0.3048 0.3048)
			(layers "F.Cu" "F.Mask" "F.Paste")
			(net "GND")
		)
		(pad "AW50" smd circle
			(at 8.41502 5.77342 180)
			(size 0.3048 0.3048)
			(layers "F.Cu" "F.Mask" "F.Paste")
			(net "GND")
		)
		(pad "AW52" smd circle
			(at 9.15416 5.48894 180)
			(size 0.3048 0.3048)
			(layers "F.Cu" "F.Mask" "F.Paste")
			(net "GND")
		)
		(pad "AW53" smd circle
			(at 9.91616 5.48894 180)
			(size 0.3048 0.3048)
			(layers "F.Cu" "F.Mask" "F.Paste")
			(net "SVID_DATA_R")
		)
		(pad "AW55" smd circle
			(at 10.67816 5.48894 180)
			(size 0.3048 0.3048)
			(layers "F.Cu" "F.Mask" "F.Paste")
			(net "GND")
		)
		(pad "AW56" smd circle
			(at 11.44016 5.48894 180)
			(size 0.3048 0.3048)
			(layers "F.Cu" "F.Mask" "F.Paste")
			(net "XDP_CPU_PRDY#")
		)
		(pad "AW58" smd circle
			(at 12.20216 5.48894 180)
			(size 0.3048 0.3048)
			(layers "F.Cu" "F.Mask" "F.Paste")
			(net "XDP_DFX_PORT2")
		)
		(pad "AW59" smd circle
			(at 12.96416 5.48894 180)
			(size 0.3048 0.3048)
			(layers "F.Cu" "F.Mask" "F.Paste")
			(net "GND")
		)
		(pad "AW62" smd circle
			(at 14.08176 5.61848 180)
			(size 0.3048 0.3048)
			(layers "F.Cu" "F.Mask" "F.Paste")
			(net "XDP_DFX_PORT7")
		)
		(pad "AW64" smd circle
			(at 15.24254 5.60832 180)
			(size 0.3048 0.3048)
			(layers "F.Cu" "F.Mask" "F.Paste")
			(net "XDP_DFX_PORT12")
		)
		(pad "AW66" smd oval
			(at 16.24838 5.83692 180)
			(size 0.3429 0.254)
			(layers "F.Cu" "F.Mask" "F.Paste")
			(net "XDP_DFX_PORT13")
		)
		(pad "AY1" smd oval
			(at -16.24838 6.0452 180)
			(size 0.3429 0.254)
			(layers "F.Cu" "F.Mask" "F.Paste")
			(net "M_A_ECC5")
		)
		(pad "AY2" smd circle
			(at -15.64132 6.39572 180)
			(size 0.3048 0.3048)
			(layers "F.Cu" "F.Mask" "F.Paste")
			(net "M_A_ECC1")
		)
		(pad "AY4" smd circle
			(at -14.89964 6.4008 180)
			(size 0.3048 0.3048)
			(layers "F.Cu" "F.Mask" "F.Paste")
			(net "M_A_ECC0")
		)
		(pad "AY5" smd circle
			(at -14.20368 6.49732 180)
			(size 0.3048 0.3048)
			(layers "F.Cu" "F.Mask" "F.Paste")
			(net "GND")
		)
		(pad "AY8" smd circle
			(at -12.96416 6.42874 180)
			(size 0.3048 0.3048)
			(layers "F.Cu" "F.Mask" "F.Paste")
			(net "M_A_DQ21")
		)
		(pad "AY9" smd circle
			(at -12.20216 6.42874 180)
			(size 0.3048 0.3048)
			(layers "F.Cu" "F.Mask" "F.Paste")
			(net "M_A_DQ16")
		)
		(pad "AY11" smd circle
			(at -11.44016 6.42874 180)
			(size 0.3048 0.3048)
			(layers "F.Cu" "F.Mask" "F.Paste")
			(net "M_A_DQ17")
		)
		(pad "AY12" smd circle
			(at -10.67816 6.42874 180)
			(size 0.3048 0.3048)
			(layers "F.Cu" "F.Mask" "F.Paste")
			(net "GND")
		)
		(pad "AY14" smd circle
			(at -9.91616 6.42874 180)
			(size 0.3048 0.3048)
			(layers "F.Cu" "F.Mask" "F.Paste")
			(net "M_A_DQ22")
		)
		(pad "AY15" smd circle
			(at -9.15416 6.42874 180)
			(size 0.3048 0.3048)
			(layers "F.Cu" "F.Mask" "F.Paste")
			(net "M_A_DQ18")
		)
		(pad "AY19" smd circle
			(at -7.47522 6.53542 180)
			(size 0.3048 0.3048)
			(layers "F.Cu" "F.Mask" "F.Paste")
			(net "PV_VDDR")
		)
		(pad "AY21" smd circle
			(at -6.18998 6.15442 180)
			(size 0.3048 0.3048)
			(layers "F.Cu" "F.Mask" "F.Paste")
			(net "PV_VDDR")
		)
		(pad "AY23" smd circle
			(at -5.48894 6.15442 180)
			(size 0.3048 0.3048)
			(layers "F.Cu" "F.Mask" "F.Paste")
			(net "PV_VDDR")
		)
		(pad "AY29" smd circle
			(at -2.21742 6.15442 180)
			(size 0.3048 0.3048)
			(layers "F.Cu" "F.Mask" "F.Paste")
			(net "M_A_VREF")
		)
		(pad "AY30" smd circle
			(at -1.51638 6.15442 180)
			(size 0.3048 0.3048)
			(layers "F.Cu" "F.Mask" "F.Paste")
			(net "M_A_DQ37")
		)
		(pad "AY37" smd circle
			(at 1.75514 6.15442 180)
			(size 0.3048 0.3048)
			(layers "F.Cu" "F.Mask" "F.Paste")
			(net "P1V0")
		)
		(pad "AY38" smd circle
			(at 2.45618 6.15442 180)
			(size 0.3048 0.3048)
			(layers "F.Cu" "F.Mask" "F.Paste")
			(net "GND")
		)
		(pad "AY45" smd circle
			(at 5.7277 6.15442 180)
			(size 0.3048 0.3048)
			(layers "F.Cu" "F.Mask" "F.Paste")
			(net "GND")
		)
		(pad "AY46" smd circle
			(at 6.42874 6.15442 180)
			(size 0.3048 0.3048)
			(layers "F.Cu" "F.Mask" "F.Paste")
			(net "Net_619")
		)
		(pad "AY52" smd circle
			(at 9.15416 6.18998 180)
			(size 0.3048 0.3048)
			(layers "F.Cu" "F.Mask" "F.Paste")
			(net "GND")
		)
		(pad "AY53" smd circle
			(at 9.91616 6.18998 180)
			(size 0.3048 0.3048)
			(layers "F.Cu" "F.Mask" "F.Paste")
			(net "XDP_CPU_PREQ#")
		)
		(pad "AY55" smd circle
			(at 10.67816 6.18998 180)
			(size 0.3048 0.3048)
			(layers "F.Cu" "F.Mask" "F.Paste")
			(net "GND")
		)
		(pad "AY56" smd circle
			(at 11.44016 6.18998 180)
			(size 0.3048 0.3048)
			(layers "F.Cu" "F.Mask" "F.Paste")
			(net "XDP_DFX_PORT5")
		)
		(pad "AY58" smd circle
			(at 12.20216 6.18998 180)
			(size 0.3048 0.3048)
			(layers "F.Cu" "F.Mask" "F.Paste")
			(net "XDP_DFX_PORT1")
		)
		(pad "AY59" smd circle
			(at 12.96416 6.18998 180)
			(size 0.3048 0.3048)
			(layers "F.Cu" "F.Mask" "F.Paste")
			(net "XDP_DFX_PORT8")
		)
		(pad "AY62" smd circle
			(at 14.20368 6.3119 180)
			(size 0.3048 0.3048)
			(layers "F.Cu" "F.Mask" "F.Paste")
			(net "GND")
		)
		(pad "AY63" smd circle
			(at 14.89964 6.21792 180)
			(size 0.3048 0.3048)
			(layers "F.Cu" "F.Mask" "F.Paste")
			(net "XDP_DFX_PORT6")
		)
		(pad "AY65" smd circle
			(at 15.63878 6.18744 180)
			(size 0.3048 0.3048)
			(layers "F.Cu" "F.Mask" "F.Paste")
			(net "XDP_DFX_PORT14")
		)
		(pad "B10" smd circle
			(at -11.8237 -12.63904 180)
			(size 0.3048 0.3048)
			(layers "F.Cu" "F.Mask" "F.Paste")
			(net "GND")
		)
		(pad "B12" smd circle
			(at -10.8966 -12.64158 180)
			(size 0.3048 0.3048)
			(layers "F.Cu" "F.Mask" "F.Paste")
			(net "M_B_ECC7")
		)
		(pad "B14" smd circle
			(at -9.8679 -12.80668 180)
			(size 0.3048 0.3048)
			(layers "F.Cu" "F.Mask" "F.Paste")
			(net "M_B_DQS_DP8")
		)
		(pad "B17" smd circle
			(at -8.38708 -12.75334 180)
			(size 0.3048 0.3048)
			(layers "F.Cu" "F.Mask" "F.Paste")
			(net "M_B_ECC5")
		)
		(pad "B19" smd circle
			(at -7.32028 -12.63904 180)
			(size 0.3048 0.3048)
			(layers "F.Cu" "F.Mask" "F.Paste")
			(net "M_B_DQ19")
		)
		(pad "B21" smd circle
			(at -6.39572 -12.64158 180)
			(size 0.3048 0.3048)
			(layers "F.Cu" "F.Mask" "F.Paste")
			(net "M_B_DQ22")
		)
		(pad "B23" smd circle
			(at -5.36448 -12.80668 180)
			(size 0.3048 0.3048)
			(layers "F.Cu" "F.Mask" "F.Paste")
			(net "M_B_DQ17")
		)
		(pad "B26" smd circle
			(at -3.8862 -12.75334 180)
			(size 0.3048 0.3048)
			(layers "F.Cu" "F.Mask" "F.Paste")
			(net "GND")
		)
		(pad "B28" smd circle
			(at -2.8194 -12.63904 180)
			(size 0.3048 0.3048)
			(layers "F.Cu" "F.Mask" "F.Paste")
			(net "M_B_DQ15")
		)
		(pad "B30" smd circle
			(at -1.8923 -12.64158 180)
			(size 0.3048 0.3048)
			(layers "F.Cu" "F.Mask" "F.Paste")
			(net "M_B_DQS_DN1")
		)
		(pad "B32" smd circle
			(at -0.8636 -12.80668 180)
			(size 0.3048 0.3048)
			(layers "F.Cu" "F.Mask" "F.Paste")
			(net "M_B_DQ8")
		)
		(pad "B35" smd circle
			(at 0.61722 -12.75334 180)
			(size 0.3048 0.3048)
			(layers "F.Cu" "F.Mask" "F.Paste")
			(net "M_B_DQ2")
		)
		(pad "B37" smd circle
			(at 1.68402 -12.63904 180)
			(size 0.3048 0.3048)
			(layers "F.Cu" "F.Mask" "F.Paste")
			(net "M_B_DQS_DN0")
		)
		(pad "B39" smd circle
			(at 2.61112 -12.64158 180)
			(size 0.3048 0.3048)
			(layers "F.Cu" "F.Mask" "F.Paste")
			(net "M_B_DQ0")
		)
		(pad "B41" smd circle
			(at 3.63982 -12.80668 180)
			(size 0.3048 0.3048)
			(layers "F.Cu" "F.Mask" "F.Paste")
			(net "GND")
		)
		(pad "B44" smd circle
			(at 5.12064 -12.75334 180)
			(size 0.3048 0.3048)
			(layers "F.Cu" "F.Mask" "F.Paste")
			(net "Net_1363")
		)
		(pad "B46" smd circle
			(at 6.18744 -12.63904 180)
			(size 0.3048 0.3048)
			(layers "F.Cu" "F.Mask" "F.Paste")
			(net "Net_277")
		)
		(pad "B48" smd circle
			(at 7.11454 -12.64158 180)
			(size 0.3048 0.3048)
			(layers "F.Cu" "F.Mask" "F.Paste")
			(net "CPU_GBE_TX_DN0")
		)
		(pad "B50" smd circle
			(at 8.14324 -12.80668 180)
			(size 0.3048 0.3048)
			(layers "F.Cu" "F.Mask" "F.Paste")
			(net "CLK_100M_CPU_GBE_DP")
		)
		(pad "B53" smd circle
			(at 9.62406 -12.75334 180)
			(size 0.3048 0.3048)
			(layers "F.Cu" "F.Mask" "F.Paste")
			(net "Net_1349")
		)
		(pad "B55" smd circle
			(at 10.69086 -12.63904 180)
			(size 0.3048 0.3048)
			(layers "F.Cu" "F.Mask" "F.Paste")
			(net "GND")
		)
		(pad "B57" smd circle
			(at 11.61796 -12.64158 180)
			(size 0.3048 0.3048)
			(layers "F.Cu" "F.Mask" "F.Paste")
			(net "SATA2_TX_DP0")
		)
		(pad "BA17" smd circle
			(at -8.17626 6.53542 180)
			(size 0.3048 0.3048)
			(layers "F.Cu" "F.Mask" "F.Paste")
			(net "GND")
		)
		(pad "BA21" smd circle
			(at -6.18998 6.91642 180)
			(size 0.3048 0.3048)
			(layers "F.Cu" "F.Mask" "F.Paste")
			(net "M_A_CK_DP0")
		)
		(pad "BA23" smd circle
			(at -5.48894 6.91642 180)
			(size 0.3048 0.3048)
			(layers "F.Cu" "F.Mask" "F.Paste")
			(net "M_A_MA13")
		)
		(pad "BA25" smd circle
			(at -4.2037 6.53542 180)
			(size 0.3048 0.3048)
			(layers "F.Cu" "F.Mask" "F.Paste")
			(net "M_A_R_RESET#")
		)
		(pad "BA26" smd circle
			(at -3.50266 6.53542 180)
			(size 0.3048 0.3048)
			(layers "F.Cu" "F.Mask" "F.Paste")
			(net "M_A_CMDPU")
		)
		(pad "BA29" smd circle
			(at -2.21742 6.91642 180)
			(size 0.3048 0.3048)
			(layers "F.Cu" "F.Mask" "F.Paste")
			(net "GND")
		)
		(pad "BA30" smd circle
			(at -1.51638 6.91642 180)
			(size 0.3048 0.3048)
			(layers "F.Cu" "F.Mask" "F.Paste")
			(net "M_A_DQ33")
		)
		(pad "BA32" smd circle
			(at -0.23114 6.53542 180)
			(size 0.3048 0.3048)
			(layers "F.Cu" "F.Mask" "F.Paste")
			(net "M_A_DQ32")
		)
		(pad "BA34" smd circle
			(at 0.4699 6.53542 180)
			(size 0.3048 0.3048)
			(layers "F.Cu" "F.Mask" "F.Paste")
			(net "GND")
		)
		(pad "BA37" smd circle
			(at 1.75514 6.91642 180)
			(size 0.3048 0.3048)
			(layers "F.Cu" "F.Mask" "F.Paste")
			(net "P1V0")
		)
		(pad "BA38" smd circle
			(at 2.45618 6.91642 180)
			(size 0.3048 0.3048)
			(layers "F.Cu" "F.Mask" "F.Paste")
			(net "PCIE_OBS_N")
		)
		(pad "BA41" smd circle
			(at 3.74142 6.53542 180)
			(size 0.3048 0.3048)
			(layers "F.Cu" "F.Mask" "F.Paste")
			(net "Net_1369")
		)
		(pad "BA42" smd circle
			(at 4.44246 6.53542 180)
			(size 0.3048 0.3048)
			(layers "F.Cu" "F.Mask" "F.Paste")
			(net "GND")
		)
		(pad "BA45" smd circle
			(at 5.7277 6.91642 180)
			(size 0.3048 0.3048)
			(layers "F.Cu" "F.Mask" "F.Paste")
			(net "USB_P1_DP")
		)
		(pad "BA46" smd circle
			(at 6.42874 6.91642 180)
			(size 0.3048 0.3048)
			(layers "F.Cu" "F.Mask" "F.Paste")
			(net "Net_618")
		)
		(pad "BA49" smd circle
			(at 7.71398 6.53542 180)
			(size 0.3048 0.3048)
			(layers "F.Cu" "F.Mask" "F.Paste")
			(net "GND")
		)
		(pad "BA50" smd circle
			(at 8.41502 6.53542 180)
			(size 0.3048 0.3048)
			(layers "F.Cu" "F.Mask" "F.Paste")
			(net "CLK_96M_CPU_USB_DN")
		)
		(pad "BB2" smd circle
			(at -15.63878 7.32028 180)
			(size 0.3048 0.3048)
			(layers "F.Cu" "F.Mask" "F.Paste")
			(net "M_A_DQS_DP8")
		)
		(pad "BB4" smd circle
			(at -14.89964 7.2898 180)
			(size 0.3048 0.3048)
			(layers "F.Cu" "F.Mask" "F.Paste")
			(net "M_A_DQS_DN8")
		)
		(pad "BB5" smd circle
			(at -14.20368 7.19836 180)
			(size 0.3048 0.3048)
			(layers "F.Cu" "F.Mask" "F.Paste")
			(net "GND")
		)
		(pad "BB17" smd circle
			(at -8.17626 7.29742 180)
			(size 0.3048 0.3048)
			(layers "F.Cu" "F.Mask" "F.Paste")
			(net "GND")
		)
		(pad "BB19" smd circle
			(at -7.47522 7.29742 180)
			(size 0.3048 0.3048)
			(layers "F.Cu" "F.Mask" "F.Paste")
			(net "M_A_CK_DP3")
		)
		(pad "BB25" smd circle
			(at -4.2037 7.29742 180)
			(size 0.3048 0.3048)
			(layers "F.Cu" "F.Mask" "F.Paste")
			(net "M_A_CS_N1")
		)
		(pad "BB26" smd circle
			(at -3.50266 7.29742 180)
			(size 0.3048 0.3048)
			(layers "F.Cu" "F.Mask" "F.Paste")
			(net "M_A_ODT1")
		)
		(pad "BB32" smd circle
			(at -0.23114 7.29742 180)
			(size 0.3048 0.3048)
			(layers "F.Cu" "F.Mask" "F.Paste")
			(net "M_A_DQ36")
		)
		(pad "BB34" smd circle
			(at 0.4699 7.29742 180)
			(size 0.3048 0.3048)
			(layers "F.Cu" "F.Mask" "F.Paste")
			(net "GND")
		)
		(pad "BB41" smd circle
			(at 3.74142 7.29742 180)
			(size 0.3048 0.3048)
			(layers "F.Cu" "F.Mask" "F.Paste")
			(net "Net_1370")
		)
		(pad "BB42" smd circle
			(at 4.44246 7.29742 180)
			(size 0.3048 0.3048)
			(layers "F.Cu" "F.Mask" "F.Paste")
			(net "Net_1368")
		)
		(pad "BB49" smd circle
			(at 7.71398 7.29742 180)
			(size 0.3048 0.3048)
			(layers "F.Cu" "F.Mask" "F.Paste")
			(net "CLK_100M_CLKBUFF_PCIE_DP")
		)
		(pad "BB50" smd circle
			(at 8.41502 7.29742 180)
			(size 0.3048 0.3048)
			(layers "F.Cu" "F.Mask" "F.Paste")
			(net "CLK_96M_CPU_USB_DP")
		)
		(pad "BB53" smd circle
			(at 9.53516 7.47522 180)
			(size 0.3048 0.3048)
			(layers "F.Cu" "F.Mask" "F.Paste")
			(net "GND")
		)
		(pad "BB54" smd circle
			(at 10.29716 7.47522 180)
			(size 0.3048 0.3048)
			(layers "F.Cu" "F.Mask" "F.Paste")
			(net "GND")
		)
		(pad "BB56" smd circle
			(at 11.05916 7.47522 180)
			(size 0.3048 0.3048)
			(layers "F.Cu" "F.Mask" "F.Paste")
			(net "GND")
		)
		(pad "BB57" smd circle
			(at 11.82116 7.47522 180)
			(size 0.3048 0.3048)
			(layers "F.Cu" "F.Mask" "F.Paste")
			(net "GND")
		)
		(pad "BB59" smd circle
			(at 12.58316 7.47522 180)
			(size 0.3048 0.3048)
			(layers "F.Cu" "F.Mask" "F.Paste")
			(net "PROCESSOR_HOT#")
		)
		(pad "BB60" smd circle
			(at 13.34516 7.47522 180)
			(size 0.3048 0.3048)
			(layers "F.Cu" "F.Mask" "F.Paste")
			(net "SVID_CLK_R")
		)
		(pad "BB62" smd circle
			(at 14.20368 7.0104 180)
			(size 0.3048 0.3048)
			(layers "F.Cu" "F.Mask" "F.Paste")
			(net "GND")
		)
		(pad "BB63" smd circle
			(at 14.89964 7.10692 180)
			(size 0.3048 0.3048)
			(layers "F.Cu" "F.Mask" "F.Paste")
			(net "XDP_DFX_PORT10")
		)
		(pad "BB65" smd circle
			(at 15.64132 7.11454 180)
			(size 0.3048 0.3048)
			(layers "F.Cu" "F.Mask" "F.Paste")
			(net "GND")
		)
		(pad "BB66" smd oval
			(at 16.24838 7.46252 180)
			(size 0.3429 0.254)
			(layers "F.Cu" "F.Mask" "F.Paste")
			(net "GND")
		)
		(pad "BC1" smd oval
			(at -16.24838 7.6708 180)
			(size 0.3429 0.254)
			(layers "F.Cu" "F.Mask" "F.Paste")
			(net "M_A_ECC6")
		)
		(pad "BC3" smd circle
			(at -15.24254 7.90194 180)
			(size 0.3048 0.3048)
			(layers "F.Cu" "F.Mask" "F.Paste")
			(net "M_A_ECC7")
		)
		(pad "BC5" smd circle
			(at -14.08176 7.89178 180)
			(size 0.3048 0.3048)
			(layers "F.Cu" "F.Mask" "F.Paste")
			(net "GND")
		)
		(pad "BC7" smd circle
			(at -13.34516 7.71398 180)
			(size 0.3048 0.3048)
			(layers "F.Cu" "F.Mask" "F.Paste")
			(net "PV_VDDR")
		)
		(pad "BC8" smd circle
			(at -12.58316 7.71398 180)
			(size 0.3048 0.3048)
			(layers "F.Cu" "F.Mask" "F.Paste")
			(net "M_A_BS2")
		)
		(pad "BC10" smd circle
			(at -11.82116 7.71398 180)
			(size 0.3048 0.3048)
			(layers "F.Cu" "F.Mask" "F.Paste")
			(net "PV_VDDR")
		)
		(pad "BC11" smd circle
			(at -11.05916 7.71398 180)
			(size 0.3048 0.3048)
			(layers "F.Cu" "F.Mask" "F.Paste")
			(net "M_A_MA14")
		)
		(pad "BC13" smd circle
			(at -10.29716 7.71398 180)
			(size 0.3048 0.3048)
			(layers "F.Cu" "F.Mask" "F.Paste")
			(net "PV_VDDR")
		)
		(pad "BC15" smd circle
			(at -9.4615 7.67842 180)
			(size 0.3048 0.3048)
			(layers "F.Cu" "F.Mask" "F.Paste")
			(net "PV_VDDR")
		)
		(pad "BC21" smd circle
			(at -6.18998 7.67842 180)
			(size 0.3048 0.3048)
			(layers "F.Cu" "F.Mask" "F.Paste")
			(net "M_A_CK_DN0")
		)
		(pad "BC23" smd circle
			(at -5.48894 7.67842 180)
			(size 0.3048 0.3048)
			(layers "F.Cu" "F.Mask" "F.Paste")
			(net "M_A_WE#")
		)
		(pad "BC29" smd circle
			(at -2.21742 7.67842 180)
			(size 0.3048 0.3048)
			(layers "F.Cu" "F.Mask" "F.Paste")
			(net "M_A_DQS_DN4")
		)
		(pad "BC30" smd circle
			(at -1.51638 7.67842 180)
			(size 0.3048 0.3048)
			(layers "F.Cu" "F.Mask" "F.Paste")
			(net "GND")
		)
		(pad "BC37" smd circle
			(at 1.75514 7.67842 180)
			(size 0.3048 0.3048)
			(layers "F.Cu" "F.Mask" "F.Paste")
			(net "GND")
		)
		(pad "BC38" smd circle
			(at 2.45618 7.67842 180)
			(size 0.3048 0.3048)
			(layers "F.Cu" "F.Mask" "F.Paste")
			(net "PCIE_OBS_P")
		)
		(pad "BC45" smd circle
			(at 5.7277 7.67842 180)
			(size 0.3048 0.3048)
			(layers "F.Cu" "F.Mask" "F.Paste")
			(net "USB_P1_DN")
		)
		(pad "BC46" smd circle
			(at 6.42874 7.67842 180)
			(size 0.3048 0.3048)
			(layers "F.Cu" "F.Mask" "F.Paste")
			(net "GND")
		)
		(pad "BC62" smd circle
			(at 14.01318 7.68858 180)
			(size 0.3048 0.3048)
			(layers "F.Cu" "F.Mask" "F.Paste")
			(net "SVID_ALERT#")
		)
		(pad "BC64" smd circle
			(at 15.24762 7.71906 180)
			(size 0.3048 0.3048)
			(layers "F.Cu" "F.Mask" "F.Paste")
			(net "XDP_DFX_PORT0")
		)
		(pad "BD2" smd circle
			(at -15.75308 8.38708 180)
			(size 0.3048 0.3048)
			(layers "F.Cu" "F.Mask" "F.Paste")
			(net "M_A_ECC2")
		)
		(pad "BD4" smd circle
			(at -14.7955 8.44042 180)
			(size 0.3048 0.3048)
			(layers "F.Cu" "F.Mask" "F.Paste")
			(net "M_A_ECC3")
		)
		(pad "BD7" smd circle
			(at -13.34516 8.41502 180)
			(size 0.3048 0.3048)
			(layers "F.Cu" "F.Mask" "F.Paste")
			(net "M_A_MA12")
		)
		(pad "BD8" smd circle
			(at -12.58316 8.41502 180)
			(size 0.3048 0.3048)
			(layers "F.Cu" "F.Mask" "F.Paste")
			(net "M_A_MA8")
		)
		(pad "BD10" smd circle
			(at -11.82116 8.41502 180)
			(size 0.3048 0.3048)
			(layers "F.Cu" "F.Mask" "F.Paste")
			(net "M_A_MA6")
		)
		(pad "BD13" smd circle
			(at -10.16254 8.44042 180)
			(size 0.3048 0.3048)
			(layers "F.Cu" "F.Mask" "F.Paste")
			(net "M_A_MA4")
		)
		(pad "BD15" smd circle
			(at -9.4615 8.44042 180)
			(size 0.3048 0.3048)
			(layers "F.Cu" "F.Mask" "F.Paste")
			(net "M_A_MA9")
		)
		(pad "BD17" smd circle
			(at -8.17626 8.05942 180)
			(size 0.3048 0.3048)
			(layers "F.Cu" "F.Mask" "F.Paste")
			(net "PV_VDDR")
		)
		(pad "BD19" smd circle
			(at -7.47522 8.05942 180)
			(size 0.3048 0.3048)
			(layers "F.Cu" "F.Mask" "F.Paste")
			(net "M_A_CK_DN3")
		)
		(pad "BD21" smd circle
			(at -6.18998 8.44042 180)
			(size 0.3048 0.3048)
			(layers "F.Cu" "F.Mask" "F.Paste")
			(net "PV_VDDR")
		)
		(pad "BD23" smd circle
			(at -5.48894 8.44042 180)
			(size 0.3048 0.3048)
			(layers "F.Cu" "F.Mask" "F.Paste")
			(net "M_A_CS_N2")
		)
		(pad "BD25" smd circle
			(at -4.2037 8.05942 180)
			(size 0.3048 0.3048)
			(layers "F.Cu" "F.Mask" "F.Paste")
			(net "PV_VDDR")
		)
		(pad "BD26" smd circle
			(at -3.50266 8.05942 180)
			(size 0.3048 0.3048)
			(layers "F.Cu" "F.Mask" "F.Paste")
			(net "M_A_ODT0")
		)
		(pad "BD29" smd circle
			(at -2.21742 8.44042 180)
			(size 0.3048 0.3048)
			(layers "F.Cu" "F.Mask" "F.Paste")
			(net "M_A_DQS_DP4")
		)
		(pad "BD30" smd circle
			(at -1.51638 8.44042 180)
			(size 0.3048 0.3048)
			(layers "F.Cu" "F.Mask" "F.Paste")
			(net "M_A_DQ35")
		)
		(pad "BD32" smd circle
			(at -0.23114 8.05942 180)
			(size 0.3048 0.3048)
			(layers "F.Cu" "F.Mask" "F.Paste")
			(net "GND")
		)
		(pad "BD34" smd circle
			(at 0.4699 8.05942 180)
			(size 0.3048 0.3048)
			(layers "F.Cu" "F.Mask" "F.Paste")
			(net "GND")
		)
		(pad "BD37" smd circle
			(at 1.75514 8.44042 180)
			(size 0.3048 0.3048)
			(layers "F.Cu" "F.Mask" "F.Paste")
			(net "P2E_CPU_NGFF_RX_DP14")
		)
		(pad "BD38" smd circle
			(at 2.45618 8.44042 180)
			(size 0.3048 0.3048)
			(layers "F.Cu" "F.Mask" "F.Paste")
			(net "GND")
		)
		(pad "BD41" smd circle
			(at 3.74142 8.05942 180)
			(size 0.3048 0.3048)
			(layers "F.Cu" "F.Mask" "F.Paste")
			(net "GND")
		)
		(pad "BD42" smd circle
			(at 4.44246 8.05942 180)
			(size 0.3048 0.3048)
			(layers "F.Cu" "F.Mask" "F.Paste")
			(net "Net_1367")
		)
		(pad "BD45" smd circle
			(at 5.7277 8.44042 180)
			(size 0.3048 0.3048)
			(layers "F.Cu" "F.Mask" "F.Paste")
			(net "GND")
		)
		(pad "BD46" smd circle
			(at 6.42874 8.44042 180)
			(size 0.3048 0.3048)
			(layers "F.Cu" "F.Mask" "F.Paste")
			(net "P2E_CPU_ETH10G_RX_DP9")
		)
		(pad "BD49" smd circle
			(at 7.71398 8.05942 180)
			(size 0.3048 0.3048)
			(layers "F.Cu" "F.Mask" "F.Paste")
			(net "CLK_100M_CLKBUFF_PCIE_DN")
		)
		(pad "BD50" smd circle
			(at 8.41502 8.05942 180)
			(size 0.3048 0.3048)
			(layers "F.Cu" "F.Mask" "F.Paste")
			(net "GND")
		)
		(pad "BD53" smd circle
			(at 9.70026 8.44042 180)
			(size 0.3048 0.3048)
			(layers "F.Cu" "F.Mask" "F.Paste")
			(net "GND")
		)
		(pad "BD54" smd circle
			(at 10.4013 8.44042 180)
			(size 0.3048 0.3048)
			(layers "F.Cu" "F.Mask" "F.Paste")
			(net "P2E_CPU_SAS_RX_DP5")
		)
		(pad "BD59" smd circle
			(at 12.58316 8.17626 180)
			(size 0.3048 0.3048)
			(layers "F.Cu" "F.Mask" "F.Paste")
			(net "GND")
		)
		(pad "BD60" smd circle
			(at 13.34516 8.17626 180)
			(size 0.3048 0.3048)
			(layers "F.Cu" "F.Mask" "F.Paste")
			(net "GND")
		)
		(pad "BD62" smd circle
			(at 14.06398 8.39216 180)
			(size 0.3048 0.3048)
			(layers "F.Cu" "F.Mask" "F.Paste")
			(net "GND")
		)
		(pad "BD63" smd circle
			(at 14.75232 8.22198 180)
			(size 0.3048 0.3048)
			(layers "F.Cu" "F.Mask" "F.Paste")
			(net "GND")
		)
		(pad "BD65" smd circle
			(at 15.80642 8.14324 180)
			(size 0.3048 0.3048)
			(layers "F.Cu" "F.Mask" "F.Paste")
			(net "GND")
		)
		(pad "BE5" smd circle
			(at -14.06398 8.5979 180)
			(size 0.3048 0.3048)
			(layers "F.Cu" "F.Mask" "F.Paste")
			(net "GND")
		)
		(pad "BE17" smd circle
			(at -8.17626 8.82142 180)
			(size 0.3048 0.3048)
			(layers "F.Cu" "F.Mask" "F.Paste")
			(net "PWRGD_DDR3_VCCA")
		)
		(pad "BE19" smd circle
			(at -7.47522 8.82142 180)
			(size 0.3048 0.3048)
			(layers "F.Cu" "F.Mask" "F.Paste")
			(net "PV_VDDR")
		)
		(pad "BE25" smd circle
			(at -4.2037 8.82142 180)
			(size 0.3048 0.3048)
			(layers "F.Cu" "F.Mask" "F.Paste")
			(net "M_A_CS_N0")
		)
		(pad "BE26" smd circle
			(at -3.50266 8.82142 180)
			(size 0.3048 0.3048)
			(layers "F.Cu" "F.Mask" "F.Paste")
			(net "PV_VDDR")
		)
		(pad "BE32" smd circle
			(at -0.23114 8.82142 180)
			(size 0.3048 0.3048)
			(layers "F.Cu" "F.Mask" "F.Paste")
			(net "GND")
		)
		(pad "BE34" smd circle
			(at 0.4699 8.82142 180)
			(size 0.3048 0.3048)
			(layers "F.Cu" "F.Mask" "F.Paste")
			(net "P2E_CPU_NGFF_RX_DP15")
		)
		(pad "BE41" smd circle
			(at 3.74142 8.82142 180)
			(size 0.3048 0.3048)
			(layers "F.Cu" "F.Mask" "F.Paste")
			(net "P2E_CPU_NGFF_RX_DP12")
		)
		(pad "BE42" smd circle
			(at 4.44246 8.82142 180)
			(size 0.3048 0.3048)
			(layers "F.Cu" "F.Mask" "F.Paste")
			(net "GND")
		)
		(pad "BE49" smd circle
			(at 7.71398 8.82142 180)
			(size 0.3048 0.3048)
			(layers "F.Cu" "F.Mask" "F.Paste")
			(net "GND")
		)
		(pad "BE50" smd circle
			(at 8.41502 8.82142 180)
			(size 0.3048 0.3048)
			(layers "F.Cu" "F.Mask" "F.Paste")
			(net "P2E_CPU_SAS_RX_DP7")
		)
		(pad "BE57" smd circle
			(at 11.68654 8.82142 180)
			(size 0.3048 0.3048)
			(layers "F.Cu" "F.Mask" "F.Paste")
			(net "GND")
		)
		(pad "BE63" smd circle
			(at 14.5415 8.9027 180)
			(size 0.3048 0.3048)
			(layers "F.Cu" "F.Mask" "F.Paste")
			(net "P2E_CPU_SAS_RX_DP0")
		)
		(pad "BE64" smd circle
			(at 15.3035 8.9535 180)
			(size 0.3048 0.3048)
			(layers "F.Cu" "F.Mask" "F.Paste")
			(net "P2E_CPU_SAS_RX_DN0")
		)
		(pad "BE66" smd oval
			(at 16.24838 8.9027 180)
			(size 0.3429 0.254)
			(layers "F.Cu" "F.Mask" "F.Paste")
			(net "GND")
		)
		(pad "BF1" smd oval
			(at -16.24838 9.10844 180)
			(size 0.3429 0.254)
			(layers "F.Cu" "F.Mask" "F.Paste")
			(net "GND")
		)
		(pad "BF3" smd circle
			(at -15.3035 9.05764 180)
			(size 0.3048 0.3048)
			(layers "F.Cu" "F.Mask" "F.Paste")
			(net "GND")
		)
		(pad "BF4" smd circle
			(at -14.5415 9.10844 180)
			(size 0.3048 0.3048)
			(layers "F.Cu" "F.Mask" "F.Paste")
			(net "GND")
		)
		(pad "BF13" smd circle
			(at -10.16254 9.20242 180)
			(size 0.3048 0.3048)
			(layers "F.Cu" "F.Mask" "F.Paste")
			(net "PV_VDDR")
		)
		(pad "BF15" smd circle
			(at -9.4615 9.20242 180)
			(size 0.3048 0.3048)
			(layers "F.Cu" "F.Mask" "F.Paste")
			(net "M_A_MA15")
		)
		(pad "BF21" smd circle
			(at -6.18998 9.20242 180)
			(size 0.3048 0.3048)
			(layers "F.Cu" "F.Mask" "F.Paste")
			(net "M_A_CK_DP1")
		)
		(pad "BF23" smd circle
			(at -5.48894 9.20242 180)
			(size 0.3048 0.3048)
			(layers "F.Cu" "F.Mask" "F.Paste")
			(net "PV_VDDR")
		)
		(pad "BF29" smd circle
			(at -2.21742 9.20242 180)
			(size 0.3048 0.3048)
			(layers "F.Cu" "F.Mask" "F.Paste")
			(net "GND")
		)
		(pad "BF30" smd circle
			(at -1.51638 9.20242 180)
			(size 0.3048 0.3048)
			(layers "F.Cu" "F.Mask" "F.Paste")
			(net "M_A_DQ34")
		)
		(pad "BF37" smd circle
			(at 1.75514 9.20242 180)
			(size 0.3048 0.3048)
			(layers "F.Cu" "F.Mask" "F.Paste")
			(net "P2E_CPU_NGFF_RX_DN14")
		)
		(pad "BF38" smd circle
			(at 2.45618 9.20242 180)
			(size 0.3048 0.3048)
			(layers "F.Cu" "F.Mask" "F.Paste")
			(net "P2E_CPU_NGFF_RX_DP13")
		)
		(pad "BF45" smd circle
			(at 5.7277 9.20242 180)
			(size 0.3048 0.3048)
			(layers "F.Cu" "F.Mask" "F.Paste")
			(net "P2E_CPU_ETH10G_RX_DP10")
		)
		(pad "BF46" smd circle
			(at 6.42874 9.20242 180)
			(size 0.3048 0.3048)
			(layers "F.Cu" "F.Mask" "F.Paste")
			(net "P2E_CPU_ETH10G_RX_DN9")
		)
		(pad "BF53" smd circle
			(at 9.70026 9.20242 180)
			(size 0.3048 0.3048)
			(layers "F.Cu" "F.Mask" "F.Paste")
			(net "P2E_CPU_SAS_RX_DP6")
		)
		(pad "BF54" smd circle
			(at 10.4013 9.20242 180)
			(size 0.3048 0.3048)
			(layers "F.Cu" "F.Mask" "F.Paste")
			(net "P2E_CPU_SAS_RX_DN5")
		)
		(pad "BF62" smd circle
			(at 14.06398 9.41324 180)
			(size 0.3048 0.3048)
			(layers "F.Cu" "F.Mask" "F.Paste")
			(net "GND")
		)
		(pad "BG1" smd circle
			(at -16.11122 9.86028 180)
			(size 0.4064 0.4064)
			(layers "F.Cu" "F.Mask" "F.Paste")
			(net "GND")
		)
		(pad "BG4" smd circle
			(at -14.75232 9.78916 180)
			(size 0.3048 0.3048)
			(layers "F.Cu" "F.Mask" "F.Paste")
			(net "M_A_CKE0")
		)
		(pad "BG5" smd circle
			(at -14.06398 9.62152 180)
			(size 0.3048 0.3048)
			(layers "F.Cu" "F.Mask" "F.Paste")
			(net "M_A_CKE2")
		)
		(pad "BG8" smd circle
			(at -12.96416 9.70026 180)
			(size 0.3048 0.3048)
			(layers "F.Cu" "F.Mask" "F.Paste")
			(net "M_A_MA11")
		)
		(pad "BG9" smd circle
			(at -12.20216 9.70026 180)
			(size 0.3048 0.3048)
			(layers "F.Cu" "F.Mask" "F.Paste")
			(net "PV_VDDR")
		)
		(pad "BG11" smd circle
			(at -11.44778 9.58342 180)
			(size 0.3048 0.3048)
			(layers "F.Cu" "F.Mask" "F.Paste")
			(net "M_A_MA3")
		)
		(pad "BG13" smd circle
			(at -10.16254 9.96442 180)
			(size 0.3048 0.3048)
			(layers "F.Cu" "F.Mask" "F.Paste")
			(net "M_A_MA2")
		)
		(pad "BG15" smd circle
			(at -9.4615 9.96442 180)
			(size 0.3048 0.3048)
			(layers "F.Cu" "F.Mask" "F.Paste")
			(net "PV_VDDR")
		)
		(pad "BG17" smd circle
			(at -8.17626 9.58342 180)
			(size 0.3048 0.3048)
			(layers "F.Cu" "F.Mask" "F.Paste")
			(net "M_DRAM_PWROK")
		)
		(pad "BG19" smd circle
			(at -7.47522 9.58342 180)
			(size 0.3048 0.3048)
			(layers "F.Cu" "F.Mask" "F.Paste")
			(net "M_A_CK_DP2")
		)
		(pad "BG21" smd circle
			(at -6.18998 9.96442 180)
			(size 0.3048 0.3048)
			(layers "F.Cu" "F.Mask" "F.Paste")
			(net "M_A_CK_DN1")
		)
		(pad "BG23" smd circle
			(at -5.48894 9.96442 180)
			(size 0.3048 0.3048)
			(layers "F.Cu" "F.Mask" "F.Paste")
			(net "M_A_RAS#")
		)
		(pad "BG25" smd circle
			(at -4.2037 9.58342 180)
			(size 0.3048 0.3048)
			(layers "F.Cu" "F.Mask" "F.Paste")
			(net "M_A_ODT3")
		)
		(pad "BG26" smd circle
			(at -3.50266 9.58342 180)
			(size 0.3048 0.3048)
			(layers "F.Cu" "F.Mask" "F.Paste")
			(net "M_A_CS_N3")
		)
		(pad "BG29" smd circle
			(at -2.21742 9.96442 180)
			(size 0.3048 0.3048)
			(layers "F.Cu" "F.Mask" "F.Paste")
			(net "M_A_DQ38")
		)
		(pad "BG30" smd circle
			(at -1.51638 9.96442 180)
			(size 0.3048 0.3048)
			(layers "F.Cu" "F.Mask" "F.Paste")
			(net "M_A_DQ39")
		)
		(pad "BG32" smd circle
			(at -0.23114 9.58342 180)
			(size 0.3048 0.3048)
			(layers "F.Cu" "F.Mask" "F.Paste")
			(net "GND")
		)
		(pad "BG34" smd circle
			(at 0.4699 9.58342 180)
			(size 0.3048 0.3048)
			(layers "F.Cu" "F.Mask" "F.Paste")
			(net "P2E_CPU_NGFF_RX_DN15")
		)
		(pad "BG37" smd circle
			(at 1.75514 9.96442 180)
			(size 0.3048 0.3048)
			(layers "F.Cu" "F.Mask" "F.Paste")
			(net "GND")
		)
		(pad "BG38" smd circle
			(at 2.45618 9.96442 180)
			(size 0.3048 0.3048)
			(layers "F.Cu" "F.Mask" "F.Paste")
			(net "P2E_CPU_NGFF_RX_DN13")
		)
		(pad "BG41" smd circle
			(at 3.74142 9.58342 180)
			(size 0.3048 0.3048)
			(layers "F.Cu" "F.Mask" "F.Paste")
			(net "P2E_CPU_NGFF_RX_DN12")
		)
		(pad "BG42" smd circle
			(at 4.44246 9.58342 180)
			(size 0.3048 0.3048)
			(layers "F.Cu" "F.Mask" "F.Paste")
			(net "P2E_CPU_ETH10G_RX_DP11")
		)
		(pad "BG45" smd circle
			(at 5.7277 9.96442 180)
			(size 0.3048 0.3048)
			(layers "F.Cu" "F.Mask" "F.Paste")
			(net "P2E_CPU_ETH10G_RX_DN10")
		)
		(pad "BG46" smd circle
			(at 6.42874 9.96442 180)
			(size 0.3048 0.3048)
			(layers "F.Cu" "F.Mask" "F.Paste")
			(net "GND")
		)
		(pad "BG49" smd circle
			(at 7.71398 9.58342 180)
			(size 0.3048 0.3048)
			(layers "F.Cu" "F.Mask" "F.Paste")
			(net "P2E_CPU_ETH10G_RX_DP8")
		)
		(pad "BG50" smd circle
			(at 8.41502 9.58342 180)
			(size 0.3048 0.3048)
			(layers "F.Cu" "F.Mask" "F.Paste")
			(net "P2E_CPU_SAS_RX_DN7")
		)
		(pad "BG53" smd circle
			(at 9.70026 9.96442 180)
			(size 0.3048 0.3048)
			(layers "F.Cu" "F.Mask" "F.Paste")
			(net "P2E_CPU_SAS_RX_DN6")
		)
		(pad "BG54" smd circle
			(at 10.4013 9.96442 180)
			(size 0.3048 0.3048)
			(layers "F.Cu" "F.Mask" "F.Paste")
			(net "GND")
		)
		(pad "BG57" smd circle
			(at 11.68654 9.58342 180)
			(size 0.3048 0.3048)
			(layers "F.Cu" "F.Mask" "F.Paste")
			(net "P2E_CPU_SAS_RX_DP4")
		)
		(pad "BG58" smd circle
			(at 12.38758 9.58342 180)
			(size 0.3048 0.3048)
			(layers "F.Cu" "F.Mask" "F.Paste")
			(net "P2E_CPU_SAS_RX_DP3")
		)
		(pad "BG63" smd circle
			(at 14.75232 9.58088 180)
			(size 0.3048 0.3048)
			(layers "F.Cu" "F.Mask" "F.Paste")
			(net "GND")
		)
		(pad "BG66" smd circle
			(at 16.11122 9.86028 180)
			(size 0.4064 0.4064)
			(layers "F.Cu" "F.Mask" "F.Paste")
			(net "GND")
		)
		(pad "BH3" smd circle
			(at -15.29842 10.31748 180)
			(size 0.3048 0.3048)
			(layers "F.Cu" "F.Mask" "F.Paste")
			(net "M_A_CKE3")
		)
		(pad "BH5" smd circle
			(at -14.01318 10.32256 180)
			(size 0.3048 0.3048)
			(layers "F.Cu" "F.Mask" "F.Paste")
			(net "M_A_CKE1")
		)
		(pad "BH8" smd circle
			(at -12.58316 10.34542 180)
			(size 0.3048 0.3048)
			(layers "F.Cu" "F.Mask" "F.Paste")
			(net "M_A_MA7")
		)
		(pad "BH11" smd circle
			(at -11.44778 10.34542 180)
			(size 0.3048 0.3048)
			(layers "F.Cu" "F.Mask" "F.Paste")
			(net "M_A_MA0")
		)
		(pad "BH17" smd circle
			(at -8.17626 10.34542 180)
			(size 0.3048 0.3048)
			(layers "F.Cu" "F.Mask" "F.Paste")
			(net "PV_VDDR")
		)
		(pad "BH19" smd circle
			(at -7.47522 10.34542 180)
			(size 0.3048 0.3048)
			(layers "F.Cu" "F.Mask" "F.Paste")
			(net "M_A_CK_DN2")
		)
		(pad "BH25" smd circle
			(at -4.2037 10.34542 180)
			(size 0.3048 0.3048)
			(layers "F.Cu" "F.Mask" "F.Paste")
			(net "M_A_ODT2")
		)
		(pad "BH26" smd circle
			(at -3.50266 10.34542 180)
			(size 0.3048 0.3048)
			(layers "F.Cu" "F.Mask" "F.Paste")
			(net "M_A_CAS#")
		)
		(pad "BH32" smd circle
			(at -0.23114 10.34542 180)
			(size 0.3048 0.3048)
			(layers "F.Cu" "F.Mask" "F.Paste")
			(net "GND")
		)
		(pad "BH34" smd circle
			(at 0.4699 10.34542 180)
			(size 0.3048 0.3048)
			(layers "F.Cu" "F.Mask" "F.Paste")
			(net "GND")
		)
		(pad "BH41" smd circle
			(at 3.74142 10.34542 180)
			(size 0.3048 0.3048)
			(layers "F.Cu" "F.Mask" "F.Paste")
			(net "GND")
		)
		(pad "BH42" smd circle
			(at 4.44246 10.34542 180)
			(size 0.3048 0.3048)
			(layers "F.Cu" "F.Mask" "F.Paste")
			(net "P2E_CPU_ETH10G_RX_DN11")
		)
		(pad "BH49" smd circle
			(at 7.71398 10.34542 180)
			(size 0.3048 0.3048)
			(layers "F.Cu" "F.Mask" "F.Paste")
			(net "P2E_CPU_ETH10G_RX_DN8")
		)
		(pad "BH50" smd circle
			(at 8.41502 10.34542 180)
			(size 0.3048 0.3048)
			(layers "F.Cu" "F.Mask" "F.Paste")
			(net "GND")
		)
		(pad "BH57" smd circle
			(at 11.68654 10.34542 180)
			(size 0.3048 0.3048)
			(layers "F.Cu" "F.Mask" "F.Paste")
			(net "P2E_CPU_SAS_RX_DN4")
		)
		(pad "BH58" smd circle
			(at 12.38758 10.34542 180)
			(size 0.3048 0.3048)
			(layers "F.Cu" "F.Mask" "F.Paste")
			(net "P2E_CPU_SAS_RX_DN3")
		)
		(pad "BH60" smd circle
			(at 13.34516 10.16254 180)
			(size 0.3048 0.3048)
			(layers "F.Cu" "F.Mask" "F.Paste")
			(net "GND")
		)
		(pad "BH62" smd circle
			(at 14.08176 10.11936 180)
			(size 0.3048 0.3048)
			(layers "F.Cu" "F.Mask" "F.Paste")
			(net "GND")
		)
		(pad "BH64" smd circle
			(at 15.29842 10.1092 180)
			(size 0.3048 0.3048)
			(layers "F.Cu" "F.Mask" "F.Paste")
			(net "P2E_CPU_SAS_RX_DN1")
		)
		(pad "BJ1" smd circle
			(at -16.11122 10.67308 180)
			(size 0.4064 0.4064)
			(layers "F.Cu" "F.Mask" "F.Paste")
			(net "GND")
		)
		(pad "BJ4" smd circle
			(at -14.89964 10.90422 180)
			(size 0.3048 0.3048)
			(layers "F.Cu" "F.Mask" "F.Paste")
			(net "PV_VDDR")
		)
		(pad "BJ62" smd circle
			(at 14.20368 10.81278 180)
			(size 0.3048 0.3048)
			(layers "F.Cu" "F.Mask" "F.Paste")
			(net "P2E_CPU_SAS_RX_DP2")
		)
		(pad "BJ63" smd circle
			(at 14.89964 10.69594 180)
			(size 0.3048 0.3048)
			(layers "F.Cu" "F.Mask" "F.Paste")
			(net "P2E_CPU_SAS_RX_DP1")
		)
		(pad "BJ66" smd circle
			(at 16.11122 10.67308 180)
			(size 0.4064 0.4064)
			(layers "F.Cu" "F.Mask" "F.Paste")
			(net "GND")
		)
		(pad "BK1" smd circle
			(at -16.11122 11.48588 180)
			(size 0.4064 0.4064)
			(layers "F.Cu" "F.Mask" "F.Paste")
			(net "GND")
		)
		(pad "BK3" smd circle
			(at -15.29842 11.48588 180)
			(size 0.4064 0.4064)
			(layers "F.Cu" "F.Mask" "F.Paste")
			(net "M_A_MON2_N")
		)
		(pad "BK5" smd circle
			(at -14.48562 11.48588 180)
			(size 0.4064 0.4064)
			(layers "F.Cu" "F.Mask" "F.Paste")
			(net "M_A_MON2_P")
		)
		(pad "BK6" smd circle
			(at -13.91666 11.06424 180)
			(size 0.3048 0.3048)
			(layers "F.Cu" "F.Mask" "F.Paste")
			(net "PV_VDDR")
		)
		(pad "BK8" smd circle
			(at -12.89558 11.06424 180)
			(size 0.3048 0.3048)
			(layers "F.Cu" "F.Mask" "F.Paste")
			(net "GND")
		)
		(pad "BK9" smd circle
			(at -12.192 11.01344 180)
			(size 0.3048 0.3048)
			(layers "F.Cu" "F.Mask" "F.Paste")
			(net "PV_VDDR")
		)
		(pad "BK10" smd circle
			(at -11.51382 11.20394 180)
			(size 0.3048 0.3048)
			(layers "F.Cu" "F.Mask" "F.Paste")
			(net "GND")
		)
		(pad "BK12" smd circle
			(at -10.81532 11.20394 180)
			(size 0.3048 0.3048)
			(layers "F.Cu" "F.Mask" "F.Paste")
			(net "PV_VDDR")
		)
		(pad "BK13" smd circle
			(at -10.11936 11.0744 180)
			(size 0.3048 0.3048)
			(layers "F.Cu" "F.Mask" "F.Paste")
			(net "PV_VDDR")
		)
		(pad "BK15" smd circle
			(at -9.41324 11.06424 180)
			(size 0.3048 0.3048)
			(layers "F.Cu" "F.Mask" "F.Paste")
			(net "GND")
		)
		(pad "BK17" smd circle
			(at -8.39216 11.06424 180)
			(size 0.3048 0.3048)
			(layers "F.Cu" "F.Mask" "F.Paste")
			(net "GND")
		)
		(pad "BK18" smd circle
			(at -7.68858 11.01344 180)
			(size 0.3048 0.3048)
			(layers "F.Cu" "F.Mask" "F.Paste")
			(net "GND")
		)
		(pad "BK19" smd circle
			(at -7.0104 11.20394 180)
			(size 0.3048 0.3048)
			(layers "F.Cu" "F.Mask" "F.Paste")
			(net "GND")
		)
		(pad "BK21" smd circle
			(at -6.3119 11.20394 180)
			(size 0.3048 0.3048)
			(layers "F.Cu" "F.Mask" "F.Paste")
			(net "GND")
		)
		(pad "BK22" smd circle
			(at -5.61848 11.0744 180)
			(size 0.3048 0.3048)
			(layers "F.Cu" "F.Mask" "F.Paste")
			(net "GND")
		)
		(pad "BK24" smd circle
			(at -4.90982 11.06424 180)
			(size 0.3048 0.3048)
			(layers "F.Cu" "F.Mask" "F.Paste")
			(net "GND")
		)
		(pad "BK26" smd circle
			(at -3.88874 11.06424 180)
			(size 0.3048 0.3048)
			(layers "F.Cu" "F.Mask" "F.Paste")
			(net "GND")
		)
		(pad "BK27" smd circle
			(at -3.18516 11.01344 180)
			(size 0.3048 0.3048)
			(layers "F.Cu" "F.Mask" "F.Paste")
			(net "GND")
		)
		(pad "BK28" smd circle
			(at -2.50952 11.20394 180)
			(size 0.3048 0.3048)
			(layers "F.Cu" "F.Mask" "F.Paste")
			(net "GND")
		)
		(pad "BK30" smd circle
			(at -1.80848 11.20394 180)
			(size 0.3048 0.3048)
			(layers "F.Cu" "F.Mask" "F.Paste")
			(net "GND")
		)
		(pad "BK31" smd circle
			(at -1.11506 11.0744 180)
			(size 0.3048 0.3048)
			(layers "F.Cu" "F.Mask" "F.Paste")
			(net "GND")
		)
		(pad "BK32" smd circle
			(at -0.4064 11.06424 180)
			(size 0.3048 0.3048)
			(layers "F.Cu" "F.Mask" "F.Paste")
			(net "M_A_DQ57")
		)
		(pad "BK35" smd circle
			(at 0.61468 11.06424 180)
			(size 0.3048 0.3048)
			(layers "F.Cu" "F.Mask" "F.Paste")
			(net "M_A_DQ62")
		)
		(pad "BK36" smd circle
			(at 1.31572 11.01344 180)
			(size 0.3048 0.3048)
			(layers "F.Cu" "F.Mask" "F.Paste")
			(net "GND")
		)
		(pad "BK37" smd circle
			(at 1.9939 11.20394 180)
			(size 0.3048 0.3048)
			(layers "F.Cu" "F.Mask" "F.Paste")
			(net "GND")
		)
		(pad "BK39" smd circle
			(at 2.69494 11.20394 180)
			(size 0.3048 0.3048)
			(layers "F.Cu" "F.Mask" "F.Paste")
			(net "GND")
		)
		(pad "BK40" smd circle
			(at 3.38836 11.0744 180)
			(size 0.3048 0.3048)
			(layers "F.Cu" "F.Mask" "F.Paste")
			(net "P2E_CPU_NGFF_C_TX_DN14")
		)
		(pad "BK42" smd circle
			(at 4.09448 11.06424 180)
			(size 0.3048 0.3048)
			(layers "F.Cu" "F.Mask" "F.Paste")
			(net "GND")
		)
		(pad "BK44" smd circle
			(at 5.1181 11.06424 180)
			(size 0.3048 0.3048)
			(layers "F.Cu" "F.Mask" "F.Paste")
			(net "GND")
		)
		(pad "BK45" smd circle
			(at 5.81914 11.01344 180)
			(size 0.3048 0.3048)
			(layers "F.Cu" "F.Mask" "F.Paste")
			(net "GND")
		)
		(pad "BK46" smd circle
			(at 6.49732 11.20394 180)
			(size 0.3048 0.3048)
			(layers "F.Cu" "F.Mask" "F.Paste")
			(net "GND")
		)
		(pad "BK48" smd circle
			(at 7.19836 11.20394 180)
			(size 0.3048 0.3048)
			(layers "F.Cu" "F.Mask" "F.Paste")
			(net "GND")
		)
		(pad "BK49" smd circle
			(at 7.89178 11.07948 180)
			(size 0.3048 0.3048)
			(layers "F.Cu" "F.Mask" "F.Paste")
			(net "GND")
		)
		(pad "BK51" smd circle
			(at 8.5979 11.06424 180)
			(size 0.3048 0.3048)
			(layers "F.Cu" "F.Mask" "F.Paste")
			(net "GND")
		)
		(pad "BK53" smd circle
			(at 9.61898 11.06424 180)
			(size 0.3048 0.3048)
			(layers "F.Cu" "F.Mask" "F.Paste")
			(net "GND")
		)
		(pad "BK54" smd circle
			(at 10.32256 11.01344 180)
			(size 0.3048 0.3048)
			(layers "F.Cu" "F.Mask" "F.Paste")
			(net "P2E_CPU_SAS_C_TX_DN4")
		)
		(pad "BK56" smd circle
			(at 11.00074 11.20394 180)
			(size 0.3048 0.3048)
			(layers "F.Cu" "F.Mask" "F.Paste")
			(net "GND")
		)
		(pad "BK57" smd circle
			(at 11.69924 11.20394 180)
			(size 0.3048 0.3048)
			(layers "F.Cu" "F.Mask" "F.Paste")
			(net "GND")
		)
		(pad "BK58" smd circle
			(at 12.3952 11.07948 180)
			(size 0.3048 0.3048)
			(layers "F.Cu" "F.Mask" "F.Paste")
			(net "GND")
		)
		(pad "BK60" smd circle
			(at 13.10132 11.06424 180)
			(size 0.3048 0.3048)
			(layers "F.Cu" "F.Mask" "F.Paste")
			(net "P2E_CPU_SAS_C_TX_DP0")
		)
		(pad "BK62" smd circle
			(at 14.48562 11.48588 180)
			(size 0.4064 0.4064)
			(layers "F.Cu" "F.Mask" "F.Paste")
			(net "P2E_CPU_SAS_RX_DN2")
		)
		(pad "BK64" smd circle
			(at 15.29842 11.48588 180)
			(size 0.4064 0.4064)
			(layers "F.Cu" "F.Mask" "F.Paste")
			(net "GND")
		)
		(pad "BK66" smd circle
			(at 16.11122 11.48588 180)
			(size 0.4064 0.4064)
			(layers "F.Cu" "F.Mask" "F.Paste")
			(net "GND")
		)
		(pad "BL7" smd circle
			(at -13.40612 11.54176 180)
			(size 0.3048 0.3048)
			(layers "F.Cu" "F.Mask" "F.Paste")
			(net "PV_VDDR")
		)
		(pad "BL8" smd circle
			(at -12.7254 11.75258 180)
			(size 0.3048 0.3048)
			(layers "F.Cu" "F.Mask" "F.Paste")
			(net "M_A_MA1")
		)
		(pad "BL10" smd circle
			(at -11.61034 11.8999 180)
			(size 0.3048 0.3048)
			(layers "F.Cu" "F.Mask" "F.Paste")
			(net "M_A_BS1")
		)
		(pad "BL12" smd circle
			(at -10.72134 11.8999 180)
			(size 0.3048 0.3048)
			(layers "F.Cu" "F.Mask" "F.Paste")
			(net "M_A_BS0")
		)
		(pad "BL14" smd circle
			(at -9.57072 11.79576 180)
			(size 0.3048 0.3048)
			(layers "F.Cu" "F.Mask" "F.Paste")
			(net "GND")
		)
		(pad "BL16" smd circle
			(at -8.9027 11.54176 180)
			(size 0.3048 0.3048)
			(layers "F.Cu" "F.Mask" "F.Paste")
			(net "M_A_DQ40")
		)
		(pad "BL17" smd circle
			(at -8.22198 11.75258 180)
			(size 0.3048 0.3048)
			(layers "F.Cu" "F.Mask" "F.Paste")
			(net "M_A_DQ41")
		)
		(pad "BL19" smd circle
			(at -7.10692 11.8999 180)
			(size 0.3048 0.3048)
			(layers "F.Cu" "F.Mask" "F.Paste")
			(net "GND")
		)
		(pad "BL21" smd circle
			(at -6.21792 11.8999 180)
			(size 0.3048 0.3048)
			(layers "F.Cu" "F.Mask" "F.Paste")
			(net "M_A_DQ42")
		)
		(pad "BL23" smd circle
			(at -5.0673 11.79576 180)
			(size 0.3048 0.3048)
			(layers "F.Cu" "F.Mask" "F.Paste")
			(net "M_A_DQ52")
		)
		(pad "BL25" smd circle
			(at -4.39928 11.54176 180)
			(size 0.3048 0.3048)
			(layers "F.Cu" "F.Mask" "F.Paste")
			(net "GND")
		)
		(pad "BL26" smd circle
			(at -3.71856 11.75258 180)
			(size 0.3048 0.3048)
			(layers "F.Cu" "F.Mask" "F.Paste")
			(net "M_A_DQS_DN6")
		)
		(pad "BL28" smd circle
			(at -2.60604 11.8999 180)
			(size 0.3048 0.3048)
			(layers "F.Cu" "F.Mask" "F.Paste")
			(net "M_A_DQ50")
		)
		(pad "BL30" smd circle
			(at -1.71704 11.8999 180)
			(size 0.3048 0.3048)
			(layers "F.Cu" "F.Mask" "F.Paste")
			(net "GND")
		)
		(pad "BL32" smd circle
			(at -0.56388 11.79576 180)
			(size 0.3048 0.3048)
			(layers "F.Cu" "F.Mask" "F.Paste")
			(net "M_A_DQ61")
		)
		(pad "BL34" smd circle
			(at 0.10414 11.54176 180)
			(size 0.3048 0.3048)
			(layers "F.Cu" "F.Mask" "F.Paste")
			(net "GND")
		)
		(pad "BL35" smd circle
			(at 0.78232 11.75258 180)
			(size 0.3048 0.3048)
			(layers "F.Cu" "F.Mask" "F.Paste")
			(net "M_A_DQ63")
		)
		(pad "BL37" smd circle
			(at 1.89738 11.8999 180)
			(size 0.3048 0.3048)
			(layers "F.Cu" "F.Mask" "F.Paste")
			(net "GND")
		)
		(pad "BL39" smd circle
			(at 2.78638 11.8999 180)
			(size 0.3048 0.3048)
			(layers "F.Cu" "F.Mask" "F.Paste")
			(net "P2E_CPU_NGFF_C_TX_DN15")
		)
		(pad "BL41" smd circle
			(at 3.937 11.79576 180)
			(size 0.3048 0.3048)
			(layers "F.Cu" "F.Mask" "F.Paste")
			(net "P2E_CPU_NGFF_C_TX_DP13")
		)
		(pad "BL43" smd circle
			(at 4.60756 11.54176 180)
			(size 0.3048 0.3048)
			(layers "F.Cu" "F.Mask" "F.Paste")
			(net "GND")
		)
		(pad "BL44" smd circle
			(at 5.28574 11.75258 180)
			(size 0.3048 0.3048)
			(layers "F.Cu" "F.Mask" "F.Paste")
			(net "P2E_CPU_ETH10G_C_TX_DN11")
		)
		(pad "BL46" smd circle
			(at 6.4008 11.8999 180)
			(size 0.3048 0.3048)
			(layers "F.Cu" "F.Mask" "F.Paste")
			(net "P2E_CPU_ETH10G_C_TX_DN10")
		)
		(pad "BL48" smd circle
			(at 7.2898 11.8999 180)
			(size 0.3048 0.3048)
			(layers "F.Cu" "F.Mask" "F.Paste")
			(net "P2E_CPU_ETH10G_C_TX_DN9")
		)
		(pad "BL50" smd circle
			(at 8.44042 11.79576 180)
			(size 0.3048 0.3048)
			(layers "F.Cu" "F.Mask" "F.Paste")
			(net "P2E_CPU_SAS_C_TX_DN7")
		)
		(pad "BL52" smd circle
			(at 9.10844 11.54176 180)
			(size 0.3048 0.3048)
			(layers "F.Cu" "F.Mask" "F.Paste")
			(net "P2E_CPU_SAS_C_TX_DP6")
		)
		(pad "BL53" smd circle
			(at 9.78916 11.75258 180)
			(size 0.3048 0.3048)
			(layers "F.Cu" "F.Mask" "F.Paste")
			(net "P2E_CPU_SAS_C_TX_DN5")
		)
		(pad "BL55" smd circle
			(at 10.90422 11.8999 180)
			(size 0.3048 0.3048)
			(layers "F.Cu" "F.Mask" "F.Paste")
			(net "P2E_CPU_SAS_C_TX_DP3")
		)
		(pad "BL57" smd circle
			(at 11.79322 11.8999 180)
			(size 0.3048 0.3048)
			(layers "F.Cu" "F.Mask" "F.Paste")
			(net "P2E_CPU_SAS_C_TX_DP2")
		)
		(pad "BL59" smd circle
			(at 12.93368 11.75258 180)
			(size 0.3048 0.3048)
			(layers "F.Cu" "F.Mask" "F.Paste")
			(net "P2E_CPU_SAS_C_TX_DP1")
		)
		(pad "BL61" smd circle
			(at 13.61186 11.54176 180)
			(size 0.3048 0.3048)
			(layers "F.Cu" "F.Mask" "F.Paste")
			(net "P2E_CPU_SAS_C_TX_DN0")
		)
		(pad "BM1" smd circle
			(at -16.11122 12.29868 180)
			(size 0.5588 0.5588)
			(layers "F.Cu" "F.Mask" "F.Paste")
			(net "GND")
		)
		(pad "BM3" smd circle
			(at -15.29842 12.29868 180)
			(size 0.4064 0.4064)
			(layers "F.Cu" "F.Mask" "F.Paste")
			(net "GND")
		)
		(pad "BM5" smd circle
			(at -14.48562 12.29868 180)
			(size 0.4064 0.4064)
			(layers "F.Cu" "F.Mask" "F.Paste")
			(net "GND")
		)
		(pad "BM7" smd circle
			(at -13.40612 12.30376 180)
			(size 0.3048 0.3048)
			(layers "F.Cu" "F.Mask" "F.Paste")
			(net "M_A_MA5")
		)
		(pad "BM9" smd circle
			(at -12.22248 12.24788 180)
			(size 0.3048 0.3048)
			(layers "F.Cu" "F.Mask" "F.Paste")
			(net "PV_VDDR")
		)
		(pad "BM13" smd circle
			(at -10.11174 12.2428 180)
			(size 0.3048 0.3048)
			(layers "F.Cu" "F.Mask" "F.Paste")
			(net "CLK_100M_CPU_MPLL0_DN")
		)
		(pad "BM16" smd circle
			(at -8.9535 12.30376 180)
			(size 0.3048 0.3048)
			(layers "F.Cu" "F.Mask" "F.Paste")
			(net "M_A_DQ44")
		)
		(pad "BM18" smd circle
			(at -7.71906 12.24788 180)
			(size 0.3048 0.3048)
			(layers "F.Cu" "F.Mask" "F.Paste")
			(net "M_A_DQS_DP5")
		)
		(pad "BM22" smd circle
			(at -5.60832 12.2428 180)
			(size 0.3048 0.3048)
			(layers "F.Cu" "F.Mask" "F.Paste")
			(net "GND")
		)
		(pad "BM25" smd circle
			(at -4.45008 12.30376 180)
			(size 0.3048 0.3048)
			(layers "F.Cu" "F.Mask" "F.Paste")
			(net "M_A_DQ48")
		)
		(pad "BM27" smd circle
			(at -3.21564 12.24788 180)
			(size 0.3048 0.3048)
			(layers "F.Cu" "F.Mask" "F.Paste")
			(net "M_A_DQ54")
		)
		(pad "BM31" smd circle
			(at -1.1049 12.2428 180)
			(size 0.3048 0.3048)
			(layers "F.Cu" "F.Mask" "F.Paste")
			(net "M_A_DQ60")
		)
		(pad "BM34" smd circle
			(at 0.05334 12.30376 180)
			(size 0.3048 0.3048)
			(layers "F.Cu" "F.Mask" "F.Paste")
			(net "M_A_DQS_DN7")
		)
		(pad "BM36" smd circle
			(at 1.28524 12.24788 180)
			(size 0.3048 0.3048)
			(layers "F.Cu" "F.Mask" "F.Paste")
			(net "M_A_DQ59")
		)
		(pad "BM40" smd circle
			(at 3.39852 12.2428 180)
			(size 0.3048 0.3048)
			(layers "F.Cu" "F.Mask" "F.Paste")
			(net "P2E_CPU_NGFF_C_TX_DP14")
		)
		(pad "BM43" smd circle
			(at 4.55676 12.30376 180)
			(size 0.3048 0.3048)
			(layers "F.Cu" "F.Mask" "F.Paste")
			(net "P2E_CPU_NGFF_C_TX_DN12")
		)
		(pad "BM45" smd circle
			(at 5.78866 12.24788 180)
			(size 0.3048 0.3048)
			(layers "F.Cu" "F.Mask" "F.Paste")
			(net "GND")
		)
		(pad "BM49" smd circle
			(at 7.90194 12.2428 180)
			(size 0.3048 0.3048)
			(layers "F.Cu" "F.Mask" "F.Paste")
			(net "P2E_CPU_ETH10G_C_TX_DN8")
		)
		(pad "BM52" smd circle
			(at 9.05764 12.30376 180)
			(size 0.3048 0.3048)
			(layers "F.Cu" "F.Mask" "F.Paste")
			(net "P2E_CPU_SAS_C_TX_DN6")
		)
		(pad "BM54" smd circle
			(at 10.29208 12.24788 180)
			(size 0.3048 0.3048)
			(layers "F.Cu" "F.Mask" "F.Paste")
			(net "P2E_CPU_SAS_C_TX_DP4")
		)
		(pad "BM58" smd circle
			(at 12.40282 12.2428 180)
			(size 0.3048 0.3048)
			(layers "F.Cu" "F.Mask" "F.Paste")
			(net "P2E_CPU_SAS_C_TX_DN1")
		)
		(pad "BM61" smd circle
			(at 13.61186 12.30376 180)
			(size 0.3048 0.3048)
			(layers "F.Cu" "F.Mask" "F.Paste")
			(net "GND")
		)
		(pad "BM62" smd circle
			(at 14.48562 12.29868 180)
			(size 0.4064 0.4064)
			(layers "F.Cu" "F.Mask" "F.Paste")
			(net "GND")
		)
		(pad "BM64" smd circle
			(at 15.29842 12.29868 180)
			(size 0.4064 0.4064)
			(layers "F.Cu" "F.Mask" "F.Paste")
			(net "GND")
		)
		(pad "BM66" smd circle
			(at 16.11122 12.29868 180)
			(size 0.5588 0.5588)
			(layers "F.Cu" "F.Mask" "F.Paste")
			(net "GND")
		)
		(pad "BN10" smd circle
			(at -11.61796 12.64158 180)
			(size 0.3048 0.3048)
			(layers "F.Cu" "F.Mask" "F.Paste")
			(net "M_A_MA10")
		)
		(pad "BN12" smd circle
			(at -10.69086 12.63904 180)
			(size 0.3048 0.3048)
			(layers "F.Cu" "F.Mask" "F.Paste")
			(net "CLK_100M_CPU_MPLL0_DP")
		)
		(pad "BN14" smd circle
			(at -9.62406 12.75334 180)
			(size 0.3048 0.3048)
			(layers "F.Cu" "F.Mask" "F.Paste")
			(net "GND")
		)
		(pad "BN17" smd circle
			(at -8.14324 12.80668 180)
			(size 0.3048 0.3048)
			(layers "F.Cu" "F.Mask" "F.Paste")
			(net "M_A_DQS_DN5")
		)
		(pad "BN19" smd circle
			(at -7.11454 12.64158 180)
			(size 0.3048 0.3048)
			(layers "F.Cu" "F.Mask" "F.Paste")
			(net "M_A_DQ47")
		)
		(pad "BN21" smd circle
			(at -6.18744 12.63904 180)
			(size 0.3048 0.3048)
			(layers "F.Cu" "F.Mask" "F.Paste")
			(net "M_A_DQ43")
		)
		(pad "BN23" smd circle
			(at -5.12064 12.75334 180)
			(size 0.3048 0.3048)
			(layers "F.Cu" "F.Mask" "F.Paste")
			(net "M_A_DQ53")
		)
		(pad "BN26" smd circle
			(at -3.63982 12.80668 180)
			(size 0.3048 0.3048)
			(layers "F.Cu" "F.Mask" "F.Paste")
			(net "M_A_DQS_DP6")
		)
		(pad "BN28" smd circle
			(at -2.61112 12.64158 180)
			(size 0.3048 0.3048)
			(layers "F.Cu" "F.Mask" "F.Paste")
			(net "M_A_DQ51")
		)
		(pad "BN30" smd circle
			(at -1.68402 12.63904 180)
			(size 0.3048 0.3048)
			(layers "F.Cu" "F.Mask" "F.Paste")
			(net "GND")
		)
		(pad "BN32" smd circle
			(at -0.61722 12.75334 180)
			(size 0.3048 0.3048)
			(layers "F.Cu" "F.Mask" "F.Paste")
			(net "M_A_DQ56")
		)
		(pad "BN35" smd circle
			(at 0.8636 12.80668 180)
			(size 0.3048 0.3048)
			(layers "F.Cu" "F.Mask" "F.Paste")
			(net "M_A_DQ58")
		)
		(pad "BN37" smd circle
			(at 1.8923 12.64158 180)
			(size 0.3048 0.3048)
			(layers "F.Cu" "F.Mask" "F.Paste")
			(net "GND")
		)
		(pad "BN39" smd circle
			(at 2.8194 12.63904 180)
			(size 0.3048 0.3048)
			(layers "F.Cu" "F.Mask" "F.Paste")
			(net "P2E_CPU_NGFF_C_TX_DP15")
		)
		(pad "BN41" smd circle
			(at 3.8862 12.75334 180)
			(size 0.3048 0.3048)
			(layers "F.Cu" "F.Mask" "F.Paste")
			(net "P2E_CPU_NGFF_C_TX_DN13")
		)
		(pad "BN44" smd circle
			(at 5.36448 12.80668 180)
			(size 0.3048 0.3048)
			(layers "F.Cu" "F.Mask" "F.Paste")
			(net "P2E_CPU_ETH10G_C_TX_DP11")
		)
		(pad "BN46" smd circle
			(at 6.39572 12.64158 180)
			(size 0.3048 0.3048)
			(layers "F.Cu" "F.Mask" "F.Paste")
			(net "P2E_CPU_ETH10G_C_TX_DP10")
		)
		(pad "BN48" smd circle
			(at 7.32028 12.63904 180)
			(size 0.3048 0.3048)
			(layers "F.Cu" "F.Mask" "F.Paste")
			(net "P2E_CPU_ETH10G_C_TX_DP9")
		)
		(pad "BN50" smd circle
			(at 8.38708 12.75334 180)
			(size 0.3048 0.3048)
			(layers "F.Cu" "F.Mask" "F.Paste")
			(net "P2E_CPU_SAS_C_TX_DP7")
		)
		(pad "BN53" smd circle
			(at 9.8679 12.80668 180)
			(size 0.3048 0.3048)
			(layers "F.Cu" "F.Mask" "F.Paste")
			(net "P2E_CPU_SAS_C_TX_DP5")
		)
		(pad "BN55" smd circle
			(at 10.8966 12.64158 180)
			(size 0.3048 0.3048)
			(layers "F.Cu" "F.Mask" "F.Paste")
			(net "P2E_CPU_SAS_C_TX_DN3")
		)
		(pad "BN57" smd circle
			(at 11.8237 12.63904 180)
			(size 0.3048 0.3048)
			(layers "F.Cu" "F.Mask" "F.Paste")
			(net "P2E_CPU_SAS_C_TX_DN2")
		)
		(pad "BP1" smd circle
			(at -16.11122 13.11148 180)
			(size 0.5588 0.5588)
			(layers "F.Cu" "F.Mask" "F.Paste")
			(net "GND")
		)
		(pad "BP3" smd circle
			(at -15.29842 13.11148 180)
			(size 0.5588 0.5588)
			(layers "F.Cu" "F.Mask" "F.Paste")
			(net "GND")
		)
		(pad "BP5" smd circle
			(at -14.48562 13.11148 180)
			(size 0.4064 0.4064)
			(layers "F.Cu" "F.Mask" "F.Paste")
			(net "GND")
		)
		(pad "BP6" smd circle
			(at -13.67282 13.11148 180)
			(size 0.4064 0.4064)
			(layers "F.Cu" "F.Mask" "F.Paste")
			(net "M_A_MON1_N")
		)
		(pad "BP8" smd circle
			(at -12.86002 13.11148 180)
			(size 0.4064 0.4064)
			(layers "F.Cu" "F.Mask" "F.Paste")
			(net "M_A_MON1_P")
		)
		(pad "BP10" smd oval
			(at -11.96594 13.24864 180)
			(size 0.254 0.3429)
			(layers "F.Cu" "F.Mask" "F.Paste")
			(net "GND")
		)
		(pad "BP13" smd oval
			(at -10.34034 13.24864 180)
			(size 0.254 0.3429)
			(layers "F.Cu" "F.Mask" "F.Paste")
			(net "GND")
		)
		(pad "BP16" smd oval
			(at -8.9027 13.24864 180)
			(size 0.254 0.3429)
			(layers "F.Cu" "F.Mask" "F.Paste")
			(net "M_A_DQ45")
		)
		(pad "BP19" smd oval
			(at -7.46252 13.24864 180)
			(size 0.254 0.3429)
			(layers "F.Cu" "F.Mask" "F.Paste")
			(net "M_A_DQ46")
		)
		(pad "BP22" smd oval
			(at -5.83692 13.24864 180)
			(size 0.254 0.3429)
			(layers "F.Cu" "F.Mask" "F.Paste")
			(net "GND")
		)
		(pad "BP25" smd oval
			(at -4.39928 13.24864 180)
			(size 0.254 0.3429)
			(layers "F.Cu" "F.Mask" "F.Paste")
			(net "M_A_DQ49")
		)
		(pad "BP28" smd oval
			(at -2.96164 13.24864 180)
			(size 0.254 0.3429)
			(layers "F.Cu" "F.Mask" "F.Paste")
			(net "M_A_DQ55")
		)
		(pad "BP31" smd oval
			(at -1.33604 13.24864 180)
			(size 0.254 0.3429)
			(layers "F.Cu" "F.Mask" "F.Paste")
			(net "GND")
		)
		(pad "BP34" smd oval
			(at 0.10414 13.24864 180)
			(size 0.254 0.3429)
			(layers "F.Cu" "F.Mask" "F.Paste")
			(net "M_A_DQS_DP7")
		)
		(pad "BP37" smd oval
			(at 1.54178 13.24864 180)
			(size 0.254 0.3429)
			(layers "F.Cu" "F.Mask" "F.Paste")
			(net "GND")
		)
		(pad "BP40" smd oval
			(at 3.16738 13.24864 180)
			(size 0.254 0.3429)
			(layers "F.Cu" "F.Mask" "F.Paste")
			(net "GND")
		)
		(pad "BP43" smd oval
			(at 4.60756 13.24864 180)
			(size 0.254 0.3429)
			(layers "F.Cu" "F.Mask" "F.Paste")
			(net "P2E_CPU_NGFF_C_TX_DP12")
		)
		(pad "BP46" smd oval
			(at 6.0452 13.24864 180)
			(size 0.254 0.3429)
			(layers "F.Cu" "F.Mask" "F.Paste")
			(net "GND")
		)
		(pad "BP49" smd oval
			(at 7.6708 13.24864 180)
			(size 0.254 0.3429)
			(layers "F.Cu" "F.Mask" "F.Paste")
			(net "P2E_CPU_ETH10G_C_TX_DP8")
		)
		(pad "BP52" smd oval
			(at 9.10844 13.24864 180)
			(size 0.254 0.3429)
			(layers "F.Cu" "F.Mask" "F.Paste")
			(net "GND")
		)
		(pad "BP55" smd oval
			(at 10.54862 13.24864 180)
			(size 0.254 0.3429)
			(layers "F.Cu" "F.Mask" "F.Paste")
			(net "GND")
		)
		(pad "BP58" smd oval
			(at 12.17422 13.24864 180)
			(size 0.254 0.3429)
			(layers "F.Cu" "F.Mask" "F.Paste")
			(net "GND")
		)
		(pad "BP59" smd circle
			(at 12.86002 13.11148 180)
			(size 0.4064 0.4064)
			(layers "F.Cu" "F.Mask" "F.Paste")
			(net "GND")
		)
		(pad "BP61" smd circle
			(at 13.67282 13.11148 180)
			(size 0.4064 0.4064)
			(layers "F.Cu" "F.Mask" "F.Paste")
			(net "GND")
		)
		(pad "BP62" smd circle
			(at 14.48562 13.11148 180)
			(size 0.4064 0.4064)
			(layers "F.Cu" "F.Mask" "F.Paste")
			(net "GND")
		)
		(pad "BP64" smd circle
			(at 15.29842 13.11148 180)
			(size 0.5588 0.5588)
			(layers "F.Cu" "F.Mask" "F.Paste")
			(net "GND")
		)
		(pad "BP66" smd circle
			(at 16.11122 13.11148 180)
			(size 0.5588 0.5588)
			(layers "F.Cu" "F.Mask" "F.Paste")
			(net "GND")
		)
		(pad "C3" smd circle
			(at -15.29842 -12.29868 180)
			(size 0.5588 0.5588)
			(layers "F.Cu" "F.Mask" "F.Paste")
			(net "GND")
		)
		(pad "C5" smd circle
			(at -14.48562 -12.29868 180)
			(size 0.4064 0.4064)
			(layers "F.Cu" "F.Mask" "F.Paste")
			(net "M_B_MON1_N")
		)
		(pad "C6" smd circle
			(at -13.61186 -12.30376 180)
			(size 0.3048 0.3048)
			(layers "F.Cu" "F.Mask" "F.Paste")
			(net "GND")
		)
		(pad "C9" smd circle
			(at -12.40282 -12.2428 180)
			(size 0.3048 0.3048)
			(layers "F.Cu" "F.Mask" "F.Paste")
			(net "M_B_CK_DP0")
		)
		(pad "C13" smd circle
			(at -10.29208 -12.24788 180)
			(size 0.3048 0.3048)
			(layers "F.Cu" "F.Mask" "F.Paste")
			(net "M_B_ECC6")
		)
		(pad "C15" smd circle
			(at -9.05764 -12.30376 180)
			(size 0.3048 0.3048)
			(layers "F.Cu" "F.Mask" "F.Paste")
			(net "M_B_ECC1")
		)
		(pad "C18" smd circle
			(at -7.90194 -12.2428 180)
			(size 0.3048 0.3048)
			(layers "F.Cu" "F.Mask" "F.Paste")
			(net "GND")
		)
		(pad "C22" smd circle
			(at -5.78866 -12.24788 180)
			(size 0.3048 0.3048)
			(layers "F.Cu" "F.Mask" "F.Paste")
			(net "M_B_DQS_DN2")
		)
		(pad "C24" smd circle
			(at -4.55676 -12.30376 180)
			(size 0.3048 0.3048)
			(layers "F.Cu" "F.Mask" "F.Paste")
			(net "M_B_DQ20")
		)
		(pad "C27" smd circle
			(at -3.39852 -12.2428 180)
			(size 0.3048 0.3048)
			(layers "F.Cu" "F.Mask" "F.Paste")
			(net "M_B_DQ11")
		)
		(pad "C31" smd circle
			(at -1.28524 -12.24788 180)
			(size 0.3048 0.3048)
			(layers "F.Cu" "F.Mask" "F.Paste")
			(net "M_B_DQ9")
		)
		(pad "C33" smd circle
			(at -0.05334 -12.30376 180)
			(size 0.3048 0.3048)
			(layers "F.Cu" "F.Mask" "F.Paste")
			(net "GND")
		)
		(pad "C36" smd circle
			(at 1.1049 -12.2428 180)
			(size 0.3048 0.3048)
			(layers "F.Cu" "F.Mask" "F.Paste")
			(net "M_B_DQ7")
		)
		(pad "C40" smd circle
			(at 3.21564 -12.24788 180)
			(size 0.3048 0.3048)
			(layers "F.Cu" "F.Mask" "F.Paste")
			(net "M_B_DQ5")
		)
		(pad "C42" smd circle
			(at 4.45008 -12.30376 180)
			(size 0.3048 0.3048)
			(layers "F.Cu" "F.Mask" "F.Paste")
			(net "Net_1364")
		)
		(pad "C45" smd circle
			(at 5.60832 -12.2428 180)
			(size 0.3048 0.3048)
			(layers "F.Cu" "F.Mask" "F.Paste")
			(net "GND")
		)
		(pad "C49" smd circle
			(at 7.71906 -12.24788 180)
			(size 0.3048 0.3048)
			(layers "F.Cu" "F.Mask" "F.Paste")
			(net "GND")
		)
		(pad "C51" smd circle
			(at 8.9535 -12.30376 180)
			(size 0.3048 0.3048)
			(layers "F.Cu" "F.Mask" "F.Paste")
			(net "GND")
		)
		(pad "C54" smd circle
			(at 10.11174 -12.2428 180)
			(size 0.3048 0.3048)
			(layers "F.Cu" "F.Mask" "F.Paste")
			(net "Net_1351")
		)
		(pad "C58" smd circle
			(at 12.22248 -12.24788 180)
			(size 0.3048 0.3048)
			(layers "F.Cu" "F.Mask" "F.Paste")
			(net "GND")
		)
		(pad "C60" smd circle
			(at 13.40612 -12.30376 180)
			(size 0.3048 0.3048)
			(layers "F.Cu" "F.Mask" "F.Paste")
			(net "Net_1358")
		)
		(pad "C62" smd circle
			(at 14.48562 -12.29868 180)
			(size 0.4064 0.4064)
			(layers "F.Cu" "F.Mask" "F.Paste")
			(net "Net_1357")
		)
		(pad "C64" smd circle
			(at 15.29842 -12.29868 180)
			(size 0.4064 0.4064)
			(layers "F.Cu" "F.Mask" "F.Paste")
			(net "GND")
		)
		(pad "C66" smd circle
			(at 16.11122 -12.29868 180)
			(size 0.5588 0.5588)
			(layers "F.Cu" "F.Mask" "F.Paste")
			(net "GND")
		)
		(pad "D6" smd circle
			(at -13.61186 -11.54176 180)
			(size 0.3048 0.3048)
			(layers "F.Cu" "F.Mask" "F.Paste")
			(net "GND")
		)
		(pad "D8" smd circle
			(at -12.93368 -11.75258 180)
			(size 0.3048 0.3048)
			(layers "F.Cu" "F.Mask" "F.Paste")
			(net "M_B_CK_DN0")
		)
		(pad "D10" smd circle
			(at -11.79322 -11.8999 180)
			(size 0.3048 0.3048)
			(layers "F.Cu" "F.Mask" "F.Paste")
			(net "GND")
		)
		(pad "D12" smd circle
			(at -10.90422 -11.8999 180)
			(size 0.3048 0.3048)
			(layers "F.Cu" "F.Mask" "F.Paste")
			(net "M_B_ECC2")
		)
		(pad "D14" smd circle
			(at -9.78916 -11.75258 180)
			(size 0.3048 0.3048)
			(layers "F.Cu" "F.Mask" "F.Paste")
			(net "M_B_DQS_DN8")
		)
		(pad "D15" smd circle
			(at -9.10844 -11.54176 180)
			(size 0.3048 0.3048)
			(layers "F.Cu" "F.Mask" "F.Paste")
			(net "M_B_ECC0")
		)
		(pad "D17" smd circle
			(at -8.44042 -11.79576 180)
			(size 0.3048 0.3048)
			(layers "F.Cu" "F.Mask" "F.Paste")
			(net "M_B_ECC4")
		)
		(pad "D19" smd circle
			(at -7.2898 -11.8999 180)
			(size 0.3048 0.3048)
			(layers "F.Cu" "F.Mask" "F.Paste")
			(net "M_B_DQ18")
		)
		(pad "D21" smd circle
			(at -6.4008 -11.8999 180)
			(size 0.3048 0.3048)
			(layers "F.Cu" "F.Mask" "F.Paste")
			(net "M_B_DQ23")
		)
		(pad "D23" smd circle
			(at -5.28574 -11.75258 180)
			(size 0.3048 0.3048)
			(layers "F.Cu" "F.Mask" "F.Paste")
			(net "M_B_DQ16")
		)
		(pad "D24" smd circle
			(at -4.60756 -11.54176 180)
			(size 0.3048 0.3048)
			(layers "F.Cu" "F.Mask" "F.Paste")
			(net "M_B_DQ21")
		)
		(pad "D26" smd circle
			(at -3.937 -11.79576 180)
			(size 0.3048 0.3048)
			(layers "F.Cu" "F.Mask" "F.Paste")
			(net "GND")
		)
		(pad "D28" smd circle
			(at -2.78638 -11.8999 180)
			(size 0.3048 0.3048)
			(layers "F.Cu" "F.Mask" "F.Paste")
			(net "M_B_DQ14")
		)
		(pad "D30" smd circle
			(at -1.89738 -11.8999 180)
			(size 0.3048 0.3048)
			(layers "F.Cu" "F.Mask" "F.Paste")
			(net "M_B_DQS_DP1")
		)
		(pad "D32" smd circle
			(at -0.78232 -11.75258 180)
			(size 0.3048 0.3048)
			(layers "F.Cu" "F.Mask" "F.Paste")
			(net "M_B_DQ13")
		)
		(pad "D33" smd circle
			(at -0.10414 -11.54176 180)
			(size 0.3048 0.3048)
			(layers "F.Cu" "F.Mask" "F.Paste")
			(net "GND")
		)
		(pad "D35" smd circle
			(at 0.56388 -11.79576 180)
			(size 0.3048 0.3048)
			(layers "F.Cu" "F.Mask" "F.Paste")
			(net "M_B_DQ3")
		)
		(pad "D37" smd circle
			(at 1.71704 -11.8999 180)
			(size 0.3048 0.3048)
			(layers "F.Cu" "F.Mask" "F.Paste")
			(net "M_B_DQS_DP0")
		)
		(pad "D39" smd circle
			(at 2.60604 -11.8999 180)
			(size 0.3048 0.3048)
			(layers "F.Cu" "F.Mask" "F.Paste")
			(net "M_B_DQ1")
		)
		(pad "D41" smd circle
			(at 3.71856 -11.75258 180)
			(size 0.3048 0.3048)
			(layers "F.Cu" "F.Mask" "F.Paste")
			(net "GND")
		)
		(pad "D42" smd circle
			(at 4.39928 -11.54176 180)
			(size 0.3048 0.3048)
			(layers "F.Cu" "F.Mask" "F.Paste")
			(net "GND")
		)
		(pad "D44" smd circle
			(at 5.0673 -11.79576 180)
			(size 0.3048 0.3048)
			(layers "F.Cu" "F.Mask" "F.Paste")
			(net "Net_1362")
		)
		(pad "D46" smd circle
			(at 6.21792 -11.8999 180)
			(size 0.3048 0.3048)
			(layers "F.Cu" "F.Mask" "F.Paste")
			(net "Net_278")
		)
		(pad "D48" smd circle
			(at 7.10692 -11.8999 180)
			(size 0.3048 0.3048)
			(layers "F.Cu" "F.Mask" "F.Paste")
			(net "CPU_GBE_TX_DP0")
		)
		(pad "D50" smd circle
			(at 8.22198 -11.75258 180)
			(size 0.3048 0.3048)
			(layers "F.Cu" "F.Mask" "F.Paste")
			(net "CLK_100M_CPU_GBE_DN")
		)
		(pad "D51" smd circle
			(at 8.9027 -11.54176 180)
			(size 0.3048 0.3048)
			(layers "F.Cu" "F.Mask" "F.Paste")
			(net "GND")
		)
		(pad "D53" smd circle
			(at 9.57072 -11.79576 180)
			(size 0.3048 0.3048)
			(layers "F.Cu" "F.Mask" "F.Paste")
			(net "Net_1350")
		)
		(pad "D55" smd circle
			(at 10.72134 -11.8999 180)
			(size 0.3048 0.3048)
			(layers "F.Cu" "F.Mask" "F.Paste")
			(net "GND")
		)
		(pad "D57" smd circle
			(at 11.61034 -11.8999 180)
			(size 0.3048 0.3048)
			(layers "F.Cu" "F.Mask" "F.Paste")
			(net "SATA2_TX_DN0")
		)
		(pad "D59" smd circle
			(at 12.7254 -11.75258 180)
			(size 0.3048 0.3048)
			(layers "F.Cu" "F.Mask" "F.Paste")
			(net "GND")
		)
		(pad "D60" smd circle
			(at 13.40612 -11.54176 180)
			(size 0.3048 0.3048)
			(layers "F.Cu" "F.Mask" "F.Paste")
			(net "Net_1354")
		)
		(pad "E1" smd circle
			(at -16.11122 -11.48588 180)
			(size 0.5588 0.5588)
			(layers "F.Cu" "F.Mask" "F.Paste")
			(net "GND")
		)
		(pad "E3" smd circle
			(at -15.29842 -11.48588 180)
			(size 0.4064 0.4064)
			(layers "F.Cu" "F.Mask" "F.Paste")
			(net "GND")
		)
		(pad "E5" smd circle
			(at -14.48562 -11.48588 180)
			(size 0.4064 0.4064)
			(layers "F.Cu" "F.Mask" "F.Paste")
			(net "M_B_MON1_P")
		)
		(pad "E7" smd circle
			(at -13.10132 -11.06424 180)
			(size 0.3048 0.3048)
			(layers "F.Cu" "F.Mask" "F.Paste")
			(net "PV_VDDR")
		)
		(pad "E9" smd circle
			(at -12.3952 -11.07948 180)
			(size 0.3048 0.3048)
			(layers "F.Cu" "F.Mask" "F.Paste")
			(net "PV_VDDR")
		)
		(pad "E10" smd circle
			(at -11.69924 -11.20394 180)
			(size 0.3048 0.3048)
			(layers "F.Cu" "F.Mask" "F.Paste")
			(net "GND")
		)
		(pad "E12" smd circle
			(at -11.00074 -11.20394 180)
			(size 0.3048 0.3048)
			(layers "F.Cu" "F.Mask" "F.Paste")
			(net "M_B_ECC3")
		)
		(pad "E13" smd circle
			(at -10.32256 -11.01344 180)
			(size 0.3048 0.3048)
			(layers "F.Cu" "F.Mask" "F.Paste")
			(net "GND")
		)
		(pad "E14" smd circle
			(at -9.61898 -11.06424 180)
			(size 0.3048 0.3048)
			(layers "F.Cu" "F.Mask" "F.Paste")
			(net "GND")
		)
		(pad "E16" smd circle
			(at -8.5979 -11.06424 180)
			(size 0.3048 0.3048)
			(layers "F.Cu" "F.Mask" "F.Paste")
			(net "GND")
		)
		(pad "E18" smd circle
			(at -7.89178 -11.07948 180)
			(size 0.3048 0.3048)
			(layers "F.Cu" "F.Mask" "F.Paste")
			(net "GND")
		)
		(pad "E19" smd circle
			(at -7.19836 -11.20394 180)
			(size 0.3048 0.3048)
			(layers "F.Cu" "F.Mask" "F.Paste")
			(net "GND")
		)
		(pad "E21" smd circle
			(at -6.49732 -11.20394 180)
			(size 0.3048 0.3048)
			(layers "F.Cu" "F.Mask" "F.Paste")
			(net "GND")
		)
		(pad "E22" smd circle
			(at -5.81914 -11.01344 180)
			(size 0.3048 0.3048)
			(layers "F.Cu" "F.Mask" "F.Paste")
			(net "GND")
		)
		(pad "E23" smd circle
			(at -5.1181 -11.06424 180)
			(size 0.3048 0.3048)
			(layers "F.Cu" "F.Mask" "F.Paste")
			(net "GND")
		)
		(pad "E25" smd circle
			(at -4.09448 -11.06424 180)
			(size 0.3048 0.3048)
			(layers "F.Cu" "F.Mask" "F.Paste")
			(net "GND")
		)
		(pad "E27" smd circle
			(at -3.38836 -11.07948 180)
			(size 0.3048 0.3048)
			(layers "F.Cu" "F.Mask" "F.Paste")
			(net "GND")
		)
		(pad "E28" smd circle
			(at -2.69494 -11.20394 180)
			(size 0.3048 0.3048)
			(layers "F.Cu" "F.Mask" "F.Paste")
			(net "GND")
		)
		(pad "E30" smd circle
			(at -1.9939 -11.20394 180)
			(size 0.3048 0.3048)
			(layers "F.Cu" "F.Mask" "F.Paste")
			(net "GND")
		)
		(pad "E31" smd circle
			(at -1.31572 -11.01344 180)
			(size 0.3048 0.3048)
			(layers "F.Cu" "F.Mask" "F.Paste")
			(net "GND")
		)
		(pad "E32" smd circle
			(at -0.61468 -11.06424 180)
			(size 0.3048 0.3048)
			(layers "F.Cu" "F.Mask" "F.Paste")
			(net "M_B_DQ12")
		)
		(pad "E34" smd circle
			(at 0.4064 -11.06424 180)
			(size 0.3048 0.3048)
			(layers "F.Cu" "F.Mask" "F.Paste")
			(net "GND")
		)
		(pad "E36" smd circle
			(at 1.11506 -11.0744 180)
			(size 0.3048 0.3048)
			(layers "F.Cu" "F.Mask" "F.Paste")
			(net "GND")
		)
		(pad "E37" smd circle
			(at 1.80848 -11.20394 180)
			(size 0.3048 0.3048)
			(layers "F.Cu" "F.Mask" "F.Paste")
			(net "GND")
		)
		(pad "E39" smd circle
			(at 2.50952 -11.20394 180)
			(size 0.3048 0.3048)
			(layers "F.Cu" "F.Mask" "F.Paste")
			(net "GND")
		)
		(pad "E40" smd circle
			(at 3.18516 -11.01344 180)
			(size 0.3048 0.3048)
			(layers "F.Cu" "F.Mask" "F.Paste")
			(net "GND")
		)
		(pad "E41" smd circle
			(at 3.88874 -11.06424 180)
			(size 0.3048 0.3048)
			(layers "F.Cu" "F.Mask" "F.Paste")
			(net "GND")
		)
		(pad "E43" smd circle
			(at 4.90982 -11.06424 180)
			(size 0.3048 0.3048)
			(layers "F.Cu" "F.Mask" "F.Paste")
			(net "GND")
		)
		(pad "E45" smd circle
			(at 5.61848 -11.07948 180)
			(size 0.3048 0.3048)
			(layers "F.Cu" "F.Mask" "F.Paste")
			(net "GND")
		)
		(pad "E46" smd circle
			(at 6.3119 -11.20394 180)
			(size 0.3048 0.3048)
			(layers "F.Cu" "F.Mask" "F.Paste")
			(net "GND")
		)
		(pad "E48" smd circle
			(at 7.0104 -11.20394 180)
			(size 0.3048 0.3048)
			(layers "F.Cu" "F.Mask" "F.Paste")
			(net "GND")
		)
		(pad "E49" smd circle
			(at 7.68858 -11.01344 180)
			(size 0.3048 0.3048)
			(layers "F.Cu" "F.Mask" "F.Paste")
			(net "GND")
		)
		(pad "E50" smd circle
			(at 8.39216 -11.06424 180)
			(size 0.3048 0.3048)
			(layers "F.Cu" "F.Mask" "F.Paste")
			(net "GND")
		)
		(pad "E52" smd circle
			(at 9.41324 -11.06424 180)
			(size 0.3048 0.3048)
			(layers "F.Cu" "F.Mask" "F.Paste")
			(net "GND")
		)
		(pad "E54" smd circle
			(at 10.11936 -11.07948 180)
			(size 0.3048 0.3048)
			(layers "F.Cu" "F.Mask" "F.Paste")
			(net "GND")
		)
		(pad "E55" smd circle
			(at 10.81532 -11.20394 180)
			(size 0.3048 0.3048)
			(layers "F.Cu" "F.Mask" "F.Paste")
			(net "GND")
		)
		(pad "E57" smd circle
			(at 11.51382 -11.20394 180)
			(size 0.3048 0.3048)
			(layers "F.Cu" "F.Mask" "F.Paste")
			(net "Net_1347")
		)
		(pad "E58" smd circle
			(at 12.192 -11.01344 180)
			(size 0.3048 0.3048)
			(layers "F.Cu" "F.Mask" "F.Paste")
			(net "Net_1355")
		)
		(pad "E59" smd circle
			(at 12.89558 -11.06424 180)
			(size 0.3048 0.3048)
			(layers "F.Cu" "F.Mask" "F.Paste")
			(net "GND")
		)
		(pad "E61" smd circle
			(at 13.91666 -11.06424 180)
			(size 0.3048 0.3048)
			(layers "F.Cu" "F.Mask" "F.Paste")
			(net "GND")
		)
		(pad "E62" smd circle
			(at 14.48562 -11.48588 180)
			(size 0.4064 0.4064)
			(layers "F.Cu" "F.Mask" "F.Paste")
			(net "Net_1352")
		)
		(pad "E64" smd circle
			(at 15.29842 -11.48588 180)
			(size 0.4064 0.4064)
			(layers "F.Cu" "F.Mask" "F.Paste")
			(net "GND")
		)
		(pad "E66" smd circle
			(at 16.11122 -11.48588 180)
			(size 0.4064 0.4064)
			(layers "F.Cu" "F.Mask" "F.Paste")
			(net "GND")
		)
		(pad "F1" smd circle
			(at -16.11122 -10.67308 180)
			(size 0.4064 0.4064)
			(layers "F.Cu" "F.Mask" "F.Paste")
			(net "GND")
		)
		(pad "F4" smd circle
			(at -14.89964 -10.69594 180)
			(size 0.3048 0.3048)
			(layers "F.Cu" "F.Mask" "F.Paste")
			(net "GND")
		)
		(pad "F5" smd circle
			(at -14.20368 -10.81278 180)
			(size 0.3048 0.3048)
			(layers "F.Cu" "F.Mask" "F.Paste")
			(net "GND")
		)
		(pad "F63" smd circle
			(at 14.89964 -10.90422 180)
			(size 0.3048 0.3048)
			(layers "F.Cu" "F.Mask" "F.Paste")
			(net "GND")
		)
		(pad "F66" smd circle
			(at 16.11122 -10.67308 180)
			(size 0.4064 0.4064)
			(layers "F.Cu" "F.Mask" "F.Paste")
			(net "GND")
		)
		(pad "G3" smd circle
			(at -15.29842 -10.1092 180)
			(size 0.3048 0.3048)
			(layers "F.Cu" "F.Mask" "F.Paste")
			(net "M_B_MA13")
		)
		(pad "G5" smd circle
			(at -14.08176 -10.11936 180)
			(size 0.3048 0.3048)
			(layers "F.Cu" "F.Mask" "F.Paste")
			(net "PV_VDDR")
		)
		(pad "G7" smd circle
			(at -13.34516 -10.16254 180)
			(size 0.3048 0.3048)
			(layers "F.Cu" "F.Mask" "F.Paste")
			(net "PV_VDDR")
		)
		(pad "G9" smd circle
			(at -12.38758 -10.34542 180)
			(size 0.3048 0.3048)
			(layers "F.Cu" "F.Mask" "F.Paste")
			(net "M_B_CK_DP1")
		)
		(pad "G10" smd circle
			(at -11.68654 -10.34542 180)
			(size 0.3048 0.3048)
			(layers "F.Cu" "F.Mask" "F.Paste")
			(net "M_B_CK_DN2")
		)
		(pad "G17" smd circle
			(at -8.41502 -10.34542 180)
			(size 0.3048 0.3048)
			(layers "F.Cu" "F.Mask" "F.Paste")
			(net "M_B_MA1")
		)
		(pad "G18" smd circle
			(at -7.71398 -10.34542 180)
			(size 0.3048 0.3048)
			(layers "F.Cu" "F.Mask" "F.Paste")
			(net "M_B_MA2")
		)
		(pad "G25" smd circle
			(at -4.44246 -10.34542 180)
			(size 0.3048 0.3048)
			(layers "F.Cu" "F.Mask" "F.Paste")
			(net "M_B_MA12")
		)
		(pad "G26" smd circle
			(at -3.74142 -10.34542 180)
			(size 0.3048 0.3048)
			(layers "F.Cu" "F.Mask" "F.Paste")
			(net "M_B_MA14")
		)
		(pad "G32" smd circle
			(at -0.4699 -10.34542 180)
			(size 0.3048 0.3048)
			(layers "F.Cu" "F.Mask" "F.Paste")
			(net "GND")
		)
		(pad "G34" smd circle
			(at 0.23114 -10.34542 180)
			(size 0.3048 0.3048)
			(layers "F.Cu" "F.Mask" "F.Paste")
			(net "GND")
		)
		(pad "G41" smd circle
			(at 3.50266 -10.34542 180)
			(size 0.3048 0.3048)
			(layers "F.Cu" "F.Mask" "F.Paste")
			(net "GND")
		)
		(pad "G42" smd circle
			(at 4.2037 -10.34542 180)
			(size 0.3048 0.3048)
			(layers "F.Cu" "F.Mask" "F.Paste")
			(net "Net_1359")
		)
		(pad "G48" smd circle
			(at 7.47522 -10.34542 180)
			(size 0.3048 0.3048)
			(layers "F.Cu" "F.Mask" "F.Paste")
			(net "GND")
		)
		(pad "G50" smd circle
			(at 8.17626 -10.34542 180)
			(size 0.3048 0.3048)
			(layers "F.Cu" "F.Mask" "F.Paste")
			(net "GBE_OBSP")
		)
		(pad "G56" smd circle
			(at 11.44778 -10.34542 180)
			(size 0.3048 0.3048)
			(layers "F.Cu" "F.Mask" "F.Paste")
			(net "GND")
		)
		(pad "G59" smd circle
			(at 12.58316 -10.34542 180)
			(size 0.3048 0.3048)
			(layers "F.Cu" "F.Mask" "F.Paste")
			(net "GND")
		)
		(pad "G62" smd circle
			(at 14.01318 -10.32256 180)
			(size 0.3048 0.3048)
			(layers "F.Cu" "F.Mask" "F.Paste")
			(net "Net_1356")
		)
		(pad "G64" smd circle
			(at 15.29842 -10.31748 180)
			(size 0.3048 0.3048)
			(layers "F.Cu" "F.Mask" "F.Paste")
			(net "Net_1353")
		)
		(pad "H1" smd circle
			(at -16.11122 -9.86028 180)
			(size 0.4064 0.4064)
			(layers "F.Cu" "F.Mask" "F.Paste")
			(net "GND")
		)
		(pad "H4" smd circle
			(at -14.75232 -9.58088 180)
			(size 0.3048 0.3048)
			(layers "F.Cu" "F.Mask" "F.Paste")
			(net "M_B_CAS#")
		)
		(pad "H9" smd circle
			(at -12.38758 -9.58342 180)
			(size 0.3048 0.3048)
			(layers "F.Cu" "F.Mask" "F.Paste")
			(net "M_B_CK_DN1")
		)
		(pad "H10" smd circle
			(at -11.68654 -9.58342 180)
			(size 0.3048 0.3048)
			(layers "F.Cu" "F.Mask" "F.Paste")
			(net "M_B_CK_DP2")
		)
		(pad "H13" smd circle
			(at -10.4013 -9.96442 180)
			(size 0.3048 0.3048)
			(layers "F.Cu" "F.Mask" "F.Paste")
			(net "PV_VDDR")
		)
		(pad "H14" smd circle
			(at -9.70026 -9.96442 180)
			(size 0.3048 0.3048)
			(layers "F.Cu" "F.Mask" "F.Paste")
			(net "PV_VDDR")
		)
		(pad "H17" smd circle
			(at -8.41502 -9.58342 180)
			(size 0.3048 0.3048)
			(layers "F.Cu" "F.Mask" "F.Paste")
			(net "M_B_MA0")
		)
		(pad "H18" smd circle
			(at -7.71398 -9.58342 180)
			(size 0.3048 0.3048)
			(layers "F.Cu" "F.Mask" "F.Paste")
			(net "M_B_BS1")
		)
		(pad "H21" smd circle
			(at -6.42874 -9.96442 180)
			(size 0.3048 0.3048)
			(layers "F.Cu" "F.Mask" "F.Paste")
			(net "M_B_MA8")
		)
		(pad "H22" smd circle
			(at -5.7277 -9.96442 180)
			(size 0.3048 0.3048)
			(layers "F.Cu" "F.Mask" "F.Paste")
			(net "M_B_MA5")
		)
		(pad "H25" smd circle
			(at -4.44246 -9.58342 180)
			(size 0.3048 0.3048)
			(layers "F.Cu" "F.Mask" "F.Paste")
			(net "M_B_BS2")
		)
		(pad "H26" smd circle
			(at -3.74142 -9.58342 180)
			(size 0.3048 0.3048)
			(layers "F.Cu" "F.Mask" "F.Paste")
			(net "M_B_MA15")
		)
		(pad "H29" smd circle
			(at -2.45618 -9.96442 180)
			(size 0.3048 0.3048)
			(layers "F.Cu" "F.Mask" "F.Paste")
			(net "M_B_DQ25")
		)
		(pad "H30" smd circle
			(at -1.75514 -9.96442 180)
			(size 0.3048 0.3048)
			(layers "F.Cu" "F.Mask" "F.Paste")
			(net "M_B_DQ24")
		)
		(pad "H32" smd circle
			(at -0.4699 -9.58342 180)
			(size 0.3048 0.3048)
			(layers "F.Cu" "F.Mask" "F.Paste")
			(net "M_B_DQ28")
		)
		(pad "H34" smd circle
			(at 0.23114 -9.58342 180)
			(size 0.3048 0.3048)
			(layers "F.Cu" "F.Mask" "F.Paste")
			(net "GND")
		)
		(pad "H37" smd circle
			(at 1.51638 -9.96442 180)
			(size 0.3048 0.3048)
			(layers "F.Cu" "F.Mask" "F.Paste")
			(net "GND")
		)
		(pad "H38" smd circle
			(at 2.21742 -9.96442 180)
			(size 0.3048 0.3048)
			(layers "F.Cu" "F.Mask" "F.Paste")
			(net "GND")
		)
		(pad "H41" smd circle
			(at 3.50266 -9.58342 180)
			(size 0.3048 0.3048)
			(layers "F.Cu" "F.Mask" "F.Paste")
			(net "GND")
		)
		(pad "H42" smd circle
			(at 4.2037 -9.58342 180)
			(size 0.3048 0.3048)
			(layers "F.Cu" "F.Mask" "F.Paste")
			(net "Net_1360")
		)
		(pad "H44" smd circle
			(at 5.48894 -9.96442 180)
			(size 0.3048 0.3048)
			(layers "F.Cu" "F.Mask" "F.Paste")
			(net "GND")
		)
		(pad "H46" smd circle
			(at 6.18998 -9.96442 180)
			(size 0.3048 0.3048)
			(layers "F.Cu" "F.Mask" "F.Paste")
			(net "GND")
		)
		(pad "H48" smd circle
			(at 7.47522 -9.58342 180)
			(size 0.3048 0.3048)
			(layers "F.Cu" "F.Mask" "F.Paste")
			(net "CPU_GBE_RX_DP0")
		)
		(pad "H50" smd circle
			(at 8.17626 -9.58342 180)
			(size 0.3048 0.3048)
			(layers "F.Cu" "F.Mask" "F.Paste")
			(net "GBE_OBSN")
		)
		(pad "H52" smd circle
			(at 9.4615 -9.96442 180)
			(size 0.3048 0.3048)
			(layers "F.Cu" "F.Mask" "F.Paste")
			(net "GND")
		)
		(pad "H54" smd circle
			(at 10.16254 -9.96442 180)
			(size 0.3048 0.3048)
			(layers "F.Cu" "F.Mask" "F.Paste")
			(net "GND")
		)
		(pad "H56" smd circle
			(at 11.44778 -9.58342 180)
			(size 0.3048 0.3048)
			(layers "F.Cu" "F.Mask" "F.Paste")
			(net "GND")
		)
		(pad "H58" smd circle
			(at 12.20216 -9.70026 180)
			(size 0.3048 0.3048)
			(layers "F.Cu" "F.Mask" "F.Paste")
			(net "GND")
		)
		(pad "H59" smd circle
			(at 12.96416 -9.70026 180)
			(size 0.3048 0.3048)
			(layers "F.Cu" "F.Mask" "F.Paste")
			(net "GND")
		)
		(pad "H62" smd circle
			(at 14.06398 -9.62152 180)
			(size 0.3048 0.3048)
			(layers "F.Cu" "F.Mask" "F.Paste")
			(net "SATA2_RX_DP0")
		)
		(pad "H63" smd circle
			(at 14.75232 -9.78916 180)
			(size 0.3048 0.3048)
			(layers "F.Cu" "F.Mask" "F.Paste")
			(net "SATA2_RX_DN0")
		)
		(pad "H66" smd circle
			(at 16.11122 -9.86028 180)
			(size 0.4064 0.4064)
			(layers "F.Cu" "F.Mask" "F.Paste")
			(net "GND")
		)
		(pad "J5" smd circle
			(at -14.06398 -9.41324 180)
			(size 0.3048 0.3048)
			(layers "F.Cu" "F.Mask" "F.Paste")
			(net "PV_VDDR")
		)
		(pad "J13" smd circle
			(at -10.4013 -9.20242 180)
			(size 0.3048 0.3048)
			(layers "F.Cu" "F.Mask" "F.Paste")
			(net "M_B_CK_DP3")
		)
		(pad "J14" smd circle
			(at -9.70026 -9.20242 180)
			(size 0.3048 0.3048)
			(layers "F.Cu" "F.Mask" "F.Paste")
			(net "CLK_100M_CPU_MPLL1_DP")
		)
		(pad "J21" smd circle
			(at -6.42874 -9.20242 180)
			(size 0.3048 0.3048)
			(layers "F.Cu" "F.Mask" "F.Paste")
			(net "M_B_MA6")
		)
		(pad "J22" smd circle
			(at -5.7277 -9.20242 180)
			(size 0.3048 0.3048)
			(layers "F.Cu" "F.Mask" "F.Paste")
			(net "M_B_MA7")
		)
		(pad "J29" smd circle
			(at -2.45618 -9.20242 180)
			(size 0.3048 0.3048)
			(layers "F.Cu" "F.Mask" "F.Paste")
			(net "GND")
		)
		(pad "J30" smd circle
			(at -1.75514 -9.20242 180)
			(size 0.3048 0.3048)
			(layers "F.Cu" "F.Mask" "F.Paste")
			(net "M_B_DQ29")
		)
		(pad "J37" smd circle
			(at 1.51638 -9.20242 180)
			(size 0.3048 0.3048)
			(layers "F.Cu" "F.Mask" "F.Paste")
			(net "CLK_100M_CPU_HFHPLL_DN")
		)
		(pad "J38" smd circle
			(at 2.21742 -9.20242 180)
			(size 0.3048 0.3048)
			(layers "F.Cu" "F.Mask" "F.Paste")
			(net "TP_CPU_RSVD17")
		)
		(pad "J44" smd circle
			(at 5.48894 -9.20242 180)
			(size 0.3048 0.3048)
			(layers "F.Cu" "F.Mask" "F.Paste")
			(net "Net_1366")
		)
		(pad "J46" smd circle
			(at 6.18998 -9.20242 180)
			(size 0.3048 0.3048)
			(layers "F.Cu" "F.Mask" "F.Paste")
			(net "Net_276")
		)
		(pad "J52" smd circle
			(at 9.4615 -9.20242 180)
			(size 0.3048 0.3048)
			(layers "F.Cu" "F.Mask" "F.Paste")
			(net "SATA2_OBS_P")
		)
		(pad "J54" smd circle
			(at 10.16254 -9.20242 180)
			(size 0.3048 0.3048)
			(layers "F.Cu" "F.Mask" "F.Paste")
			(net "CLK_100M_SATA2_DP")
		)
		(pad "J63" smd circle
			(at 14.5415 -9.10844 180)
			(size 0.3048 0.3048)
			(layers "F.Cu" "F.Mask" "F.Paste")
			(net "GND")
		)
		(pad "J64" smd circle
			(at 15.3035 -9.05764 180)
			(size 0.3048 0.3048)
			(layers "F.Cu" "F.Mask" "F.Paste")
			(net "GND")
		)
		(pad "J66" smd oval
			(at 16.24838 -9.10844 180)
			(size 0.3429 0.254)
			(layers "F.Cu" "F.Mask" "F.Paste")
			(net "GND")
		)
		(pad "K1" smd oval
			(at -16.24838 -8.9027 180)
			(size 0.3429 0.254)
			(layers "F.Cu" "F.Mask" "F.Paste")
			(net "GND")
		)
		(pad "K3" smd circle
			(at -15.3035 -8.9535 180)
			(size 0.3048 0.3048)
			(layers "F.Cu" "F.Mask" "F.Paste")
			(net "M_B_CS_N0")
		)
		(pad "K4" smd circle
			(at -14.5415 -8.9027 180)
			(size 0.3048 0.3048)
			(layers "F.Cu" "F.Mask" "F.Paste")
			(net "M_B_CS_N3")
		)
		(pad "K10" smd circle
			(at -11.68654 -8.82142 180)
			(size 0.3048 0.3048)
			(layers "F.Cu" "F.Mask" "F.Paste")
			(net "PV_VDDR")
		)
		(pad "K17" smd circle
			(at -8.41502 -8.82142 180)
			(size 0.3048 0.3048)
			(layers "F.Cu" "F.Mask" "F.Paste")
			(net "PV_VDDR")
		)
		(pad "K18" smd circle
			(at -7.71398 -8.82142 180)
			(size 0.3048 0.3048)
			(layers "F.Cu" "F.Mask" "F.Paste")
			(net "PV_VDDR")
		)
		(pad "K25" smd circle
			(at -4.44246 -8.82142 180)
			(size 0.3048 0.3048)
			(layers "F.Cu" "F.Mask" "F.Paste")
			(net "PV_VDDR")
		)
		(pad "K26" smd circle
			(at -3.74142 -8.82142 180)
			(size 0.3048 0.3048)
			(layers "F.Cu" "F.Mask" "F.Paste")
			(net "PV_VDDR")
		)
		(pad "K32" smd circle
			(at -0.4699 -8.82142 180)
			(size 0.3048 0.3048)
			(layers "F.Cu" "F.Mask" "F.Paste")
			(net "GND")
		)
		(pad "K34" smd circle
			(at 0.23114 -8.82142 180)
			(size 0.3048 0.3048)
			(layers "F.Cu" "F.Mask" "F.Paste")
			(net "GND")
		)
		(pad "K41" smd circle
			(at 3.50266 -8.82142 180)
			(size 0.3048 0.3048)
			(layers "F.Cu" "F.Mask" "F.Paste")
			(net "P1V0")
		)
		(pad "K42" smd circle
			(at 4.2037 -8.82142 180)
			(size 0.3048 0.3048)
			(layers "F.Cu" "F.Mask" "F.Paste")
			(net "GND")
		)
		(pad "K48" smd circle
			(at 7.47522 -8.82142 180)
			(size 0.3048 0.3048)
			(layers "F.Cu" "F.Mask" "F.Paste")
			(net "CPU_GBE_RX_DN0")
		)
		(pad "K50" smd circle
			(at 8.17626 -8.82142 180)
			(size 0.3048 0.3048)
			(layers "F.Cu" "F.Mask" "F.Paste")
			(net "GND")
		)
		(pad "K62" smd circle
			(at 14.06398 -8.5979 180)
			(size 0.3048 0.3048)
			(layers "F.Cu" "F.Mask" "F.Paste")
			(net "GND")
		)
		(pad "L2" smd circle
			(at -15.80642 -8.14324 180)
			(size 0.3048 0.3048)
			(layers "F.Cu" "F.Mask" "F.Paste")
			(net "M_B_ODT0")
		)
		(pad "L4" smd circle
			(at -14.75232 -8.22198 180)
			(size 0.3048 0.3048)
			(layers "F.Cu" "F.Mask" "F.Paste")
			(net "M_B_ODT3")
		)
		(pad "L5" smd circle
			(at -14.06398 -8.39216 180)
			(size 0.3048 0.3048)
			(layers "F.Cu" "F.Mask" "F.Paste")
			(net "PV_VDDR")
		)
		(pad "L7" smd circle
			(at -13.34516 -8.17626 180)
			(size 0.3048 0.3048)
			(layers "F.Cu" "F.Mask" "F.Paste")
			(net "M_B_CS_N2")
		)
		(pad "L8" smd circle
			(at -12.58316 -8.17626 180)
			(size 0.3048 0.3048)
			(layers "F.Cu" "F.Mask" "F.Paste")
			(net "M_B_RAS#")
		)
		(pad "L13" smd circle
			(at -10.4013 -8.44042 180)
			(size 0.3048 0.3048)
			(layers "F.Cu" "F.Mask" "F.Paste")
			(net "M_B_CK_DN3")
		)
		(pad "L14" smd circle
			(at -9.70026 -8.44042 180)
			(size 0.3048 0.3048)
			(layers "F.Cu" "F.Mask" "F.Paste")
			(net "CLK_100M_CPU_MPLL1_DN")
		)
		(pad "L17" smd circle
			(at -8.41502 -8.05942 180)
			(size 0.3048 0.3048)
			(layers "F.Cu" "F.Mask" "F.Paste")
			(net "M_DRAM_PWROK")
		)
		(pad "L18" smd circle
			(at -7.71398 -8.05942 180)
			(size 0.3048 0.3048)
			(layers "F.Cu" "F.Mask" "F.Paste")
			(net "M_B_MA10")
		)
		(pad "L21" smd circle
			(at -6.42874 -8.44042 180)
			(size 0.3048 0.3048)
			(layers "F.Cu" "F.Mask" "F.Paste")
			(net "PV_VDDR")
		)
		(pad "L22" smd circle
			(at -5.7277 -8.44042 180)
			(size 0.3048 0.3048)
			(layers "F.Cu" "F.Mask" "F.Paste")
			(net "PV_VDDR")
		)
		(pad "L25" smd circle
			(at -4.44246 -8.05942 180)
			(size 0.3048 0.3048)
			(layers "F.Cu" "F.Mask" "F.Paste")
			(net "M_B_CKE2")
		)
		(pad "L26" smd circle
			(at -3.74142 -8.05942 180)
			(size 0.3048 0.3048)
			(layers "F.Cu" "F.Mask" "F.Paste")
			(net "M_B_CKE3")
		)
		(pad "L29" smd circle
			(at -2.45618 -8.44042 180)
			(size 0.3048 0.3048)
			(layers "F.Cu" "F.Mask" "F.Paste")
			(net "M_B_DQS_DN3")
		)
		(pad "L30" smd circle
			(at -1.75514 -8.44042 180)
			(size 0.3048 0.3048)
			(layers "F.Cu" "F.Mask" "F.Paste")
			(net "GND")
		)
		(pad "L32" smd circle
			(at -0.4699 -8.05942 180)
			(size 0.3048 0.3048)
			(layers "F.Cu" "F.Mask" "F.Paste")
			(net "M_B_DQ27")
		)
		(pad "L34" smd circle
			(at 0.23114 -8.05942 180)
			(size 0.3048 0.3048)
			(layers "F.Cu" "F.Mask" "F.Paste")
			(net "GND")
		)
		(pad "L37" smd circle
			(at 1.51638 -8.44042 180)
			(size 0.3048 0.3048)
			(layers "F.Cu" "F.Mask" "F.Paste")
			(net "CLK_100M_CPU_HFHPLL_DP")
		)
		(pad "L38" smd circle
			(at 2.21742 -8.44042 180)
			(size 0.3048 0.3048)
			(layers "F.Cu" "F.Mask" "F.Paste")
			(net "TP_CPU_RSVD16")
		)
		(pad "L41" smd circle
			(at 3.50266 -8.05942 180)
			(size 0.3048 0.3048)
			(layers "F.Cu" "F.Mask" "F.Paste")
			(net "P1V0")
		)
		(pad "L42" smd circle
			(at 4.2037 -8.05942 180)
			(size 0.3048 0.3048)
			(layers "F.Cu" "F.Mask" "F.Paste")
			(net "P1V0")
		)
		(pad "L44" smd circle
			(at 5.48894 -8.44042 180)
			(size 0.3048 0.3048)
			(layers "F.Cu" "F.Mask" "F.Paste")
			(net "Net_1365")
		)
		(pad "L46" smd circle
			(at 6.18998 -8.44042 180)
			(size 0.3048 0.3048)
			(layers "F.Cu" "F.Mask" "F.Paste")
			(net "Net_275")
		)
		(pad "L48" smd circle
			(at 7.47522 -8.05942 180)
			(size 0.3048 0.3048)
			(layers "F.Cu" "F.Mask" "F.Paste")
			(net "GND")
		)
		(pad "L50" smd circle
			(at 8.17626 -8.05942 180)
			(size 0.3048 0.3048)
			(layers "F.Cu" "F.Mask" "F.Paste")
			(net "GND")
		)
		(pad "L52" smd circle
			(at 9.4615 -8.44042 180)
			(size 0.3048 0.3048)
			(layers "F.Cu" "F.Mask" "F.Paste")
			(net "SATA2_OBS_N")
		)
		(pad "L54" smd circle
			(at 10.16254 -8.44042 180)
			(size 0.3048 0.3048)
			(layers "F.Cu" "F.Mask" "F.Paste")
			(net "CLK_100M_SATA2_DN")
		)
		(pad "L57" smd circle
			(at 11.82116 -8.41502 180)
			(size 0.3048 0.3048)
			(layers "F.Cu" "F.Mask" "F.Paste")
			(net "CLK_100M_CPU_SATA3_DP")
		)
		(pad "L59" smd circle
			(at 12.58316 -8.41502 180)
			(size 0.3048 0.3048)
			(layers "F.Cu" "F.Mask" "F.Paste")
			(net "CLK_100M_CPU_SATA3_DN")
		)
		(pad "L60" smd circle
			(at 13.34516 -8.41502 180)
			(size 0.3048 0.3048)
			(layers "F.Cu" "F.Mask" "F.Paste")
			(net "GND")
		)
		(pad "L63" smd circle
			(at 14.7955 -8.44042 180)
			(size 0.3048 0.3048)
			(layers "F.Cu" "F.Mask" "F.Paste")
			(net "SATA3_RX_DP1")
		)
		(pad "L65" smd circle
			(at 15.75308 -8.38708 180)
			(size 0.3048 0.3048)
			(layers "F.Cu" "F.Mask" "F.Paste")
			(net "SATA3_RX_DN1")
		)
		(pad "M3" smd circle
			(at -15.24762 -7.71906 180)
			(size 0.3048 0.3048)
			(layers "F.Cu" "F.Mask" "F.Paste")
			(net "PV_VDDR")
		)
		(pad "M5" smd circle
			(at -14.01318 -7.68858 180)
			(size 0.3048 0.3048)
			(layers "F.Cu" "F.Mask" "F.Paste")
			(net "GND")
		)
		(pad "M21" smd circle
			(at -6.42874 -7.67842 180)
			(size 0.3048 0.3048)
			(layers "F.Cu" "F.Mask" "F.Paste")
			(net "M_B_MA4")
		)
		(pad "M22" smd circle
			(at -5.7277 -7.67842 180)
			(size 0.3048 0.3048)
			(layers "F.Cu" "F.Mask" "F.Paste")
			(net "M_B_MA9")
		)
		(pad "M29" smd circle
			(at -2.45618 -7.67842 180)
			(size 0.3048 0.3048)
			(layers "F.Cu" "F.Mask" "F.Paste")
			(net "M_B_DQS_DP3")
		)
		(pad "M30" smd circle
			(at -1.75514 -7.67842 180)
			(size 0.3048 0.3048)
			(layers "F.Cu" "F.Mask" "F.Paste")
			(net "M_B_DQ30")
		)
		(pad "M37" smd circle
			(at 1.51638 -7.67842 180)
			(size 0.3048 0.3048)
			(layers "F.Cu" "F.Mask" "F.Paste")
			(net "GND")
		)
		(pad "M38" smd circle
			(at 2.21742 -7.67842 180)
			(size 0.3048 0.3048)
			(layers "F.Cu" "F.Mask" "F.Paste")
			(net "GND")
		)
		(pad "M44" smd circle
			(at 5.48894 -7.67842 180)
			(size 0.3048 0.3048)
			(layers "F.Cu" "F.Mask" "F.Paste")
			(net "GND")
		)
		(pad "M46" smd circle
			(at 6.18998 -7.67842 180)
			(size 0.3048 0.3048)
			(layers "F.Cu" "F.Mask" "F.Paste")
			(net "GND")
		)
		(pad "M52" smd circle
			(at 9.4615 -7.67842 180)
			(size 0.3048 0.3048)
			(layers "F.Cu" "F.Mask" "F.Paste")
			(net "GND")
		)
		(pad "M54" smd circle
			(at 10.29716 -7.71398 180)
			(size 0.3048 0.3048)
			(layers "F.Cu" "F.Mask" "F.Paste")
			(net "GND")
		)
		(pad "M56" smd circle
			(at 11.05916 -7.71398 180)
			(size 0.3048 0.3048)
			(layers "F.Cu" "F.Mask" "F.Paste")
			(net "GND")
		)
		(pad "M57" smd circle
			(at 11.82116 -7.71398 180)
			(size 0.3048 0.3048)
			(layers "F.Cu" "F.Mask" "F.Paste")
			(net "GND")
		)
		(pad "M59" smd circle
			(at 12.58316 -7.71398 180)
			(size 0.3048 0.3048)
			(layers "F.Cu" "F.Mask" "F.Paste")
			(net "GND")
		)
		(pad "M60" smd circle
			(at 13.34516 -7.71398 180)
			(size 0.3048 0.3048)
			(layers "F.Cu" "F.Mask" "F.Paste")
			(net "GND")
		)
		(pad "M62" smd circle
			(at 14.08176 -7.89178 180)
			(size 0.3048 0.3048)
			(layers "F.Cu" "F.Mask" "F.Paste")
			(net "SATA3_RX_DP0")
		)
		(pad "M64" smd circle
			(at 15.24254 -7.90194 180)
			(size 0.3048 0.3048)
			(layers "F.Cu" "F.Mask" "F.Paste")
			(net "SATA3_RX_DN0")
		)
		(pad "M66" smd oval
			(at 16.24838 -7.6708 180)
			(size 0.3429 0.254)
			(layers "F.Cu" "F.Mask" "F.Paste")
			(net "GND")
		)
		(pad "N1" smd oval
			(at -16.24838 -7.46252 180)
			(size 0.3429 0.254)
			(layers "F.Cu" "F.Mask" "F.Paste")
			(net "GND")
		)
		(pad "N2" smd circle
			(at -15.64132 -7.11454 180)
			(size 0.3048 0.3048)
			(layers "F.Cu" "F.Mask" "F.Paste")
			(net "M_B_ODT1")
		)
		(pad "N4" smd circle
			(at -14.89964 -7.10692 180)
			(size 0.3048 0.3048)
			(layers "F.Cu" "F.Mask" "F.Paste")
			(net "M_B_CS_N1")
		)
		(pad "N5" smd circle
			(at -14.20368 -7.0104 180)
			(size 0.3048 0.3048)
			(layers "F.Cu" "F.Mask" "F.Paste")
			(net "GND")
		)
		(pad "N7" smd circle
			(at -13.34516 -7.47522 180)
			(size 0.3048 0.3048)
			(layers "F.Cu" "F.Mask" "F.Paste")
			(net "M_B_WE#")
		)
		(pad "N8" smd circle
			(at -12.58316 -7.47522 180)
			(size 0.3048 0.3048)
			(layers "F.Cu" "F.Mask" "F.Paste")
			(net "M_B_ODT2")
		)
		(pad "N10" smd circle
			(at -11.82116 -7.47522 180)
			(size 0.3048 0.3048)
			(layers "F.Cu" "F.Mask" "F.Paste")
			(net "GND")
		)
		(pad "N11" smd circle
			(at -11.05916 -7.47522 180)
			(size 0.3048 0.3048)
			(layers "F.Cu" "F.Mask" "F.Paste")
			(net "M_B_R_RESET#")
		)
		(pad "N13" smd circle
			(at -10.29716 -7.47522 180)
			(size 0.3048 0.3048)
			(layers "F.Cu" "F.Mask" "F.Paste")
			(net "PV_VDDR")
		)
		(pad "N14" smd circle
			(at -9.53516 -7.47522 180)
			(size 0.3048 0.3048)
			(layers "F.Cu" "F.Mask" "F.Paste")
			(net "PV_VDDR")
		)
		(pad "N17" smd circle
			(at -8.41502 -7.29742 180)
			(size 0.3048 0.3048)
			(layers "F.Cu" "F.Mask" "F.Paste")
			(net "PWRGD_DDR3_VCCA")
		)
		(pad "N18" smd circle
			(at -7.71398 -7.29742 180)
			(size 0.3048 0.3048)
			(layers "F.Cu" "F.Mask" "F.Paste")
			(net "M_B_BS0")
		)
		(pad "N25" smd circle
			(at -4.44246 -7.29742 180)
			(size 0.3048 0.3048)
			(layers "F.Cu" "F.Mask" "F.Paste")
			(net "M_B_CKE1")
		)
		(pad "N26" smd circle
			(at -3.74142 -7.29742 180)
			(size 0.3048 0.3048)
			(layers "F.Cu" "F.Mask" "F.Paste")
			(net "M_B_CKE0")
		)
		(pad "N32" smd circle
			(at -0.4699 -7.29742 180)
			(size 0.3048 0.3048)
			(layers "F.Cu" "F.Mask" "F.Paste")
			(net "M_B_DQ26")
		)
		(pad "N34" smd circle
			(at 0.23114 -7.29742 180)
			(size 0.3048 0.3048)
			(layers "F.Cu" "F.Mask" "F.Paste")
			(net "GND")
		)
		(pad "N41" smd circle
			(at 3.50266 -7.29742 180)
			(size 0.3048 0.3048)
			(layers "F.Cu" "F.Mask" "F.Paste")
			(net "P1V0")
		)
		(pad "N42" smd circle
			(at 4.2037 -7.29742 180)
			(size 0.3048 0.3048)
			(layers "F.Cu" "F.Mask" "F.Paste")
			(net "P1V0")
		)
		(pad "N48" smd circle
			(at 7.47522 -7.29742 180)
			(size 0.3048 0.3048)
			(layers "F.Cu" "F.Mask" "F.Paste")
			(net "GND")
		)
		(pad "N50" smd circle
			(at 8.17626 -7.29742 180)
			(size 0.3048 0.3048)
			(layers "F.Cu" "F.Mask" "F.Paste")
			(net "GND")
		)
		(pad "N62" smd circle
			(at 14.20368 -7.19836 180)
			(size 0.3048 0.3048)
			(layers "F.Cu" "F.Mask" "F.Paste")
			(net "GND")
		)
		(pad "N63" smd circle
			(at 14.89964 -7.2898 180)
			(size 0.3048 0.3048)
			(layers "F.Cu" "F.Mask" "F.Paste")
			(net "GND")
		)
		(pad "N65" smd circle
			(at 15.63878 -7.32028 180)
			(size 0.3048 0.3048)
			(layers "F.Cu" "F.Mask" "F.Paste")
			(net "GND")
		)
		(pad "P17" smd circle
			(at -8.41502 -6.53542 180)
			(size 0.3048 0.3048)
			(layers "F.Cu" "F.Mask" "F.Paste")
			(net "PV_VDDR")
		)
		(pad "P18" smd circle
			(at -7.71398 -6.53542 180)
			(size 0.3048 0.3048)
			(layers "F.Cu" "F.Mask" "F.Paste")
			(net "PV_VDDR")
		)
		(pad "P21" smd circle
			(at -6.42874 -6.91642 180)
			(size 0.3048 0.3048)
			(layers "F.Cu" "F.Mask" "F.Paste")
			(net "M_B_MA3")
		)
		(pad "P22" smd circle
			(at -5.7277 -6.91642 180)
			(size 0.3048 0.3048)
			(layers "F.Cu" "F.Mask" "F.Paste")
			(net "M_B_MA11")
		)
		(pad "P25" smd circle
			(at -4.44246 -6.53542 180)
			(size 0.3048 0.3048)
			(layers "F.Cu" "F.Mask" "F.Paste")
			(net "PV_VDDR")
		)
		(pad "P26" smd circle
			(at -3.74142 -6.53542 180)
			(size 0.3048 0.3048)
			(layers "F.Cu" "F.Mask" "F.Paste")
			(net "PV_VDDR")
		)
		(pad "P29" smd circle
			(at -2.45618 -6.91642 180)
			(size 0.3048 0.3048)
			(layers "F.Cu" "F.Mask" "F.Paste")
			(net "GND")
		)
		(pad "P30" smd circle
			(at -1.75514 -6.91642 180)
			(size 0.3048 0.3048)
			(layers "F.Cu" "F.Mask" "F.Paste")
			(net "M_B_DQ31")
		)
		(pad "P32" smd circle
			(at -0.4699 -6.53542 180)
			(size 0.3048 0.3048)
			(layers "F.Cu" "F.Mask" "F.Paste")
			(net "GND")
		)
		(pad "P34" smd circle
			(at 0.23114 -6.53542 180)
			(size 0.3048 0.3048)
			(layers "F.Cu" "F.Mask" "F.Paste")
			(net "GND")
		)
		(pad "P37" smd circle
			(at 1.51638 -6.91642 180)
			(size 0.3048 0.3048)
			(layers "F.Cu" "F.Mask" "F.Paste")
			(net "GND")
		)
		(pad "P38" smd circle
			(at 2.21742 -6.91642 180)
			(size 0.3048 0.3048)
			(layers "F.Cu" "F.Mask" "F.Paste")
			(net "TP_CPU_RSVD15")
		)
		(pad "P41" smd circle
			(at 3.50266 -6.53542 180)
			(size 0.3048 0.3048)
			(layers "F.Cu" "F.Mask" "F.Paste")
			(net "P1V0")
		)
		(pad "P42" smd circle
			(at 4.2037 -6.53542 180)
			(size 0.3048 0.3048)
			(layers "F.Cu" "F.Mask" "F.Paste")
			(net "P1V0")
		)
		(pad "P44" smd circle
			(at 5.48894 -6.91642 180)
			(size 0.3048 0.3048)
			(layers "F.Cu" "F.Mask" "F.Paste")
			(net "GND")
		)
		(pad "P46" smd circle
			(at 6.18998 -6.91642 180)
			(size 0.3048 0.3048)
			(layers "F.Cu" "F.Mask" "F.Paste")
			(net "BD_REV_0")
		)
		(pad "P48" smd circle
			(at 7.47522 -6.53542 180)
			(size 0.3048 0.3048)
			(layers "F.Cu" "F.Mask" "F.Paste")
			(net "NGFF_PRESENT#")
		)
		(pad "P50" smd circle
			(at 8.17626 -6.53542 180)
			(size 0.3048 0.3048)
			(layers "F.Cu" "F.Mask" "F.Paste")
			(net "GBE_SMBCLK")
		)
		(pad "R2" smd circle
			(at -15.63878 -6.18744 180)
			(size 0.3048 0.3048)
			(layers "F.Cu" "F.Mask" "F.Paste")
			(net "GND")
		)
		(pad "R4" smd circle
			(at -14.89964 -6.21792 180)
			(size 0.3048 0.3048)
			(layers "F.Cu" "F.Mask" "F.Paste")
			(net "GND")
		)
		(pad "R5" smd circle
			(at -14.20368 -6.3119 180)
			(size 0.3048 0.3048)
			(layers "F.Cu" "F.Mask" "F.Paste")
			(net "GND")
		)
		(pad "R8" smd circle
			(at -12.96416 -6.18998 180)
			(size 0.3048 0.3048)
			(layers "F.Cu" "F.Mask" "F.Paste")
			(net "M_B_DQ38")
		)
		(pad "R9" smd circle
			(at -12.20216 -6.18998 180)
			(size 0.3048 0.3048)
			(layers "F.Cu" "F.Mask" "F.Paste")
			(net "M_B_DQ34")
		)
		(pad "R11" smd circle
			(at -11.44016 -6.18998 180)
			(size 0.3048 0.3048)
			(layers "F.Cu" "F.Mask" "F.Paste")
			(net "M_B_DQ35")
		)
		(pad "R12" smd circle
			(at -10.67816 -6.18998 180)
			(size 0.3048 0.3048)
			(layers "F.Cu" "F.Mask" "F.Paste")
			(net "GND")
		)
		(pad "R14" smd circle
			(at -9.91616 -6.18998 180)
			(size 0.3048 0.3048)
			(layers "F.Cu" "F.Mask" "F.Paste")
			(net "M_B_DQ33")
		)
		(pad "R15" smd circle
			(at -9.15416 -6.18998 180)
			(size 0.3048 0.3048)
			(layers "F.Cu" "F.Mask" "F.Paste")
			(net "M_B_DQ32")
		)
		(pad "R21" smd circle
			(at -6.42874 -6.15442 180)
			(size 0.3048 0.3048)
			(layers "F.Cu" "F.Mask" "F.Paste")
			(net "PV_VDDR")
		)
		(pad "R22" smd circle
			(at -5.7277 -6.15442 180)
			(size 0.3048 0.3048)
			(layers "F.Cu" "F.Mask" "F.Paste")
			(net "PV_VDDR")
		)
		(pad "R29" smd circle
			(at -2.45618 -6.15442 180)
			(size 0.3048 0.3048)
			(layers "F.Cu" "F.Mask" "F.Paste")
			(net "M_B_VREF")
		)
		(pad "R30" smd circle
			(at -1.75514 -6.15442 180)
			(size 0.3048 0.3048)
			(layers "F.Cu" "F.Mask" "F.Paste")
			(net "GND")
		)
		(pad "R37" smd circle
			(at 1.51638 -6.15442 180)
			(size 0.3048 0.3048)
			(layers "F.Cu" "F.Mask" "F.Paste")
			(net "TP_CPU_RSVD14")
		)
		(pad "R38" smd circle
			(at 2.21742 -6.15442 180)
			(size 0.3048 0.3048)
			(layers "F.Cu" "F.Mask" "F.Paste")
			(net "GND")
		)
		(pad "R44" smd circle
			(at 5.48894 -6.15442 180)
			(size 0.3048 0.3048)
			(layers "F.Cu" "F.Mask" "F.Paste")
			(net "P1V0")
		)
		(pad "R46" smd circle
			(at 6.18998 -6.15442 180)
			(size 0.3048 0.3048)
			(layers "F.Cu" "F.Mask" "F.Paste")
			(net "P1V0")
		)
		(pad "R52" smd circle
			(at 9.15416 -6.42874 180)
			(size 0.3048 0.3048)
			(layers "F.Cu" "F.Mask" "F.Paste")
			(net "GND")
		)
		(pad "R53" smd circle
			(at 9.91616 -6.42874 180)
			(size 0.3048 0.3048)
			(layers "F.Cu" "F.Mask" "F.Paste")
			(net "SATA3_OBS_N")
		)
		(pad "R55" smd circle
			(at 10.67816 -6.42874 180)
			(size 0.3048 0.3048)
			(layers "F.Cu" "F.Mask" "F.Paste")
			(net "SATA3_OBS_P")
		)
		(pad "R56" smd circle
			(at 11.44016 -6.42874 180)
			(size 0.3048 0.3048)
			(layers "F.Cu" "F.Mask" "F.Paste")
			(net "GND")
		)
		(pad "R58" smd circle
			(at 12.20216 -6.42874 180)
			(size 0.3048 0.3048)
			(layers "F.Cu" "F.Mask" "F.Paste")
			(net "MSATA_PRESENT#")
		)
		(pad "R59" smd circle
			(at 12.96416 -6.42874 180)
			(size 0.3048 0.3048)
			(layers "F.Cu" "F.Mask" "F.Paste")
			(net "SPI_CS_GBE#")
		)
		(pad "R62" smd circle
			(at 14.20368 -6.49732 180)
			(size 0.3048 0.3048)
			(layers "F.Cu" "F.Mask" "F.Paste")
			(net "GND")
		)
		(pad "R63" smd circle
			(at 14.89964 -6.4008 180)
			(size 0.3048 0.3048)
			(layers "F.Cu" "F.Mask" "F.Paste")
			(net "SATA3_TX_DP1")
		)
		(pad "R65" smd circle
			(at 15.64132 -6.39572 180)
			(size 0.3048 0.3048)
			(layers "F.Cu" "F.Mask" "F.Paste")
			(net "SATA3_TX_DN1")
		)
		(pad "R66" smd oval
			(at 16.24838 -6.0452 180)
			(size 0.3429 0.254)
			(layers "F.Cu" "F.Mask" "F.Paste")
			(net "SATA3_TX_DP0")
		)
		(pad "T1" smd oval
			(at -16.24838 -5.83692 180)
			(size 0.3429 0.254)
			(layers "F.Cu" "F.Mask" "F.Paste")
			(net "M_B_DQ45")
		)
		(pad "T3" smd circle
			(at -15.24254 -5.60832 180)
			(size 0.3048 0.3048)
			(layers "F.Cu" "F.Mask" "F.Paste")
			(net "M_B_DQ44")
		)
		(pad "T5" smd circle
			(at -14.08176 -5.61848 180)
			(size 0.3048 0.3048)
			(layers "F.Cu" "F.Mask" "F.Paste")
			(net "GND")
		)
		(pad "T17" smd circle
			(at -8.41502 -5.77342 180)
			(size 0.3048 0.3048)
			(layers "F.Cu" "F.Mask" "F.Paste")
			(net "M_B_DQ36")
		)
		(pad "T18" smd circle
			(at -7.71398 -5.77342 180)
			(size 0.3048 0.3048)
			(layers "F.Cu" "F.Mask" "F.Paste")
			(net "GND")
		)
		(pad "T20" smd circle
			(at -6.70052 -5.50164 180)
			(size 0.3048 0.3048)
			(layers "F.Cu" "F.Mask" "F.Paste")
			(net "GND")
		)
		(pad "T21" smd circle
			(at -5.99948 -5.50164 180)
			(size 0.3048 0.3048)
			(layers "F.Cu" "F.Mask" "F.Paste")
			(net "GND")
		)
		(pad "T23" smd circle
			(at -5.20192 -5.50164 180)
			(size 0.381 0.381)
			(layers "F.Cu" "F.Mask" "F.Paste")
			(net "GND")
		)
		(pad "T25" smd circle
			(at -4.44246 -5.77342 180)
			(size 0.3048 0.3048)
			(layers "F.Cu" "F.Mask" "F.Paste")
			(net "M_B_CMDPU")
		)
		(pad "T26" smd circle
			(at -3.74142 -5.77342 180)
			(size 0.3048 0.3048)
			(layers "F.Cu" "F.Mask" "F.Paste")
			(net "M_B_DQPU")
		)
		(pad "T28" smd circle
			(at -2.79908 -5.50164 180)
			(size 0.381 0.381)
			(layers "F.Cu" "F.Mask" "F.Paste")
			(net "GND")
		)
		(pad "T29" smd circle
			(at -2.10058 -5.50164 180)
			(size 0.381 0.381)
			(layers "F.Cu" "F.Mask" "F.Paste")
			(net "GND")
		)
		(pad "T31" smd circle
			(at -1.19888 -5.50164 180)
			(size 0.381 0.381)
			(layers "F.Cu" "F.Mask" "F.Paste")
			(net "GND")
		)
		(pad "T32" smd circle
			(at -0.4699 -5.77342 180)
			(size 0.3048 0.3048)
			(layers "F.Cu" "F.Mask" "F.Paste")
			(net "M_B_ODTPU")
		)
		(pad "T34" smd circle
			(at 0.23114 -5.77342 180)
			(size 0.3048 0.3048)
			(layers "F.Cu" "F.Mask" "F.Paste")
			(net "GND")
		)
		(pad "T36" smd circle
			(at 1.19888 -5.50164 180)
			(size 0.381 0.381)
			(layers "F.Cu" "F.Mask" "F.Paste")
			(net "GND")
		)
		(pad "T37" smd circle
			(at 1.89992 -5.50164 180)
			(size 0.381 0.381)
			(layers "F.Cu" "F.Mask" "F.Paste")
			(net "P1V0_STBY")
		)
		(pad "T39" smd circle
			(at 2.79908 -5.50164 180)
			(size 0.381 0.381)
			(layers "F.Cu" "F.Mask" "F.Paste")
			(net "P1V0_STBY")
		)
		(pad "T41" smd circle
			(at 3.50266 -5.77342 180)
			(size 0.3048 0.3048)
			(layers "F.Cu" "F.Mask" "F.Paste")
			(net "GND")
		)
		(pad "T42" smd circle
			(at 4.2037 -5.77342 180)
			(size 0.3048 0.3048)
			(layers "F.Cu" "F.Mask" "F.Paste")
			(net "GND")
		)
		(pad "T44" smd circle
			(at 5.20192 -5.50164 180)
			(size 0.381 0.381)
			(layers "F.Cu" "F.Mask" "F.Paste")
			(net "P1V0")
		)
		(pad "T45" smd circle
			(at 5.90042 -5.50164 180)
			(size 0.3048 0.3048)
			(layers "F.Cu" "F.Mask" "F.Paste")
			(net "P1V0")
		)
		(pad "T47" smd circle
			(at 6.80212 -5.50164 180)
			(size 0.3048 0.3048)
			(layers "F.Cu" "F.Mask" "F.Paste")
			(net "GND")
		)
		(pad "T48" smd circle
			(at 7.47522 -5.77342 180)
			(size 0.3048 0.3048)
			(layers "F.Cu" "F.Mask" "F.Paste")
			(net "BD_REV_2")
		)
		(pad "T50" smd circle
			(at 8.17626 -5.77342 180)
			(size 0.3048 0.3048)
			(layers "F.Cu" "F.Mask" "F.Paste")
			(net "SPI_CLK_GBE")
		)
		(pad "T52" smd circle
			(at 9.15416 -5.7277 180)
			(size 0.3048 0.3048)
			(layers "F.Cu" "F.Mask" "F.Paste")
			(net "GND")
		)
		(pad "T53" smd circle
			(at 9.91616 -5.7277 180)
			(size 0.3048 0.3048)
			(layers "F.Cu" "F.Mask" "F.Paste")
			(net "BD_ID_2")
		)
		(pad "T55" smd circle
			(at 10.67816 -5.7277 180)
			(size 0.3048 0.3048)
			(layers "F.Cu" "F.Mask" "F.Paste")
			(net "GBE_SMBALRT#")
		)
		(pad "T56" smd circle
			(at 11.44016 -5.7277 180)
			(size 0.3048 0.3048)
			(layers "F.Cu" "F.Mask" "F.Paste")
			(net "GND")
		)
		(pad "T58" smd circle
			(at 12.20216 -5.7277 180)
			(size 0.3048 0.3048)
			(layers "F.Cu" "F.Mask" "F.Paste")
			(net "GBE_SDP0")
		)
		(pad "T59" smd circle
			(at 12.96416 -5.7277 180)
			(size 0.3048 0.3048)
			(layers "F.Cu" "F.Mask" "F.Paste")
			(net "GBE_SMBDATA")
		)
		(pad "T62" smd circle
			(at 14.01318 -5.81914 180)
			(size 0.3048 0.3048)
			(layers "F.Cu" "F.Mask" "F.Paste")
			(net "GND")
		)
		(pad "T64" smd circle
			(at 15.24762 -5.78866 180)
			(size 0.3048 0.3048)
			(layers "F.Cu" "F.Mask" "F.Paste")
			(net "SATA3_TX_DN0")
		)
		(pad "U2" smd circle
			(at -15.75308 -5.12064 180)
			(size 0.3048 0.3048)
			(layers "F.Cu" "F.Mask" "F.Paste")
			(net "M_B_DQ41")
		)
		(pad "U4" smd circle
			(at -14.7955 -5.0673 180)
			(size 0.3048 0.3048)
			(layers "F.Cu" "F.Mask" "F.Paste")
			(net "M_B_DQ40")
		)
		(pad "U8" smd circle
			(at -12.96416 -5.48894 180)
			(size 0.3048 0.3048)
			(layers "F.Cu" "F.Mask" "F.Paste")
			(net "M_B_DQ39")
		)
		(pad "U9" smd circle
			(at -12.20216 -5.48894 180)
			(size 0.3048 0.3048)
			(layers "F.Cu" "F.Mask" "F.Paste")
			(net "GND")
		)
		(pad "U11" smd circle
			(at -11.44016 -5.48894 180)
			(size 0.3048 0.3048)
			(layers "F.Cu" "F.Mask" "F.Paste")
			(net "M_B_DQS_DP4")
		)
		(pad "U12" smd circle
			(at -10.67816 -5.48894 180)
			(size 0.3048 0.3048)
			(layers "F.Cu" "F.Mask" "F.Paste")
			(net "M_B_DQS_DN4")
		)
		(pad "U14" smd circle
			(at -9.91616 -5.48894 180)
			(size 0.3048 0.3048)
			(layers "F.Cu" "F.Mask" "F.Paste")
			(net "GND")
		)
		(pad "U15" smd circle
			(at -9.15416 -5.48894 180)
			(size 0.3048 0.3048)
			(layers "F.Cu" "F.Mask" "F.Paste")
			(net "M_B_DQ37")
		)
		(pad "U62" smd circle
			(at 14.06398 -5.1181 180)
			(size 0.3048 0.3048)
			(layers "F.Cu" "F.Mask" "F.Paste")
			(net "GND")
		)
		(pad "U63" smd circle
			(at 14.75232 -5.28574 180)
			(size 0.3048 0.3048)
			(layers "F.Cu" "F.Mask" "F.Paste")
			(net "GND")
		)
		(pad "U65" smd circle
			(at 15.80642 -5.36702 180)
			(size 0.3048 0.3048)
			(layers "F.Cu" "F.Mask" "F.Paste")
			(net "GND")
		)
		(pad "V5" smd circle
			(at -14.06398 -4.90982 180)
			(size 0.3048 0.3048)
			(layers "F.Cu" "F.Mask" "F.Paste")
			(net "GND")
		)
		(pad "V20" smd circle
			(at -6.72592 -4.8006 180)
			(size 0.3048 0.3048)
			(layers "F.Cu" "F.Mask" "F.Paste")
			(net "P1V0")
		)
		(pad "V21" smd circle
			(at -5.99948 -4.8006 180)
			(size 0.381 0.381)
			(layers "F.Cu" "F.Mask" "F.Paste")
			(net "P1V0")
		)
		(pad "V23" smd circle
			(at -5.20192 -4.8006 180)
			(size 0.381 0.381)
			(layers "F.Cu" "F.Mask" "F.Paste")
			(net "P1V0")
		)
		(pad "V25" smd circle
			(at -4.39928 -4.8006 180)
			(size 0.381 0.381)
			(layers "F.Cu" "F.Mask" "F.Paste")
			(net "P1V0")
		)
		(pad "V26" smd circle
			(at -3.60172 -4.8006 180)
			(size 0.381 0.381)
			(layers "F.Cu" "F.Mask" "F.Paste")
			(net "P1V0")
		)
		(pad "V28" smd circle
			(at -2.79908 -4.8006 180)
			(size 0.381 0.381)
			(layers "F.Cu" "F.Mask" "F.Paste")
			(net "VCCACKDDR1")
		)
		(pad "V29" smd circle
			(at -2.00152 -4.8006 180)
			(size 0.381 0.381)
			(layers "F.Cu" "F.Mask" "F.Paste")
			(net "VCCCLKDDR1")
		)
		(pad "V31" smd circle
			(at -1.19888 -4.8006 180)
			(size 0.381 0.381)
			(layers "F.Cu" "F.Mask" "F.Paste")
			(net "P1V35")
		)
		(pad "V32" smd circle
			(at -0.40132 -4.8006 180)
			(size 0.381 0.381)
			(layers "F.Cu" "F.Mask" "F.Paste")
			(net "GND")
		)
		(pad "V34" smd circle
			(at 0.40132 -4.8006 180)
			(size 0.381 0.381)
			(layers "F.Cu" "F.Mask" "F.Paste")
			(net "P1V35")
		)
		(pad "V36" smd circle
			(at 1.19888 -4.8006 180)
			(size 0.381 0.381)
			(layers "F.Cu" "F.Mask" "F.Paste")
			(net "GND")
		)
		(pad "V38" smd circle
			(at 2.00152 -4.8006 180)
			(size 0.381 0.381)
			(layers "F.Cu" "F.Mask" "F.Paste")
			(net "P1V0_STBY")
		)
		(pad "V39" smd circle
			(at 2.79908 -4.8006 180)
			(size 0.381 0.381)
			(layers "F.Cu" "F.Mask" "F.Paste")
			(net "P1V0_STBY")
		)
		(pad "V41" smd circle
			(at 3.60172 -4.8006 180)
			(size 0.381 0.381)
			(layers "F.Cu" "F.Mask" "F.Paste")
			(net "P1V0_STBY")
		)
		(pad "V42" smd circle
			(at 4.39928 -4.8006 180)
			(size 0.381 0.381)
			(layers "F.Cu" "F.Mask" "F.Paste")
			(net "GND")
		)
		(pad "V44" smd circle
			(at 5.20192 -4.8006 180)
			(size 0.381 0.381)
			(layers "F.Cu" "F.Mask" "F.Paste")
			(net "GND")
		)
		(pad "V46" smd circle
			(at 5.99948 -4.8006 180)
			(size 0.381 0.381)
			(layers "F.Cu" "F.Mask" "F.Paste")
			(net "P1V0")
		)
		(pad "V63" smd circle
			(at 14.5415 -4.60756 180)
			(size 0.3048 0.3048)
			(layers "F.Cu" "F.Mask" "F.Paste")
			(net "GBE_WOL")
		)
		(pad "V64" smd circle
			(at 15.3035 -4.55676 180)
			(size 0.3048 0.3048)
			(layers "F.Cu" "F.Mask" "F.Paste")
			(net "PMU_SLP_S45#")
		)
		(pad "V66" smd oval
			(at 16.24838 -4.60756 180)
			(size 0.3429 0.254)
			(layers "F.Cu" "F.Mask" "F.Paste")
			(net "SPI_CPU_WP#")
		)
		(pad "W1" smd oval
			(at -16.24838 -4.39928 180)
			(size 0.3429 0.254)
			(layers "F.Cu" "F.Mask" "F.Paste")
			(net "M_B_DQS_DP5")
		)
		(pad "W3" smd circle
			(at -15.3035 -4.45008 180)
			(size 0.3048 0.3048)
			(layers "F.Cu" "F.Mask" "F.Paste")
			(net "M_B_DQS_DN5")
		)
		(pad "W4" smd circle
			(at -14.5415 -4.39928 180)
			(size 0.3048 0.3048)
			(layers "F.Cu" "F.Mask" "F.Paste")
			(net "GND")
		)
		(pad "W7" smd circle
			(at -13.34516 -4.2037 180)
			(size 0.3048 0.3048)
			(layers "F.Cu" "F.Mask" "F.Paste")
			(net "M_B_DQS_DN6")
		)
		(pad "W8" smd circle
			(at -12.58316 -4.2037 180)
			(size 0.3048 0.3048)
			(layers "F.Cu" "F.Mask" "F.Paste")
			(net "M_B_DQ54")
		)
		(pad "W10" smd circle
			(at -11.82116 -4.2037 180)
			(size 0.3048 0.3048)
			(layers "F.Cu" "F.Mask" "F.Paste")
			(net "M_B_DQ50")
		)
		(pad "W11" smd circle
			(at -11.05916 -4.2037 180)
			(size 0.3048 0.3048)
			(layers "F.Cu" "F.Mask" "F.Paste")
			(net "GND")
		)
		(pad "W13" smd circle
			(at -10.29716 -4.2037 180)
			(size 0.3048 0.3048)
			(layers "F.Cu" "F.Mask" "F.Paste")
			(net "M_B_DQ49")
		)
		(pad "W14" smd circle
			(at -9.53516 -4.2037 180)
			(size 0.3048 0.3048)
			(layers "F.Cu" "F.Mask" "F.Paste")
			(net "M_B_DQ48")
		)
		(pad "W16" smd circle
			(at -8.77316 -4.2037 180)
			(size 0.3048 0.3048)
			(layers "F.Cu" "F.Mask" "F.Paste")
			(net "GND")
		)
		(pad "W17" smd circle
			(at -8.01116 -4.2037 180)
			(size 0.3048 0.3048)
			(layers "F.Cu" "F.Mask" "F.Paste")
			(net "GND")
		)
		(pad "W19" smd circle
			(at -7.24916 -4.2037 180)
			(size 0.3048 0.3048)
			(layers "F.Cu" "F.Mask" "F.Paste")
			(net "GND")
		)
		(pad "W21" smd circle
			(at -5.99948 -4.0005 180)
			(size 0.381 0.381)
			(layers "F.Cu" "F.Mask" "F.Paste")
			(net "P1V0")
		)
		(pad "W23" smd circle
			(at -5.20192 -4.0005 180)
			(size 0.381 0.381)
			(layers "F.Cu" "F.Mask" "F.Paste")
			(net "P1V0")
		)
		(pad "W25" smd circle
			(at -4.39928 -4.0005 180)
			(size 0.381 0.381)
			(layers "F.Cu" "F.Mask" "F.Paste")
			(net "P1V0")
		)
		(pad "W26" smd circle
			(at -3.60172 -4.0005 180)
			(size 0.381 0.381)
			(layers "F.Cu" "F.Mask" "F.Paste")
			(net "P1V0")
		)
		(pad "W28" smd circle
			(at -2.79908 -4.0005 180)
			(size 0.381 0.381)
			(layers "F.Cu" "F.Mask" "F.Paste")
			(net "VCCACKDDR1")
		)
		(pad "W29" smd circle
			(at -2.00152 -4.0005 180)
			(size 0.381 0.381)
			(layers "F.Cu" "F.Mask" "F.Paste")
			(net "VCCCLKDDR1")
		)
		(pad "W31" smd circle
			(at -1.19888 -4.0005 180)
			(size 0.381 0.381)
			(layers "F.Cu" "F.Mask" "F.Paste")
			(net "VCCA_PLLDDR1_AVN")
		)
		(pad "W32" smd circle
			(at -0.40132 -4.0005 180)
			(size 0.381 0.381)
			(layers "F.Cu" "F.Mask" "F.Paste")
			(net "GND")
		)
		(pad "W34" smd circle
			(at 0.40132 -4.0005 180)
			(size 0.381 0.381)
			(layers "F.Cu" "F.Mask" "F.Paste")
			(net "P1V35")
		)
		(pad "W36" smd circle
			(at 1.19888 -4.0005 180)
			(size 0.381 0.381)
			(layers "F.Cu" "F.Mask" "F.Paste")
			(net "GND")
		)
		(pad "W38" smd circle
			(at 2.00152 -4.0005 180)
			(size 0.381 0.381)
			(layers "F.Cu" "F.Mask" "F.Paste")
			(net "P1V0_STBY")
		)
		(pad "W39" smd circle
			(at 2.79908 -4.0005 180)
			(size 0.381 0.381)
			(layers "F.Cu" "F.Mask" "F.Paste")
			(net "GND")
		)
		(pad "W41" smd circle
			(at 3.60172 -4.0005 180)
			(size 0.381 0.381)
			(layers "F.Cu" "F.Mask" "F.Paste")
			(net "P1V0_STBY")
		)
		(pad "W42" smd circle
			(at 4.39928 -4.0005 180)
			(size 0.381 0.381)
			(layers "F.Cu" "F.Mask" "F.Paste")
			(net "GND")
		)
		(pad "W44" smd circle
			(at 5.20192 -4.0005 180)
			(size 0.381 0.381)
			(layers "F.Cu" "F.Mask" "F.Paste")
			(net "P1V0")
		)
		(pad "W46" smd circle
			(at 5.99948 -4.0005 180)
			(size 0.381 0.381)
			(layers "F.Cu" "F.Mask" "F.Paste")
			(net "P1V0")
		)
		(pad "W48" smd circle
			(at 7.24916 -4.44246 180)
			(size 0.3048 0.3048)
			(layers "F.Cu" "F.Mask" "F.Paste")
			(net "GND")
		)
		(pad "W50" smd circle
			(at 8.01116 -4.44246 180)
			(size 0.3048 0.3048)
			(layers "F.Cu" "F.Mask" "F.Paste")
			(net "BD_REV_1")
		)
		(pad "W51" smd circle
			(at 8.77316 -4.44246 180)
			(size 0.3048 0.3048)
			(layers "F.Cu" "F.Mask" "F.Paste")
			(net "SPI_MOSI_GBE")
		)
		(pad "W53" smd circle
			(at 9.53516 -4.44246 180)
			(size 0.3048 0.3048)
			(layers "F.Cu" "F.Mask" "F.Paste")
			(net "GND")
		)
		(pad "W54" smd circle
			(at 10.29716 -4.44246 180)
			(size 0.3048 0.3048)
			(layers "F.Cu" "F.Mask" "F.Paste")
			(net "FPGA_READY#")
		)
		(pad "W56" smd circle
			(at 11.05916 -4.44246 180)
			(size 0.3048 0.3048)
			(layers "F.Cu" "F.Mask" "F.Paste")
			(net "GBE_MDIO_CLK0")
		)
		(pad "W57" smd circle
			(at 11.82116 -4.44246 180)
			(size 0.3048 0.3048)
			(layers "F.Cu" "F.Mask" "F.Paste")
			(net "GND")
		)
		(pad "W59" smd circle
			(at 12.58316 -4.44246 180)
			(size 0.3048 0.3048)
			(layers "F.Cu" "F.Mask" "F.Paste")
			(net "GBE_MDIO_DATA0")
		)
		(pad "W60" smd circle
			(at 13.34516 -4.44246 180)
			(size 0.3048 0.3048)
			(layers "F.Cu" "F.Mask" "F.Paste")
			(net "SPI_MISO_R_GBE")
		)
		(pad "W62" smd circle
			(at 14.06398 -4.09448 180)
			(size 0.3048 0.3048)
			(layers "F.Cu" "F.Mask" "F.Paste")
			(net "GND")
		)
		(pad "Y2" smd circle
			(at -15.80642 -3.63982 180)
			(size 0.3048 0.3048)
			(layers "F.Cu" "F.Mask" "F.Paste")
			(net "M_B_DQ47")
		)
		(pad "Y4" smd circle
			(at -14.75232 -3.71856 180)
			(size 0.3048 0.3048)
			(layers "F.Cu" "F.Mask" "F.Paste")
			(net "M_B_DQ46")
		)
		(pad "Y5" smd circle
			(at -14.06398 -3.88874 180)
			(size 0.3048 0.3048)
			(layers "F.Cu" "F.Mask" "F.Paste")
			(net "GND")
		)
		(pad "Y7" smd circle
			(at -13.34516 -3.50266 180)
			(size 0.3048 0.3048)
			(layers "F.Cu" "F.Mask" "F.Paste")
			(net "M_B_DQS_DP6")
		)
		(pad "Y8" smd circle
			(at -12.58316 -3.50266 180)
			(size 0.3048 0.3048)
			(layers "F.Cu" "F.Mask" "F.Paste")
			(net "GND")
		)
		(pad "Y10" smd circle
			(at -11.82116 -3.50266 180)
			(size 0.3048 0.3048)
			(layers "F.Cu" "F.Mask" "F.Paste")
			(net "M_B_DQ55")
		)
		(pad "Y11" smd circle
			(at -11.05916 -3.50266 180)
			(size 0.3048 0.3048)
			(layers "F.Cu" "F.Mask" "F.Paste")
			(net "M_B_DQ51")
		)
		(pad "Y13" smd circle
			(at -10.29716 -3.50266 180)
			(size 0.3048 0.3048)
			(layers "F.Cu" "F.Mask" "F.Paste")
			(net "GND")
		)
		(pad "Y14" smd circle
			(at -9.53516 -3.50266 180)
			(size 0.3048 0.3048)
			(layers "F.Cu" "F.Mask" "F.Paste")
			(net "M_B_DQ53")
		)
		(pad "Y16" smd circle
			(at -8.77316 -3.50266 180)
			(size 0.3048 0.3048)
			(layers "F.Cu" "F.Mask" "F.Paste")
			(net "M_B_DQ52")
		)
		(pad "Y17" smd circle
			(at -8.01116 -3.50266 180)
			(size 0.3048 0.3048)
			(layers "F.Cu" "F.Mask" "F.Paste")
			(net "GND")
		)
		(pad "Y19" smd circle
			(at -7.24916 -3.50266 180)
			(size 0.3048 0.3048)
			(layers "F.Cu" "F.Mask" "F.Paste")
			(net "GND")
		)
		(pad "Y48" smd circle
			(at 7.24916 -3.74142 180)
			(size 0.3048 0.3048)
			(layers "F.Cu" "F.Mask" "F.Paste")
			(net "GND")
		)
		(pad "Y50" smd circle
			(at 8.01116 -3.74142 180)
			(size 0.3048 0.3048)
			(layers "F.Cu" "F.Mask" "F.Paste")
			(net "PMU_SLP_LAN#")
		)
		(pad "Y51" smd circle
			(at 8.77316 -3.74142 180)
			(size 0.3048 0.3048)
			(layers "F.Cu" "F.Mask" "F.Paste")
			(net "GND")
		)
		(pad "Y53" smd circle
			(at 9.53516 -3.74142 180)
			(size 0.3048 0.3048)
			(layers "F.Cu" "F.Mask" "F.Paste")
			(net "REV_CPU_FPGA_IO1")
		)
		(pad "Y54" smd circle
			(at 10.29716 -3.74142 180)
			(size 0.3048 0.3048)
			(layers "F.Cu" "F.Mask" "F.Paste")
			(net "REV_CPU_FPGA_IO0")
		)
		(pad "Y56" smd circle
			(at 11.05916 -3.74142 180)
			(size 0.3048 0.3048)
			(layers "F.Cu" "F.Mask" "F.Paste")
			(net "GND")
		)
		(pad "Y57" smd circle
			(at 11.82116 -3.74142 180)
			(size 0.3048 0.3048)
			(layers "F.Cu" "F.Mask" "F.Paste")
			(net "SUSPWRDNACK")
		)
		(pad "Y59" smd circle
			(at 12.58316 -3.74142 180)
			(size 0.3048 0.3048)
			(layers "F.Cu" "F.Mask" "F.Paste")
			(net "TP_CPU_RSVD13")
		)
		(pad "Y60" smd circle
			(at 13.34516 -3.74142 180)
			(size 0.3048 0.3048)
			(layers "F.Cu" "F.Mask" "F.Paste")
			(net "GND")
		)
		(pad "Y63" smd circle
			(at 14.7955 -3.937 180)
			(size 0.3048 0.3048)
			(layers "F.Cu" "F.Mask" "F.Paste")
			(net "XDP_CPU_RESET#")
		)
		(pad "Y65" smd circle
			(at 15.75308 -3.8862 180)
			(size 0.3048 0.3048)
			(layers "F.Cu" "F.Mask" "F.Paste")
			(net "SPI_CPU_CS0#")
		)
	)
	(footprint ""
		(layer "F.Cu")
		(at 15.24 -31.877)
		(property "Reference" "PR196"
			(at 0 0 0)
			(layer "F.SilkS")
			(hide yes)
			(effects
				(font
					(size 1.27 1.27)
				)
			)
		)
		(property "Value" "10KR2F-2-GP"
			(at 1.7907 -1.1176 0)
			(unlocked yes)
			(layer "F.Fab")
			(hide yes)
			(effects
				(font
					(size 1.016 1.016)
					(thickness 0.1524)
				)
			)
		)
		(property "Device Type" "R402H16"
			(at 1.7907 -2.6416 0)
			(unlocked yes)
			(layer "F.Fab")
			(hide yes)
			(effects
				(font
					(size 1.016 1.016)
					(thickness 0.1524)
				)
			)
		)
		(duplicate_pad_numbers_are_jumpers no)
		(fp_rect
			(start -0.381 0.8382)
			(end 0.381 -0.8382)
			(stroke
				(width 0)
				(type default)
			)
			(fill no)
			(layer "F.CrtYd")
		)
		(fp_rect
			(start -0.381 0.8382)
			(end 0.381 -0.8382)
			(stroke
				(width 0)
				(type default)
			)
			(fill no)
			(layer "F.Fab")
		)
		(pad "1" smd custom
			(at 0 -0.4318)
			(size 0.127 0.127)
			(layers "F.Cu" "F.Mask" "F.Paste")
			(net "P3V3_STBY_EN")
			(options
				(clearance outline)
				(anchor circle)
			)
			(primitives
				(gr_poly
					(pts
						(arc
							(start -0.2032 -0.2794)
							(mid -0.239121 -0.264521)
							(end -0.254 -0.2286)
						)
						(arc
							(start -0.254 0.2286)
							(mid -0.239121 0.264521)
							(end -0.2032 0.2794)
						)
						(arc
							(start 0.2032 0.2794)
							(mid 0.239121 0.264521)
							(end 0.254 0.2286)
						)
						(arc
							(start 0.254 -0.2286)
							(mid 0.239121 -0.264521)
							(end 0.2032 -0.2794)
						)
					)
					(width 0)
					(fill yes)
				)
			)
		)
		(pad "2" smd custom
			(at 0 0.4318)
			(size 0.127 0.127)
			(layers "F.Cu" "F.Mask" "F.Paste")
			(net "P12V")
			(options
				(clearance outline)
				(anchor circle)
			)
			(primitives
				(gr_poly
					(pts
						(arc
							(start -0.2032 -0.2794)
							(mid -0.239121 -0.264521)
							(end -0.254 -0.2286)
						)
						(arc
							(start -0.254 0.2286)
							(mid -0.239121 0.264521)
							(end -0.2032 0.2794)
						)
						(arc
							(start 0.2032 0.2794)
							(mid 0.239121 0.264521)
							(end 0.254 0.2286)
						)
						(arc
							(start 0.254 -0.2286)
							(mid 0.239121 -0.264521)
							(end 0.2032 -0.2794)
						)
					)
					(width 0)
					(fill yes)
				)
			)
		)
	)
	(footprint ""
		(layer "F.Cu")
		(at 154.7876 -59.309)
		(property "Reference" "C329"
			(at 0 0 0)
			(layer "F.SilkS")
			(hide yes)
			(effects
				(font
					(size 1.27 1.27)
				)
			)
		)
		(property "Value" "SCD1U16V2KX-3GP"
			(at 1.8923 -1.2065 0)
			(unlocked yes)
			(layer "F.Fab")
			(hide yes)
			(effects
				(font
					(size 1.016 1.016)
					(thickness 0.1524)
				)
			)
		)
		(property "Device Type" "C402H22"
			(at 1.8923 -2.7305 0)
			(unlocked yes)
			(layer "F.Fab")
			(hide yes)
			(effects
				(font
					(size 1.016 1.016)
					(thickness 0.1524)
				)
			)
		)
		(duplicate_pad_numbers_are_jumpers no)
		(fp_rect
			(start -0.381 0.7366)
			(end 0.381 -0.7366)
			(stroke
				(width 0)
				(type default)
			)
			(fill no)
			(layer "F.CrtYd")
		)
		(fp_rect
			(start -0.381 0.7366)
			(end 0.381 -0.7366)
			(stroke
				(width 0)
				(type default)
			)
			(fill no)
			(layer "F.Fab")
		)
		(pad "1" smd custom
			(at 0 -0.4572)
			(size 0.1143 0.1143)
			(layers "F.Cu" "F.Mask" "F.Paste")
			(net "PV_VDDR")
			(options
				(clearance outline)
				(anchor circle)
			)
			(primitives
				(gr_poly
					(pts
						(arc
							(start -0.254 -0.1778)
							(mid -0.239121 -0.213721)
							(end -0.2032 -0.2286)
						)
						(arc
							(start 0.2032 -0.2286)
							(mid 0.239121 -0.213721)
							(end 0.254 -0.1778)
						)
						(arc
							(start 0.254 0.1778)
							(mid 0.239121 0.213721)
							(end 0.2032 0.2286)
						)
						(arc
							(start -0.2032 0.2286)
							(mid -0.239121 0.213721)
							(end -0.254 0.1778)
						)
					)
					(width 0)
					(fill yes)
				)
			)
		)
		(pad "2" smd custom
			(at 0 0.4572)
			(size 0.1143 0.1143)
			(layers "F.Cu" "F.Mask" "F.Paste")
			(net "GND")
			(options
				(clearance outline)
				(anchor circle)
			)
			(primitives
				(gr_poly
					(pts
						(arc
							(start -0.254 -0.1778)
							(mid -0.239121 -0.213721)
							(end -0.2032 -0.2286)
						)
						(arc
							(start 0.2032 -0.2286)
							(mid 0.239121 -0.213721)
							(end 0.254 -0.1778)
						)
						(arc
							(start 0.254 0.1778)
							(mid 0.239121 0.213721)
							(end 0.2032 0.2286)
						)
						(arc
							(start -0.2032 0.2286)
							(mid -0.239121 0.213721)
							(end -0.254 0.1778)
						)
					)
					(width 0)
					(fill yes)
				)
			)
		)
	)
	(footprint ""
		(layer "F.Cu")
		(at 95.758 -14.097 180)
		(property "Reference" "C319"
			(at 0 0 180)
			(layer "F.SilkS")
			(hide yes)
			(effects
				(font
					(size 1.27 1.27)
				)
			)
		)
		(property "Value" "SC22U25V5MX-GP"
			(at 0 -4.9022 180)
			(unlocked yes)
			(layer "F.Fab")
			(hide yes)
			(effects
				(font
					(size 1.016 1.016)
					(thickness 0.1524)
				)
			)
		)
		(property "Device Type" "C805H58"
			(at 0 -6.8072 180)
			(unlocked yes)
			(layer "F.Fab")
			(hide yes)
			(effects
				(font
					(size 1.016 1.016)
					(thickness 0.1524)
				)
			)
		)
		(duplicate_pad_numbers_are_jumpers no)
		(fp_line
			(start 0.6096 0)
			(end -0.6096 0)
			(stroke
				(width 0.3048)
				(type default)
			)
			(layer "F.SilkS")
		)
		(fp_poly
			(pts
				(xy -0.9017 1.4351) (xy 0.9017 1.4351) (xy 0.9017 -1.4351) (xy -0.9017 -1.4351)
			)
			(stroke
				(width 0)
				(type default)
			)
			(fill no)
			(layer "F.CrtYd")
		)
		(fp_poly
			(pts
				(xy 0.9017 1.4351) (xy 0.9017 -1.4351) (xy -0.9017 -1.4351) (xy -0.9017 1.4351)
			)
			(stroke
				(width 0)
				(type default)
			)
			(fill no)
			(layer "F.Fab")
		)
		(pad "1" smd rect
			(at 0 -0.8382 180)
			(size 1.5494 0.9398)
			(layers "F.Cu" "F.Mask" "F.Paste")
			(net "P12V")
		)
		(pad "2" smd rect
			(at 0 0.8382 180)
			(size 1.5494 0.9398)
			(layers "F.Cu" "F.Mask" "F.Paste")
			(net "GND")
		)
	)
	(footprint ""
		(layer "F.Cu")
		(at 41.3004 -39.4208 90)
		(property "Reference" "R69"
			(at 0 0 90)
			(layer "F.SilkS")
			(hide yes)
			(effects
				(font
					(size 1.27 1.27)
				)
			)
		)
		(property "Value" "8K2R2F-1-GP"
			(at 1.7907 -1.1176 90)
			(unlocked yes)
			(layer "F.Fab")
			(hide yes)
			(effects
				(font
					(size 1.016 1.016)
					(thickness 0.1524)
				)
			)
		)
		(property "Device Type" "R402H16"
			(at 1.7907 -2.6416 90)
			(unlocked yes)
			(layer "F.Fab")
			(hide yes)
			(effects
				(font
					(size 1.016 1.016)
					(thickness 0.1524)
				)
			)
		)
		(duplicate_pad_numbers_are_jumpers no)
		(fp_rect
			(start -0.381 0.8382)
			(end 0.381 -0.8382)
			(stroke
				(width 0)
				(type default)
			)
			(fill no)
			(layer "F.CrtYd")
		)
		(fp_rect
			(start -0.381 0.8382)
			(end 0.381 -0.8382)
			(stroke
				(width 0)
				(type default)
			)
			(fill no)
			(layer "F.Fab")
		)
		(pad "1" smd custom
			(at 0 -0.4318 90)
			(size 0.127 0.127)
			(layers "F.Cu" "F.Mask" "F.Paste")
			(net "P3V3")
			(options
				(clearance outline)
				(anchor circle)
			)
			(primitives
				(gr_poly
					(pts
						(arc
							(start -0.2032 -0.2794)
							(mid -0.239121 -0.264521)
							(end -0.254 -0.2286)
						)
						(arc
							(start -0.254 0.2286)
							(mid -0.239121 0.264521)
							(end -0.2032 0.2794)
						)
						(arc
							(start 0.2032 0.2794)
							(mid 0.239121 0.264521)
							(end 0.254 0.2286)
						)
						(arc
							(start 0.254 -0.2286)
							(mid 0.239121 -0.264521)
							(end 0.2032 -0.2794)
						)
					)
					(width 0)
					(fill yes)
				)
			)
		)
		(pad "2" smd custom
			(at 0 0.4318 90)
			(size 0.127 0.127)
			(layers "F.Cu" "F.Mask" "F.Paste")
			(net "CLK_GEN_DELAY0_PG")
			(options
				(clearance outline)
				(anchor circle)
			)
			(primitives
				(gr_poly
					(pts
						(arc
							(start -0.2032 -0.2794)
							(mid -0.239121 -0.264521)
							(end -0.254 -0.2286)
						)
						(arc
							(start -0.254 0.2286)
							(mid -0.239121 0.264521)
							(end -0.2032 0.2794)
						)
						(arc
							(start 0.2032 0.2794)
							(mid 0.239121 0.264521)
							(end 0.254 0.2286)
						)
						(arc
							(start 0.254 -0.2286)
							(mid 0.239121 -0.264521)
							(end 0.2032 -0.2794)
						)
					)
					(width 0)
					(fill yes)
				)
			)
		)
	)
	(footprint ""
		(layer "F.Cu")
		(at 25.1206 -51.3588)
		(property "Reference" "PC58"
			(at 0 0 0)
			(layer "F.SilkS")
			(hide yes)
			(effects
				(font
					(size 1.27 1.27)
				)
			)
		)
		(property "Value" "SC150P50V2KX-GP"
			(at 1.8923 -1.2065 0)
			(unlocked yes)
			(layer "F.Fab")
			(hide yes)
			(effects
				(font
					(size 1.016 1.016)
					(thickness 0.1524)
				)
			)
		)
		(property "Device Type" "C402H22"
			(at 1.8923 -2.7305 0)
			(unlocked yes)
			(layer "F.Fab")
			(hide yes)
			(effects
				(font
					(size 1.016 1.016)
					(thickness 0.1524)
				)
			)
		)
		(duplicate_pad_numbers_are_jumpers no)
		(fp_rect
			(start -0.381 0.7366)
			(end 0.381 -0.7366)
			(stroke
				(width 0)
				(type default)
			)
			(fill no)
			(layer "F.CrtYd")
		)
		(fp_rect
			(start -0.381 0.7366)
			(end 0.381 -0.7366)
			(stroke
				(width 0)
				(type default)
			)
			(fill no)
			(layer "F.Fab")
		)
		(pad "1" smd custom
			(at 0 -0.4572)
			(size 0.1143 0.1143)
			(layers "F.Cu" "F.Mask" "F.Paste")
			(net "VR_PVCCP_ISUMN_RC")
			(options
				(clearance outline)
				(anchor circle)
			)
			(primitives
				(gr_poly
					(pts
						(arc
							(start -0.254 -0.1778)
							(mid -0.239121 -0.213721)
							(end -0.2032 -0.2286)
						)
						(arc
							(start 0.2032 -0.2286)
							(mid 0.239121 -0.213721)
							(end 0.254 -0.1778)
						)
						(arc
							(start 0.254 0.1778)
							(mid 0.239121 0.213721)
							(end 0.2032 0.2286)
						)
						(arc
							(start -0.2032 0.2286)
							(mid -0.239121 0.213721)
							(end -0.254 0.1778)
						)
					)
					(width 0)
					(fill yes)
				)
			)
		)
		(pad "2" smd custom
			(at 0 0.4572)
			(size 0.1143 0.1143)
			(layers "F.Cu" "F.Mask" "F.Paste")
			(net "VR_PVCCP_ISUMN")
			(options
				(clearance outline)
				(anchor circle)
			)
			(primitives
				(gr_poly
					(pts
						(arc
							(start -0.254 -0.1778)
							(mid -0.239121 -0.213721)
							(end -0.2032 -0.2286)
						)
						(arc
							(start 0.2032 -0.2286)
							(mid 0.239121 -0.213721)
							(end 0.254 -0.1778)
						)
						(arc
							(start 0.254 0.1778)
							(mid 0.239121 0.213721)
							(end 0.2032 0.2286)
						)
						(arc
							(start -0.2032 0.2286)
							(mid -0.239121 0.213721)
							(end -0.254 0.1778)
						)
					)
					(width 0)
					(fill yes)
				)
			)
		)
	)
	(footprint ""
		(layer "F.Cu")
		(at 160.5026 -46.99 -90)
		(property "Reference" "U25"
			(at 0 0 270)
			(layer "F.SilkS")
			(hide yes)
			(effects
				(font
					(size 1.27 1.27)
				)
			)
		)
		(property "Value" "2N7002DW-7F-GP"
			(at -2.5654 1.1049 270)
			(unlocked yes)
			(layer "F.Fab")
			(hide yes)
			(effects
				(font
					(size 1.016 1.016)
					(thickness 0.1524)
				)
			)
		)
		(property "Device Type" "SOT-363H44"
			(at -2.5654 -0.4191 270)
			(unlocked yes)
			(layer "F.Fab")
			(hide yes)
			(effects
				(font
					(size 1.016 1.016)
					(thickness 0.1524)
				)
			)
		)
		(duplicate_pad_numbers_are_jumpers no)
		(fp_poly
			(pts
				(xy -0.6731 1.4351) (xy -0.9779 1.7399) (xy -0.381 1.7399) (xy -0.3683 1.7399) (xy -0.381 1.7272)
			)
			(stroke
				(width 0)
				(type default)
			)
			(fill yes)
			(layer "F.SilkS")
		)
		(fp_poly
			(pts
				(xy 1.2573 0.8763) (xy 1.2573 -0.8763) (xy 0.9525 -0.8763) (xy 0.9525 -1.4351) (xy -0.9525 -1.4351)
				(xy -0.9525 -0.8763) (xy -1.2573 -0.8763) (xy -1.2573 0.8763) (xy -0.9525 0.8763) (xy -0.9525 1.4351)
				(xy 0.9525 1.4351) (xy 0.9525 0.8763)
			)
			(stroke
				(width 0)
				(type default)
			)
			(fill no)
			(layer "F.CrtYd")
		)
		(fp_poly
			(pts
				(xy 1.2573 0.8763) (xy 1.2573 -0.8763) (xy 0.9525 -0.8763) (xy 0.9525 -1.4351) (xy -0.9525 -1.4351)
				(xy -0.9525 -0.8763) (xy -1.2573 -0.8763) (xy -1.2573 0.8763) (xy -0.9525 0.8763) (xy -0.9525 1.4351)
				(xy 0.9525 1.4351) (xy 0.9525 0.8763)
			)
			(stroke
				(width 0)
				(type default)
			)
			(fill no)
			(layer "F.Fab")
		)
		(pad "1" smd rect
			(at -0.65024 0.8255 270)
			(size 0.3556 0.9652)
			(layers "F.Cu" "F.Mask" "F.Paste")
			(net "XDP_SOC_CPU_TMS_S")
		)
		(pad "2" smd rect
			(at 0 0.8255 270)
			(size 0.3556 0.9652)
			(layers "F.Cu" "F.Mask" "F.Paste")
			(net "JTAG_CHAIN_EN")
		)
		(pad "3" smd rect
			(at 0.65024 0.8255 270)
			(size 0.3556 0.9652)
			(layers "F.Cu" "F.Mask" "F.Paste")
			(net "JTAG_PLD_TCK_D")
		)
		(pad "4" smd rect
			(at 0.65024 -0.8255 270)
			(size 0.3556 0.9652)
			(layers "F.Cu" "F.Mask" "F.Paste")
			(net "XDP_SOC_CPU_TCK_S")
		)
		(pad "5" smd rect
			(at 0 -0.8255 270)
			(size 0.3556 0.9652)
			(layers "F.Cu" "F.Mask" "F.Paste")
			(net "JTAG_CHAIN_EN")
		)
		(pad "6" smd rect
			(at -0.65024 -0.8255 270)
			(size 0.3556 0.9652)
			(layers "F.Cu" "F.Mask" "F.Paste")
			(net "JTAG_PLD_TMS_D")
		)
	)
	(footprint ""
		(layer "F.Cu")
		(at 157.48 -25.781)
		(property "Reference" "TP63"
			(at 0 0 0)
			(layer "F.SilkS")
			(hide yes)
			(effects
				(font
					(size 1.27 1.27)
				)
			)
		)
		(property "Value" "TPAD28-1-GP-U"
			(at 0.0508 -1.9304 0)
			(unlocked yes)
			(layer "F.Fab")
			(hide yes)
			(effects
				(font
					(size 1.016 1.016)
					(thickness 0.1524)
				)
			)
		)
		(property "Device Type" "TPAD28-1-U"
			(at 0.0508 -3.4544 0)
			(unlocked yes)
			(layer "F.Fab")
			(hide yes)
			(effects
				(font
					(size 1.016 1.016)
					(thickness 0.1524)
				)
			)
		)
		(duplicate_pad_numbers_are_jumpers no)
		(fp_poly
			(pts
				(arc
					(start 0.3556 0)
					(mid -0.3556 0)
					(end 0.3556 0)
				)
			)
			(stroke
				(width 0)
				(type default)
			)
			(fill no)
			(layer "F.CrtYd")
		)
		(fp_poly
			(pts
				(arc
					(start 0.9525 0)
					(mid -0.9525 0)
					(end 0.9525 0)
				)
			)
			(stroke
				(width 0)
				(type default)
			)
			(fill no)
			(layer "F.Fab")
		)
		(pad "1" smd circle
			(at 0 0)
			(size 0.7112 0.7112)
			(layers "F.Cu" "F.Mask" "F.Paste")
			(net "TP_FPGA_P113")
		)
	)
	(footprint ""
		(layer "F.Cu")
		(at 32.258 -38.735 180)
		(property "Reference" "R488"
			(at 0 0 180)
			(layer "F.SilkS")
			(hide yes)
			(effects
				(font
					(size 1.27 1.27)
				)
			)
		)
		(property "Value" "51R2F-2-GP"
			(at 1.7907 -1.1176 180)
			(unlocked yes)
			(layer "F.Fab")
			(hide yes)
			(effects
				(font
					(size 1.016 1.016)
					(thickness 0.1524)
				)
			)
		)
		(property "Device Type" "R402H16"
			(at 1.7907 -2.6416 180)
			(unlocked yes)
			(layer "F.Fab")
			(hide yes)
			(effects
				(font
					(size 1.016 1.016)
					(thickness 0.1524)
				)
			)
		)
		(duplicate_pad_numbers_are_jumpers no)
		(fp_rect
			(start -0.381 0.8382)
			(end 0.381 -0.8382)
			(stroke
				(width 0)
				(type default)
			)
			(fill no)
			(layer "F.CrtYd")
		)
		(fp_rect
			(start -0.381 0.8382)
			(end 0.381 -0.8382)
			(stroke
				(width 0)
				(type default)
			)
			(fill no)
			(layer "F.Fab")
		)
		(pad "1" smd custom
			(at 0 -0.4318 180)
			(size 0.127 0.127)
			(layers "F.Cu" "F.Mask" "F.Paste")
			(net "XDP_SOC_CPU_TMS")
			(options
				(clearance outline)
				(anchor circle)
			)
			(primitives
				(gr_poly
					(pts
						(arc
							(start -0.2032 -0.2794)
							(mid -0.239121 -0.264521)
							(end -0.254 -0.2286)
						)
						(arc
							(start -0.254 0.2286)
							(mid -0.239121 0.264521)
							(end -0.2032 0.2794)
						)
						(arc
							(start 0.2032 0.2794)
							(mid 0.239121 0.264521)
							(end 0.254 0.2286)
						)
						(arc
							(start 0.254 -0.2286)
							(mid 0.239121 -0.264521)
							(end 0.2032 -0.2794)
						)
					)
					(width 0)
					(fill yes)
				)
			)
		)
		(pad "2" smd custom
			(at 0 0.4318 180)
			(size 0.127 0.127)
			(layers "F.Cu" "F.Mask" "F.Paste")
			(net "GND")
			(options
				(clearance outline)
				(anchor circle)
			)
			(primitives
				(gr_poly
					(pts
						(arc
							(start -0.2032 -0.2794)
							(mid -0.239121 -0.264521)
							(end -0.254 -0.2286)
						)
						(arc
							(start -0.254 0.2286)
							(mid -0.239121 0.264521)
							(end -0.2032 0.2794)
						)
						(arc
							(start 0.2032 0.2794)
							(mid 0.239121 0.264521)
							(end 0.254 0.2286)
						)
						(arc
							(start 0.254 -0.2286)
							(mid 0.239121 -0.264521)
							(end 0.2032 -0.2794)
						)
					)
					(width 0)
					(fill yes)
				)
			)
		)
	)
	(footprint ""
		(layer "F.Cu")
		(at 141.859 -48.26 -90)
		(property "Reference" "R78"
			(at 0 0 270)
			(layer "F.SilkS")
			(hide yes)
			(effects
				(font
					(size 1.27 1.27)
				)
			)
		)
		(property "Value" "10KR2F-2-GP"
			(at 0.064008 -3.993896 270)
			(unlocked yes)
			(layer "F.Fab")
			(hide yes)
			(effects
				(font
					(size 1.016 1.016)
					(thickness 0.1524)
				)
			)
		)
		(property "Device Type" "R402H16"
			(at 0.064008 -5.517896 270)
			(unlocked yes)
			(layer "F.Fab")
			(hide yes)
			(effects
				(font
					(size 1.016 1.016)
					(thickness 0.1524)
				)
			)
		)
		(duplicate_pad_numbers_are_jumpers no)
		(fp_rect
			(start -0.381 0.8382)
			(end 0.381 -0.8382)
			(stroke
				(width 0)
				(type default)
			)
			(fill no)
			(layer "F.CrtYd")
		)
		(fp_rect
			(start -0.381 0.8382)
			(end 0.381 -0.8382)
			(stroke
				(width 0)
				(type default)
			)
			(fill no)
			(layer "F.Fab")
		)
		(pad "1" smd custom
			(at 0 -0.4318 270)
			(size 0.127 0.127)
			(layers "F.Cu" "F.Mask" "F.Paste")
			(net "P3V3_STBY")
			(options
				(clearance outline)
				(anchor circle)
			)
			(primitives
				(gr_poly
					(pts
						(arc
							(start -0.2032 -0.2794)
							(mid -0.239121 -0.264521)
							(end -0.254 -0.2286)
						)
						(arc
							(start -0.254 0.2286)
							(mid -0.239121 0.264521)
							(end -0.2032 0.2794)
						)
						(arc
							(start 0.2032 0.2794)
							(mid 0.239121 0.264521)
							(end 0.254 0.2286)
						)
						(arc
							(start 0.254 -0.2286)
							(mid 0.239121 -0.264521)
							(end 0.2032 -0.2794)
						)
					)
					(width 0)
					(fill yes)
				)
			)
		)
		(pad "2" smd custom
			(at 0 0.4318 270)
			(size 0.127 0.127)
			(layers "F.Cu" "F.Mask" "F.Paste")
			(net "C_NCONFIG#")
			(options
				(clearance outline)
				(anchor circle)
			)
			(primitives
				(gr_poly
					(pts
						(arc
							(start -0.2032 -0.2794)
							(mid -0.239121 -0.264521)
							(end -0.254 -0.2286)
						)
						(arc
							(start -0.254 0.2286)
							(mid -0.239121 0.264521)
							(end -0.2032 0.2794)
						)
						(arc
							(start 0.2032 0.2794)
							(mid 0.239121 0.264521)
							(end 0.254 0.2286)
						)
						(arc
							(start 0.254 -0.2286)
							(mid 0.239121 -0.264521)
							(end 0.2032 -0.2794)
						)
					)
					(width 0)
					(fill yes)
				)
			)
		)
	)
	(footprint ""
		(layer "F.Cu")
		(at 34.7472 -65.659 180)
		(property "Reference" "PQ1"
			(at 0 0 180)
			(layer "F.SilkS")
			(hide yes)
			(effects
				(font
					(size 1.27 1.27)
				)
			)
		)
		(property "Value" "FDMC8200-GP"
			(at -4.6736 -4.6228 180)
			(unlocked yes)
			(layer "F.Fab")
			(hide yes)
			(effects
				(font
					(size 1.016 1.016)
					(thickness 0.1524)
				)
			)
		)
		(property "Device Type" "MLP8F3-G2P-1H32"
			(at -4.6736 -6.1468 180)
			(unlocked yes)
			(layer "F.Fab")
			(hide yes)
			(effects
				(font
					(size 1.016 1.016)
					(thickness 0.1524)
				)
			)
		)
		(duplicate_pad_numbers_are_jumpers no)
		(fp_poly
			(pts
				(xy 0.430784 -2.553208) (xy 1.49987 -2.553208) (xy 0.9652 -2.018792)
			)
			(stroke
				(width 0)
				(type default)
			)
			(fill yes)
			(layer "F.SilkS")
		)
		(fp_rect
			(start -1.7526 2.0066)
			(end 1.7526 -2.0066)
			(stroke
				(width 0)
				(type default)
			)
			(fill no)
			(layer "F.CrtYd")
		)
		(fp_rect
			(start -1.7526 2.0066)
			(end 1.7526 -2.0066)
			(stroke
				(width 0)
				(type default)
			)
			(fill no)
			(layer "F.Fab")
		)
		(pad "1" smd rect
			(at 0.975106 -1.524 180)
			(size 0.4064 0.7112)
			(layers "F.Cu" "F.Mask" "F.Paste")
			(net "VR_PVNN_GH_R")
		)
		(pad "2" smd rect
			(at 0.32512 -1.524 180)
			(size 0.4064 0.7112)
			(layers "F.Cu" "F.Mask" "F.Paste")
			(net "VR_FET_SW_P12V_PVCCP_PVNN")
		)
		(pad "3" smd rect
			(at -0.32512 -1.524 180)
			(size 0.4064 0.7112)
			(layers "F.Cu" "F.Mask" "F.Paste")
			(net "VR_FET_SW_P12V_PVCCP_PVNN")
		)
		(pad "4" smd rect
			(at -0.975106 -1.524 180)
			(size 0.4064 0.7112)
			(layers "F.Cu" "F.Mask" "F.Paste")
			(net "VR_FET_SW_P12V_PVCCP_PVNN")
		)
		(pad "5" smd rect
			(at -0.975106 1.524 180)
			(size 0.4064 0.7112)
			(layers "F.Cu" "F.Mask" "F.Paste")
			(net "GND")
		)
		(pad "6" smd rect
			(at -0.32512 1.524 180)
			(size 0.4064 0.7112)
			(layers "F.Cu" "F.Mask" "F.Paste")
			(net "GND")
		)
		(pad "7" smd rect
			(at 0.32512 1.524 180)
			(size 0.4064 0.7112)
			(layers "F.Cu" "F.Mask" "F.Paste")
			(net "GND")
		)
		(pad "8" smd rect
			(at 0.975106 1.524 180)
			(size 0.4064 0.7112)
			(layers "F.Cu" "F.Mask" "F.Paste")
			(net "VR_PVNN_LH_R")
		)
		(pad "9" smd rect
			(at 0 -0.670306 180)
			(size 2.4384 0.5588)
			(layers "F.Cu" "F.Mask" "F.Paste")
			(net "VR_FET_SW_P12V_PVCCP_PVNN")
		)
		(pad "10" smd rect
			(at 0 0.429006 180)
			(size 2.4384 1.0414)
			(layers "F.Cu" "F.Mask" "F.Paste")
			(net "VR_PVNN_PHASE")
		)
	)
	(footprint ""
		(layer "F.Cu")
		(at 203.4794 -58.2676 90)
		(property "Reference" "PC170"
			(at 0 0 90)
			(layer "F.SilkS")
			(hide yes)
			(effects
				(font
					(size 1.27 1.27)
				)
			)
		)
		(property "Value" "SC22U6D3V5MX-2GP"
			(at 0 -4.9022 90)
			(unlocked yes)
			(layer "F.Fab")
			(hide yes)
			(effects
				(font
					(size 1.016 1.016)
					(thickness 0.1524)
				)
			)
		)
		(property "Device Type" "C805H58"
			(at 0 -6.8072 90)
			(unlocked yes)
			(layer "F.Fab")
			(hide yes)
			(effects
				(font
					(size 1.016 1.016)
					(thickness 0.1524)
				)
			)
		)
		(duplicate_pad_numbers_are_jumpers no)
		(fp_line
			(start 0.6096 0)
			(end -0.6096 0)
			(stroke
				(width 0.3048)
				(type default)
			)
			(layer "F.SilkS")
		)
		(fp_poly
			(pts
				(xy -0.9017 1.4351) (xy 0.9017 1.4351) (xy 0.9017 -1.4351) (xy -0.9017 -1.4351)
			)
			(stroke
				(width 0)
				(type default)
			)
			(fill no)
			(layer "F.CrtYd")
		)
		(fp_poly
			(pts
				(xy 0.9017 1.4351) (xy 0.9017 -1.4351) (xy -0.9017 -1.4351) (xy -0.9017 1.4351)
			)
			(stroke
				(width 0)
				(type default)
			)
			(fill no)
			(layer "F.Fab")
		)
		(pad "1" smd rect
			(at 0 -0.8382 90)
			(size 1.5494 0.9398)
			(layers "F.Cu" "F.Mask" "F.Paste")
			(net "PV_VDDR")
		)
		(pad "2" smd rect
			(at 0 0.8382 90)
			(size 1.5494 0.9398)
			(layers "F.Cu" "F.Mask" "F.Paste")
			(net "GND")
		)
	)
	(footprint ""
		(layer "F.Cu")
		(at 23.38324 -68.6562 90)
		(property "Reference" "PD1"
			(at 0 0 90)
			(layer "F.SilkS")
			(hide yes)
			(effects
				(font
					(size 1.27 1.27)
				)
			)
		)
		(property "Value" "MM3Z5V6T1G-GP"
			(at 2.5527 -1.9812 90)
			(unlocked yes)
			(layer "F.Fab")
			(hide yes)
			(effects
				(font
					(size 1.016 1.016)
					(thickness 0.1524)
				)
			)
		)
		(property "Device Type" "SOD323AKH40"
			(at 2.5527 -3.5052 90)
			(unlocked yes)
			(layer "F.Fab")
			(hide yes)
			(effects
				(font
					(size 1.016 1.016)
					(thickness 0.1524)
				)
			)
		)
		(duplicate_pad_numbers_are_jumpers no)
		(fp_line
			(start 0.7747 1.7653)
			(end -0.7747 1.7653)
			(stroke
				(width 0.254)
				(type default)
			)
			(layer "F.SilkS")
		)
		(fp_rect
			(start -0.9017 1.6383)
			(end 0.9017 -1.6383)
			(stroke
				(width 0)
				(type default)
			)
			(fill no)
			(layer "F.CrtYd")
		)
		(fp_rect
			(start -0.9017 1.6383)
			(end 0.9017 -1.6383)
			(stroke
				(width 0)
				(type default)
			)
			(fill no)
			(layer "F.Fab")
		)
		(pad "A" smd rect
			(at 0 -1.100074 90)
			(size 0.5588 0.8128)
			(layers "F.Cu" "F.Mask" "F.Paste")
			(net "GND")
		)
		(pad "K" smd rect
			(at 0 1.100074 90)
			(size 0.5588 0.8128)
			(layers "F.Cu" "F.Mask" "F.Paste")
			(net "VCCP_Z")
		)
	)
	(footprint ""
		(layer "F.Cu")
		(at 40.132 -38.6588 90)
		(property "Reference" "R251"
			(at 0 0 90)
			(layer "F.SilkS")
			(hide yes)
			(effects
				(font
					(size 1.27 1.27)
				)
			)
		)
		(property "Value" "51R2F-2-GP"
			(at 0.064008 -3.993896 90)
			(unlocked yes)
			(layer "F.Fab")
			(hide yes)
			(effects
				(font
					(size 1.016 1.016)
					(thickness 0.1524)
				)
			)
		)
		(property "Device Type" "R402H16"
			(at 0.064008 -5.517896 90)
			(unlocked yes)
			(layer "F.Fab")
			(hide yes)
			(effects
				(font
					(size 1.016 1.016)
					(thickness 0.1524)
				)
			)
		)
		(duplicate_pad_numbers_are_jumpers no)
		(fp_rect
			(start -0.381 0.8382)
			(end 0.381 -0.8382)
			(stroke
				(width 0)
				(type default)
			)
			(fill no)
			(layer "F.CrtYd")
		)
		(fp_rect
			(start -0.381 0.8382)
			(end 0.381 -0.8382)
			(stroke
				(width 0)
				(type default)
			)
			(fill no)
			(layer "F.Fab")
		)
		(pad "1" smd custom
			(at 0 -0.4318 90)
			(size 0.127 0.127)
			(layers "F.Cu" "F.Mask" "F.Paste")
			(net "XDP_SOC_CPU_TCK")
			(options
				(clearance outline)
				(anchor circle)
			)
			(primitives
				(gr_poly
					(pts
						(arc
							(start -0.2032 -0.2794)
							(mid -0.239121 -0.264521)
							(end -0.254 -0.2286)
						)
						(arc
							(start -0.254 0.2286)
							(mid -0.239121 0.264521)
							(end -0.2032 0.2794)
						)
						(arc
							(start 0.2032 0.2794)
							(mid 0.239121 0.264521)
							(end 0.254 0.2286)
						)
						(arc
							(start 0.254 -0.2286)
							(mid 0.239121 -0.264521)
							(end 0.2032 -0.2794)
						)
					)
					(width 0)
					(fill yes)
				)
			)
		)
		(pad "2" smd custom
			(at 0 0.4318 90)
			(size 0.127 0.127)
			(layers "F.Cu" "F.Mask" "F.Paste")
			(net "GND")
			(options
				(clearance outline)
				(anchor circle)
			)
			(primitives
				(gr_poly
					(pts
						(arc
							(start -0.2032 -0.2794)
							(mid -0.239121 -0.264521)
							(end -0.254 -0.2286)
						)
						(arc
							(start -0.254 0.2286)
							(mid -0.239121 0.264521)
							(end -0.2032 0.2794)
						)
						(arc
							(start 0.2032 0.2794)
							(mid 0.239121 0.264521)
							(end 0.254 0.2286)
						)
						(arc
							(start 0.254 -0.2286)
							(mid 0.239121 -0.264521)
							(end 0.2032 -0.2794)
						)
					)
					(width 0)
					(fill yes)
				)
			)
		)
	)
	(footprint ""
		(layer "F.Cu")
		(at 24.3586 -51.3588)
		(property "Reference" "PR77"
			(at 0 0 0)
			(layer "F.SilkS")
			(hide yes)
			(effects
				(font
					(size 1.27 1.27)
				)
			)
		)
		(property "Value" "180R2F-1-GP"
			(at 1.7907 -1.1176 0)
			(unlocked yes)
			(layer "F.Fab")
			(hide yes)
			(effects
				(font
					(size 1.016 1.016)
					(thickness 0.1524)
				)
			)
		)
		(property "Device Type" "R402H16"
			(at 1.7907 -2.6416 0)
			(unlocked yes)
			(layer "F.Fab")
			(hide yes)
			(effects
				(font
					(size 1.016 1.016)
					(thickness 0.1524)
				)
			)
		)
		(duplicate_pad_numbers_are_jumpers no)
		(fp_rect
			(start -0.381 0.8382)
			(end 0.381 -0.8382)
			(stroke
				(width 0)
				(type default)
			)
			(fill no)
			(layer "F.CrtYd")
		)
		(fp_rect
			(start -0.381 0.8382)
			(end 0.381 -0.8382)
			(stroke
				(width 0)
				(type default)
			)
			(fill no)
			(layer "F.Fab")
		)
		(pad "1" smd custom
			(at 0 -0.4318)
			(size 0.127 0.127)
			(layers "F.Cu" "F.Mask" "F.Paste")
			(net "VR_PVCCP_ISUMN_R")
			(options
				(clearance outline)
				(anchor circle)
			)
			(primitives
				(gr_poly
					(pts
						(arc
							(start -0.2032 -0.2794)
							(mid -0.239121 -0.264521)
							(end -0.254 -0.2286)
						)
						(arc
							(start -0.254 0.2286)
							(mid -0.239121 0.264521)
							(end -0.2032 0.2794)
						)
						(arc
							(start 0.2032 0.2794)
							(mid 0.239121 0.264521)
							(end 0.254 0.2286)
						)
						(arc
							(start 0.254 -0.2286)
							(mid 0.239121 -0.264521)
							(end 0.2032 -0.2794)
						)
					)
					(width 0)
					(fill yes)
				)
			)
		)
		(pad "2" smd custom
			(at 0 0.4318)
			(size 0.127 0.127)
			(layers "F.Cu" "F.Mask" "F.Paste")
			(net "VR_PVCCP_ISUMN")
			(options
				(clearance outline)
				(anchor circle)
			)
			(primitives
				(gr_poly
					(pts
						(arc
							(start -0.2032 -0.2794)
							(mid -0.239121 -0.264521)
							(end -0.254 -0.2286)
						)
						(arc
							(start -0.254 0.2286)
							(mid -0.239121 0.264521)
							(end -0.2032 0.2794)
						)
						(arc
							(start 0.2032 0.2794)
							(mid 0.239121 0.264521)
							(end 0.254 0.2286)
						)
						(arc
							(start 0.254 -0.2286)
							(mid 0.239121 -0.264521)
							(end 0.2032 -0.2794)
						)
					)
					(width 0)
					(fill yes)
				)
			)
		)
	)
	(footprint ""
		(layer "F.Cu")
		(at 17.272 -50.8 180)
		(property "Reference" "PR188"
			(at 0 0 180)
			(layer "F.SilkS")
			(hide yes)
			(effects
				(font
					(size 1.27 1.27)
				)
			)
		)
		(property "Value" "2K2R2F-GP"
			(at 1.7907 -1.1176 180)
			(unlocked yes)
			(layer "F.Fab")
			(hide yes)
			(effects
				(font
					(size 1.016 1.016)
					(thickness 0.1524)
				)
			)
		)
		(property "Device Type" "R402H16"
			(at 1.7907 -2.6416 180)
			(unlocked yes)
			(layer "F.Fab")
			(hide yes)
			(effects
				(font
					(size 1.016 1.016)
					(thickness 0.1524)
				)
			)
		)
		(duplicate_pad_numbers_are_jumpers no)
		(fp_rect
			(start -0.381 0.8382)
			(end 0.381 -0.8382)
			(stroke
				(width 0)
				(type default)
			)
			(fill no)
			(layer "F.CrtYd")
		)
		(fp_rect
			(start -0.381 0.8382)
			(end 0.381 -0.8382)
			(stroke
				(width 0)
				(type default)
			)
			(fill no)
			(layer "F.Fab")
		)
		(pad "1" smd custom
			(at 0 -0.4318 180)
			(size 0.127 0.127)
			(layers "F.Cu" "F.Mask" "F.Paste")
			(net "VR_PVCCP_COMP_RC")
			(options
				(clearance outline)
				(anchor circle)
			)
			(primitives
				(gr_poly
					(pts
						(arc
							(start -0.2032 -0.2794)
							(mid -0.239121 -0.264521)
							(end -0.254 -0.2286)
						)
						(arc
							(start -0.254 0.2286)
							(mid -0.239121 0.264521)
							(end -0.2032 0.2794)
						)
						(arc
							(start 0.2032 0.2794)
							(mid 0.239121 0.264521)
							(end 0.254 0.2286)
						)
						(arc
							(start 0.254 -0.2286)
							(mid 0.239121 -0.264521)
							(end 0.2032 -0.2794)
						)
					)
					(width 0)
					(fill yes)
				)
			)
		)
		(pad "2" smd custom
			(at 0 0.4318 180)
			(size 0.127 0.127)
			(layers "F.Cu" "F.Mask" "F.Paste")
			(net "VR_PVCCP_FB")
			(options
				(clearance outline)
				(anchor circle)
			)
			(primitives
				(gr_poly
					(pts
						(arc
							(start -0.2032 -0.2794)
							(mid -0.239121 -0.264521)
							(end -0.254 -0.2286)
						)
						(arc
							(start -0.254 0.2286)
							(mid -0.239121 0.264521)
							(end -0.2032 0.2794)
						)
						(arc
							(start 0.2032 0.2794)
							(mid 0.239121 0.264521)
							(end 0.254 0.2286)
						)
						(arc
							(start 0.254 -0.2286)
							(mid 0.239121 -0.264521)
							(end 0.2032 -0.2794)
						)
					)
					(width 0)
					(fill yes)
				)
			)
		)
	)
	(footprint ""
		(layer "F.Cu")
		(at 48.514 -49.149 -90)
		(property "Reference" "C25"
			(at 0 0 270)
			(layer "F.SilkS")
			(hide yes)
			(effects
				(font
					(size 1.27 1.27)
				)
			)
		)
		(property "Value" "SCD1U10V2KX-5GP"
			(at 1.1811 -2.7051 270)
			(unlocked yes)
			(layer "F.Fab")
			(hide yes)
			(effects
				(font
					(size 1.016 1.016)
					(thickness 0.1524)
				)
			)
		)
		(property "Device Type" "C402H22"
			(at 1.1811 -4.2291 270)
			(unlocked yes)
			(layer "F.Fab")
			(hide yes)
			(effects
				(font
					(size 1.016 1.016)
					(thickness 0.1524)
				)
			)
		)
		(duplicate_pad_numbers_are_jumpers no)
		(fp_rect
			(start -0.381 0.7366)
			(end 0.381 -0.7366)
			(stroke
				(width 0)
				(type default)
			)
			(fill no)
			(layer "F.CrtYd")
		)
		(fp_rect
			(start -0.381 0.7366)
			(end 0.381 -0.7366)
			(stroke
				(width 0)
				(type default)
			)
			(fill no)
			(layer "F.Fab")
		)
		(pad "1" smd custom
			(at 0 -0.4572 270)
			(size 0.1143 0.1143)
			(layers "F.Cu" "F.Mask" "F.Paste")
			(net "P1V5_CLK_SCR_LVIO")
			(options
				(clearance outline)
				(anchor circle)
			)
			(primitives
				(gr_poly
					(pts
						(arc
							(start -0.254 -0.1778)
							(mid -0.239121 -0.213721)
							(end -0.2032 -0.2286)
						)
						(arc
							(start 0.2032 -0.2286)
							(mid 0.239121 -0.213721)
							(end 0.254 -0.1778)
						)
						(arc
							(start 0.254 0.1778)
							(mid 0.239121 0.213721)
							(end 0.2032 0.2286)
						)
						(arc
							(start -0.2032 0.2286)
							(mid -0.239121 0.213721)
							(end -0.254 0.1778)
						)
					)
					(width 0)
					(fill yes)
				)
			)
		)
		(pad "2" smd custom
			(at 0 0.4572 270)
			(size 0.1143 0.1143)
			(layers "F.Cu" "F.Mask" "F.Paste")
			(net "GND")
			(options
				(clearance outline)
				(anchor circle)
			)
			(primitives
				(gr_poly
					(pts
						(arc
							(start -0.254 -0.1778)
							(mid -0.239121 -0.213721)
							(end -0.2032 -0.2286)
						)
						(arc
							(start 0.2032 -0.2286)
							(mid 0.239121 -0.213721)
							(end 0.254 -0.1778)
						)
						(arc
							(start 0.254 0.1778)
							(mid 0.239121 0.213721)
							(end 0.2032 0.2286)
						)
						(arc
							(start -0.2032 0.2286)
							(mid -0.239121 0.213721)
							(end -0.254 0.1778)
						)
					)
					(width 0)
					(fill yes)
				)
			)
		)
	)
	(footprint ""
		(layer "F.Cu")
		(at 18.3896 -52.6288 90)
		(property "Reference" "PC72"
			(at 0 0 90)
			(layer "F.SilkS")
			(hide yes)
			(effects
				(font
					(size 1.27 1.27)
				)
			)
		)
		(property "Value" "SC1KP50V2KX-1GP"
			(at 1.8923 -1.2065 90)
			(unlocked yes)
			(layer "F.Fab")
			(hide yes)
			(effects
				(font
					(size 1.016 1.016)
					(thickness 0.1524)
				)
			)
		)
		(property "Device Type" "C402H22"
			(at 1.8923 -2.7305 90)
			(unlocked yes)
			(layer "F.Fab")
			(hide yes)
			(effects
				(font
					(size 1.016 1.016)
					(thickness 0.1524)
				)
			)
		)
		(duplicate_pad_numbers_are_jumpers no)
		(fp_rect
			(start -0.381 0.7366)
			(end 0.381 -0.7366)
			(stroke
				(width 0)
				(type default)
			)
			(fill no)
			(layer "F.CrtYd")
		)
		(fp_rect
			(start -0.381 0.7366)
			(end 0.381 -0.7366)
			(stroke
				(width 0)
				(type default)
			)
			(fill no)
			(layer "F.Fab")
		)
		(pad "1" smd custom
			(at 0 -0.4572 90)
			(size 0.1143 0.1143)
			(layers "F.Cu" "F.Mask" "F.Paste")
			(net "GND")
			(options
				(clearance outline)
				(anchor circle)
			)
			(primitives
				(gr_poly
					(pts
						(arc
							(start -0.254 -0.1778)
							(mid -0.239121 -0.213721)
							(end -0.2032 -0.2286)
						)
						(arc
							(start 0.2032 -0.2286)
							(mid 0.239121 -0.213721)
							(end 0.254 -0.1778)
						)
						(arc
							(start 0.254 0.1778)
							(mid 0.239121 0.213721)
							(end 0.2032 0.2286)
						)
						(arc
							(start -0.2032 0.2286)
							(mid -0.239121 0.213721)
							(end -0.254 0.1778)
						)
					)
					(width 0)
					(fill yes)
				)
			)
		)
		(pad "2" smd custom
			(at 0 0.4572 90)
			(size 0.1143 0.1143)
			(layers "F.Cu" "F.Mask" "F.Paste")
			(net "VR_PVCCP_FB_RC2")
			(options
				(clearance outline)
				(anchor circle)
			)
			(primitives
				(gr_poly
					(pts
						(arc
							(start -0.254 -0.1778)
							(mid -0.239121 -0.213721)
							(end -0.2032 -0.2286)
						)
						(arc
							(start 0.2032 -0.2286)
							(mid 0.239121 -0.213721)
							(end 0.254 -0.1778)
						)
						(arc
							(start 0.254 0.1778)
							(mid 0.239121 0.213721)
							(end 0.2032 0.2286)
						)
						(arc
							(start -0.2032 0.2286)
							(mid -0.239121 0.213721)
							(end -0.254 0.1778)
						)
					)
					(width 0)
					(fill yes)
				)
			)
		)
	)
	(footprint ""
		(layer "F.Cu")
		(at 60.706 -32.004 180)
		(property "Reference" "Q7"
			(at 0 0 180)
			(layer "F.SilkS")
			(hide yes)
			(effects
				(font
					(size 1.27 1.27)
				)
			)
		)
		(property "Value" "MMBT3904TT1G-GP"
			(at 0 -9.7282 180)
			(unlocked yes)
			(layer "F.Fab")
			(hide yes)
			(effects
				(font
					(size 1.016 1.016)
					(thickness 0.1524)
				)
			)
		)
		(property "Device Type" "SC75CBE1D6H36"
			(at 0 -11.6332 180)
			(unlocked yes)
			(layer "F.Fab")
			(hide yes)
			(effects
				(font
					(size 1.016 1.016)
					(thickness 0.1524)
				)
			)
		)
		(duplicate_pad_numbers_are_jumpers no)
		(fp_poly
			(pts
				(xy 0.381 -1.1938) (xy -0.381 -1.1938) (xy -0.381 -0.6604) (xy -1.0541 -0.6604) (xy -1.0541 0.6604)
				(xy -0.889 0.6604) (xy -0.889 1.1938) (xy 0.889 1.1938) (xy 0.889 0.6604) (xy 1.0541 0.6604) (xy 1.0541 -0.6604)
				(xy 0.381 -0.6604)
			)
			(stroke
				(width 0)
				(type default)
			)
			(fill no)
			(layer "F.CrtYd")
		)
		(fp_poly
			(pts
				(xy 0.381 -1.1938) (xy -0.381 -1.1938) (xy -0.381 -0.6604) (xy -1.0541 -0.6604) (xy -1.0541 0.6604)
				(xy -0.889 0.6604) (xy -0.889 1.1938) (xy 0.889 1.1938) (xy 0.889 0.6604) (xy 1.0541 0.6604) (xy 1.0541 -0.6604)
				(xy 0.381 -0.6604)
			)
			(stroke
				(width 0)
				(type default)
			)
			(fill no)
			(layer "F.Fab")
		)
		(pad "B" smd custom
			(at -0.508 0.6604 180)
			(size 0.127 0.127)
			(layers "F.Cu" "F.Mask" "F.Paste")
			(net "P1V8_B")
			(options
				(clearance outline)
				(anchor circle)
			)
			(primitives
				(gr_poly
					(pts
						(arc
							(start -0.0508 0.4064)
							(mid -0.194484 0.346884)
							(end -0.254 0.2032)
						)
						(arc
							(start -0.254 -0.2032)
							(mid -0.194484 -0.346884)
							(end -0.0508 -0.4064)
						)
						(arc
							(start 0.0508 -0.4064)
							(mid 0.194484 -0.346884)
							(end 0.254 -0.2032)
						)
						(arc
							(start 0.254 0.2032)
							(mid 0.194484 0.346884)
							(end 0.0508 0.4064)
						)
					)
					(width 0)
					(fill yes)
				)
			)
		)
		(pad "C" smd custom
			(at 0 -0.6604 180)
			(size 0.127 0.127)
			(layers "F.Cu" "F.Mask" "F.Paste")
			(net "P1V8_G")
			(options
				(clearance outline)
				(anchor circle)
			)
			(primitives
				(gr_poly
					(pts
						(arc
							(start -0.0508 0.4064)
							(mid -0.194484 0.346884)
							(end -0.254 0.2032)
						)
						(arc
							(start -0.254 -0.2032)
							(mid -0.194484 -0.346884)
							(end -0.0508 -0.4064)
						)
						(arc
							(start 0.0508 -0.4064)
							(mid 0.194484 -0.346884)
							(end 0.254 -0.2032)
						)
						(arc
							(start 0.254 0.2032)
							(mid 0.194484 0.346884)
							(end 0.0508 0.4064)
						)
					)
					(width 0)
					(fill yes)
				)
			)
		)
		(pad "E" smd custom
			(at 0.508 0.6604 180)
			(size 0.127 0.127)
			(layers "F.Cu" "F.Mask" "F.Paste")
			(net "GND")
			(options
				(clearance outline)
				(anchor circle)
			)
			(primitives
				(gr_poly
					(pts
						(arc
							(start -0.0508 0.4064)
							(mid -0.194484 0.346884)
							(end -0.254 0.2032)
						)
						(arc
							(start -0.254 -0.2032)
							(mid -0.194484 -0.346884)
							(end -0.0508 -0.4064)
						)
						(arc
							(start 0.0508 -0.4064)
							(mid 0.194484 -0.346884)
							(end 0.254 -0.2032)
						)
						(arc
							(start 0.254 0.2032)
							(mid 0.194484 0.346884)
							(end 0.0508 0.4064)
						)
					)
					(width 0)
					(fill yes)
				)
			)
		)
	)
	(footprint ""
		(layer "F.Cu")
		(at 113.284 -71.12 180)
		(property "Reference" "R234"
			(at 0 0 180)
			(layer "F.SilkS")
			(hide yes)
			(effects
				(font
					(size 1.27 1.27)
				)
			)
		)
		(property "Value" "4K7R2F-GP"
			(at 0.064008 -3.993896 180)
			(unlocked yes)
			(layer "F.Fab")
			(hide yes)
			(effects
				(font
					(size 1.016 1.016)
					(thickness 0.1524)
				)
			)
		)
		(property "Device Type" "R402H16"
			(at 0.064008 -5.517896 180)
			(unlocked yes)
			(layer "F.Fab")
			(hide yes)
			(effects
				(font
					(size 1.016 1.016)
					(thickness 0.1524)
				)
			)
		)
		(duplicate_pad_numbers_are_jumpers no)
		(fp_rect
			(start -0.381 0.8382)
			(end 0.381 -0.8382)
			(stroke
				(width 0)
				(type default)
			)
			(fill no)
			(layer "F.CrtYd")
		)
		(fp_rect
			(start -0.381 0.8382)
			(end 0.381 -0.8382)
			(stroke
				(width 0)
				(type default)
			)
			(fill no)
			(layer "F.Fab")
		)
		(pad "1" smd custom
			(at 0 -0.4318 180)
			(size 0.127 0.127)
			(layers "F.Cu" "F.Mask" "F.Paste")
			(net "P3V3_STBY")
			(options
				(clearance outline)
				(anchor circle)
			)
			(primitives
				(gr_poly
					(pts
						(arc
							(start -0.2032 -0.2794)
							(mid -0.239121 -0.264521)
							(end -0.254 -0.2286)
						)
						(arc
							(start -0.254 0.2286)
							(mid -0.239121 0.264521)
							(end -0.2032 0.2794)
						)
						(arc
							(start 0.2032 0.2794)
							(mid 0.239121 0.264521)
							(end 0.254 0.2286)
						)
						(arc
							(start 0.254 -0.2286)
							(mid 0.239121 -0.264521)
							(end 0.2032 -0.2794)
						)
					)
					(width 0)
					(fill yes)
				)
			)
		)
		(pad "2" smd custom
			(at 0 0.4318 180)
			(size 0.127 0.127)
			(layers "F.Cu" "F.Mask" "F.Paste")
			(net "CHA_1_SA0")
			(options
				(clearance outline)
				(anchor circle)
			)
			(primitives
				(gr_poly
					(pts
						(arc
							(start -0.2032 -0.2794)
							(mid -0.239121 -0.264521)
							(end -0.254 -0.2286)
						)
						(arc
							(start -0.254 0.2286)
							(mid -0.239121 0.264521)
							(end -0.2032 0.2794)
						)
						(arc
							(start 0.2032 0.2794)
							(mid 0.239121 0.264521)
							(end 0.254 0.2286)
						)
						(arc
							(start 0.254 -0.2286)
							(mid 0.239121 -0.264521)
							(end 0.2032 -0.2794)
						)
					)
					(width 0)
					(fill yes)
				)
			)
		)
	)
	(footprint ""
		(layer "F.Cu")
		(at 9.525 -32.004 180)
		(property "Reference" "PR206"
			(at 0 0 180)
			(layer "F.SilkS")
			(hide yes)
			(effects
				(font
					(size 1.27 1.27)
				)
			)
		)
		(property "Value" "866KR2F-GP"
			(at 1.7907 -1.1176 180)
			(unlocked yes)
			(layer "F.Fab")
			(hide yes)
			(effects
				(font
					(size 1.016 1.016)
					(thickness 0.1524)
				)
			)
		)
		(property "Device Type" "R402H16"
			(at 1.7907 -2.6416 180)
			(unlocked yes)
			(layer "F.Fab")
			(hide yes)
			(effects
				(font
					(size 1.016 1.016)
					(thickness 0.1524)
				)
			)
		)
		(duplicate_pad_numbers_are_jumpers no)
		(fp_rect
			(start -0.381 0.8382)
			(end 0.381 -0.8382)
			(stroke
				(width 0)
				(type default)
			)
			(fill no)
			(layer "F.CrtYd")
		)
		(fp_rect
			(start -0.381 0.8382)
			(end 0.381 -0.8382)
			(stroke
				(width 0)
				(type default)
			)
			(fill no)
			(layer "F.Fab")
		)
		(pad "1" smd custom
			(at 0 -0.4318 180)
			(size 0.127 0.127)
			(layers "F.Cu" "F.Mask" "F.Paste")
			(net "P3V3_STBY_VREG")
			(options
				(clearance outline)
				(anchor circle)
			)
			(primitives
				(gr_poly
					(pts
						(arc
							(start -0.2032 -0.2794)
							(mid -0.239121 -0.264521)
							(end -0.254 -0.2286)
						)
						(arc
							(start -0.254 0.2286)
							(mid -0.239121 0.264521)
							(end -0.2032 0.2794)
						)
						(arc
							(start 0.2032 0.2794)
							(mid 0.239121 0.264521)
							(end 0.254 0.2286)
						)
						(arc
							(start 0.254 -0.2286)
							(mid 0.239121 -0.264521)
							(end 0.2032 -0.2794)
						)
					)
					(width 0)
					(fill yes)
				)
			)
		)
		(pad "2" smd custom
			(at 0 0.4318 180)
			(size 0.127 0.127)
			(layers "F.Cu" "F.Mask" "F.Paste")
			(net "P3V3_STBY_RF")
			(options
				(clearance outline)
				(anchor circle)
			)
			(primitives
				(gr_poly
					(pts
						(arc
							(start -0.2032 -0.2794)
							(mid -0.239121 -0.264521)
							(end -0.254 -0.2286)
						)
						(arc
							(start -0.254 0.2286)
							(mid -0.239121 0.264521)
							(end -0.2032 0.2794)
						)
						(arc
							(start 0.2032 0.2794)
							(mid 0.239121 0.264521)
							(end 0.254 0.2286)
						)
						(arc
							(start 0.254 -0.2286)
							(mid 0.239121 -0.264521)
							(end 0.2032 -0.2794)
						)
					)
					(width 0)
					(fill yes)
				)
			)
		)
	)
	(footprint ""
		(layer "F.Cu")
		(at 128.143 -35.306 -90)
		(property "Reference" "R28"
			(at 0 0 270)
			(layer "F.SilkS")
			(hide yes)
			(effects
				(font
					(size 1.27 1.27)
				)
			)
		)
		(property "Value" "33R2F-3-GP"
			(at 0.064008 -3.993896 270)
			(unlocked yes)
			(layer "F.Fab")
			(hide yes)
			(effects
				(font
					(size 1.016 1.016)
					(thickness 0.1524)
				)
			)
		)
		(property "Device Type" "R402H16"
			(at 0.064008 -5.517896 270)
			(unlocked yes)
			(layer "F.Fab")
			(hide yes)
			(effects
				(font
					(size 1.016 1.016)
					(thickness 0.1524)
				)
			)
		)
		(duplicate_pad_numbers_are_jumpers no)
		(fp_rect
			(start -0.381 0.8382)
			(end 0.381 -0.8382)
			(stroke
				(width 0)
				(type default)
			)
			(fill no)
			(layer "F.CrtYd")
		)
		(fp_rect
			(start -0.381 0.8382)
			(end 0.381 -0.8382)
			(stroke
				(width 0)
				(type default)
			)
			(fill no)
			(layer "F.Fab")
		)
		(pad "1" smd custom
			(at 0 -0.4318 270)
			(size 0.127 0.127)
			(layers "F.Cu" "F.Mask" "F.Paste")
			(net "LPC_AD_0")
			(options
				(clearance outline)
				(anchor circle)
			)
			(primitives
				(gr_poly
					(pts
						(arc
							(start -0.2032 -0.2794)
							(mid -0.239121 -0.264521)
							(end -0.254 -0.2286)
						)
						(arc
							(start -0.254 0.2286)
							(mid -0.239121 0.264521)
							(end -0.2032 0.2794)
						)
						(arc
							(start 0.2032 0.2794)
							(mid 0.239121 0.264521)
							(end 0.254 0.2286)
						)
						(arc
							(start 0.254 -0.2286)
							(mid 0.239121 -0.264521)
							(end 0.2032 -0.2794)
						)
					)
					(width 0)
					(fill yes)
				)
			)
		)
		(pad "2" smd custom
			(at 0 0.4318 270)
			(size 0.127 0.127)
			(layers "F.Cu" "F.Mask" "F.Paste")
			(net "LPC_CPU_LAD0")
			(options
				(clearance outline)
				(anchor circle)
			)
			(primitives
				(gr_poly
					(pts
						(arc
							(start -0.2032 -0.2794)
							(mid -0.239121 -0.264521)
							(end -0.254 -0.2286)
						)
						(arc
							(start -0.254 0.2286)
							(mid -0.239121 0.264521)
							(end -0.2032 0.2794)
						)
						(arc
							(start 0.2032 0.2794)
							(mid 0.239121 0.264521)
							(end 0.254 0.2286)
						)
						(arc
							(start 0.254 -0.2286)
							(mid 0.239121 -0.264521)
							(end 0.2032 -0.2794)
						)
					)
					(width 0)
					(fill yes)
				)
			)
		)
	)
	(footprint ""
		(layer "F.Cu")
		(at 64.008 -52.578 -90)
		(property "Reference" "PR163"
			(at 0 0 270)
			(layer "F.SilkS")
			(hide yes)
			(effects
				(font
					(size 1.27 1.27)
				)
			)
		)
		(property "Value" "0R3J-6-GP"
			(at -0.0254 -2.0193 270)
			(unlocked yes)
			(layer "F.Fab")
			(hide yes)
			(effects
				(font
					(size 1.016 1.016)
					(thickness 0.1524)
				)
			)
		)
		(property "Device Type" "R603H22"
			(at -0.0254 -3.5433 270)
			(unlocked yes)
			(layer "F.Fab")
			(hide yes)
			(effects
				(font
					(size 1.016 1.016)
					(thickness 0.1524)
				)
			)
		)
		(duplicate_pad_numbers_are_jumpers no)
		(fp_line
			(start -0.2032 0)
			(end -0.4191 0)
			(stroke
				(width 0.2032)
				(type default)
			)
			(layer "F.SilkS")
		)
		(fp_line
			(start 0.4318 0)
			(end 0.2032 0)
			(stroke
				(width 0.2032)
				(type default)
			)
			(layer "F.SilkS")
		)
		(fp_rect
			(start -0.635 1.1811)
			(end 0.635 -1.1811)
			(stroke
				(width 0)
				(type default)
			)
			(fill no)
			(layer "F.CrtYd")
		)
		(fp_rect
			(start -0.635 1.1811)
			(end 0.635 -1.1811)
			(stroke
				(width 0)
				(type default)
			)
			(fill no)
			(layer "F.Fab")
		)
		(pad "1" smd custom
			(at 0 -0.6604 270)
			(size 0.19685 0.19685)
			(layers "F.Cu" "F.Mask" "F.Paste")
			(net "P1V0_STBY")
			(options
				(clearance outline)
				(anchor circle)
			)
			(primitives
				(gr_poly
					(pts
						(arc
							(start 0.508 -0.2921)
							(mid 0.478242 -0.363942)
							(end 0.4064 -0.3937)
						)
						(arc
							(start -0.4064 -0.3937)
							(mid -0.478242 -0.363942)
							(end -0.508 -0.2921)
						)
						(arc
							(start -0.508 0.2921)
							(mid -0.478242 0.363942)
							(end -0.4064 0.3937)
						)
						(arc
							(start 0.4064 0.3937)
							(mid 0.478242 0.363942)
							(end 0.508 0.2921)
						)
					)
					(width 0)
					(fill yes)
				)
			)
		)
		(pad "2" smd custom
			(at 0 0.6604 270)
			(size 0.19685 0.19685)
			(layers "F.Cu" "F.Mask" "F.Paste")
			(net "P1V0_STBY_VOUT")
			(options
				(clearance outline)
				(anchor circle)
			)
			(primitives
				(gr_poly
					(pts
						(arc
							(start 0.508 -0.2921)
							(mid 0.478242 -0.363942)
							(end 0.4064 -0.3937)
						)
						(arc
							(start -0.4064 -0.3937)
							(mid -0.478242 -0.363942)
							(end -0.508 -0.2921)
						)
						(arc
							(start -0.508 0.2921)
							(mid -0.478242 0.363942)
							(end -0.4064 0.3937)
						)
						(arc
							(start 0.4064 0.3937)
							(mid 0.478242 0.363942)
							(end 0.508 0.2921)
						)
					)
					(width 0)
					(fill yes)
				)
			)
		)
	)
	(footprint ""
		(layer "F.Cu")
		(at 155.575 -52.451)
		(property "Reference" "R286"
			(at 0 0 0)
			(layer "F.SilkS")
			(hide yes)
			(effects
				(font
					(size 1.27 1.27)
				)
			)
		)
		(property "Value" "33R2F-3-GP"
			(at 1.7907 -1.1176 0)
			(unlocked yes)
			(layer "F.Fab")
			(hide yes)
			(effects
				(font
					(size 1.016 1.016)
					(thickness 0.1524)
				)
			)
		)
		(property "Device Type" "R402H16"
			(at 1.7907 -2.6416 0)
			(unlocked yes)
			(layer "F.Fab")
			(hide yes)
			(effects
				(font
					(size 1.016 1.016)
					(thickness 0.1524)
				)
			)
		)
		(duplicate_pad_numbers_are_jumpers no)
		(fp_rect
			(start -0.381 0.8382)
			(end 0.381 -0.8382)
			(stroke
				(width 0)
				(type default)
			)
			(fill no)
			(layer "F.CrtYd")
		)
		(fp_rect
			(start -0.381 0.8382)
			(end 0.381 -0.8382)
			(stroke
				(width 0)
				(type default)
			)
			(fill no)
			(layer "F.Fab")
		)
		(pad "1" smd custom
			(at 0 -0.4318)
			(size 0.127 0.127)
			(layers "F.Cu" "F.Mask" "F.Paste")
			(net "C_R_DCLK")
			(options
				(clearance outline)
				(anchor circle)
			)
			(primitives
				(gr_poly
					(pts
						(arc
							(start -0.2032 -0.2794)
							(mid -0.239121 -0.264521)
							(end -0.254 -0.2286)
						)
						(arc
							(start -0.254 0.2286)
							(mid -0.239121 0.264521)
							(end -0.2032 0.2794)
						)
						(arc
							(start 0.2032 0.2794)
							(mid 0.239121 0.264521)
							(end 0.254 0.2286)
						)
						(arc
							(start 0.254 -0.2286)
							(mid 0.239121 -0.264521)
							(end 0.2032 -0.2794)
						)
					)
					(width 0)
					(fill yes)
				)
			)
		)
		(pad "2" smd custom
			(at 0 0.4318)
			(size 0.127 0.127)
			(layers "F.Cu" "F.Mask" "F.Paste")
			(net "C_DCLK")
			(options
				(clearance outline)
				(anchor circle)
			)
			(primitives
				(gr_poly
					(pts
						(arc
							(start -0.2032 -0.2794)
							(mid -0.239121 -0.264521)
							(end -0.254 -0.2286)
						)
						(arc
							(start -0.254 0.2286)
							(mid -0.239121 0.264521)
							(end -0.2032 0.2794)
						)
						(arc
							(start 0.2032 0.2794)
							(mid 0.239121 0.264521)
							(end 0.254 0.2286)
						)
						(arc
							(start 0.254 -0.2286)
							(mid 0.239121 -0.264521)
							(end 0.2032 -0.2794)
						)
					)
					(width 0)
					(fill yes)
				)
			)
		)
	)
	(footprint ""
		(layer "F.Cu")
		(at 82.423 -63.754 -90)
		(property "Reference" "R133"
			(at 0 0 270)
			(layer "F.SilkS")
			(hide yes)
			(effects
				(font
					(size 1.27 1.27)
				)
			)
		)
		(property "Value" "0R2J-2-GP"
			(at 0.064008 -3.993896 270)
			(unlocked yes)
			(layer "F.Fab")
			(hide yes)
			(effects
				(font
					(size 1.016 1.016)
					(thickness 0.1524)
				)
			)
		)
		(property "Device Type" "R402H16"
			(at 0.064008 -5.517896 270)
			(unlocked yes)
			(layer "F.Fab")
			(hide yes)
			(effects
				(font
					(size 1.016 1.016)
					(thickness 0.1524)
				)
			)
		)
		(duplicate_pad_numbers_are_jumpers no)
		(fp_rect
			(start -0.381 0.8382)
			(end 0.381 -0.8382)
			(stroke
				(width 0)
				(type default)
			)
			(fill no)
			(layer "F.CrtYd")
		)
		(fp_rect
			(start -0.381 0.8382)
			(end 0.381 -0.8382)
			(stroke
				(width 0)
				(type default)
			)
			(fill no)
			(layer "F.Fab")
		)
		(pad "1" smd custom
			(at 0 -0.4318 270)
			(size 0.127 0.127)
			(layers "F.Cu" "F.Mask" "F.Paste")
			(net "PV_VDDR")
			(options
				(clearance outline)
				(anchor circle)
			)
			(primitives
				(gr_poly
					(pts
						(arc
							(start -0.2032 -0.2794)
							(mid -0.239121 -0.264521)
							(end -0.254 -0.2286)
						)
						(arc
							(start -0.254 0.2286)
							(mid -0.239121 0.264521)
							(end -0.2032 0.2794)
						)
						(arc
							(start 0.2032 0.2794)
							(mid 0.239121 0.264521)
							(end 0.254 0.2286)
						)
						(arc
							(start 0.254 -0.2286)
							(mid 0.239121 -0.264521)
							(end 0.2032 -0.2794)
						)
					)
					(width 0)
					(fill yes)
				)
			)
		)
		(pad "2" smd custom
			(at 0 0.4318 270)
			(size 0.127 0.127)
			(layers "F.Cu" "F.Mask" "F.Paste")
			(net "PV_VDDR_SENSE")
			(options
				(clearance outline)
				(anchor circle)
			)
			(primitives
				(gr_poly
					(pts
						(arc
							(start -0.2032 -0.2794)
							(mid -0.239121 -0.264521)
							(end -0.254 -0.2286)
						)
						(arc
							(start -0.254 0.2286)
							(mid -0.239121 0.264521)
							(end -0.2032 0.2794)
						)
						(arc
							(start 0.2032 0.2794)
							(mid 0.239121 0.264521)
							(end 0.254 0.2286)
						)
						(arc
							(start 0.254 -0.2286)
							(mid 0.239121 -0.264521)
							(end 0.2032 -0.2794)
						)
					)
					(width 0)
					(fill yes)
				)
			)
		)
	)
	(footprint ""
		(layer "F.Cu")
		(at 81.788 -65.913 180)
		(property "Reference" "R187"
			(at 0 0 180)
			(layer "F.SilkS")
			(hide yes)
			(effects
				(font
					(size 1.27 1.27)
				)
			)
		)
		(property "Value" "4K7R2F-GP"
			(at 0.064008 -3.993896 180)
			(unlocked yes)
			(layer "F.Fab")
			(hide yes)
			(effects
				(font
					(size 1.016 1.016)
					(thickness 0.1524)
				)
			)
		)
		(property "Device Type" "R402H16"
			(at 0.064008 -5.517896 180)
			(unlocked yes)
			(layer "F.Fab")
			(hide yes)
			(effects
				(font
					(size 1.016 1.016)
					(thickness 0.1524)
				)
			)
		)
		(duplicate_pad_numbers_are_jumpers no)
		(fp_rect
			(start -0.381 0.8382)
			(end 0.381 -0.8382)
			(stroke
				(width 0)
				(type default)
			)
			(fill no)
			(layer "F.CrtYd")
		)
		(fp_rect
			(start -0.381 0.8382)
			(end 0.381 -0.8382)
			(stroke
				(width 0)
				(type default)
			)
			(fill no)
			(layer "F.Fab")
		)
		(pad "1" smd custom
			(at 0 -0.4318 180)
			(size 0.127 0.127)
			(layers "F.Cu" "F.Mask" "F.Paste")
			(net "VOL1_SEN_ADDR0")
			(options
				(clearance outline)
				(anchor circle)
			)
			(primitives
				(gr_poly
					(pts
						(arc
							(start -0.2032 -0.2794)
							(mid -0.239121 -0.264521)
							(end -0.254 -0.2286)
						)
						(arc
							(start -0.254 0.2286)
							(mid -0.239121 0.264521)
							(end -0.2032 0.2794)
						)
						(arc
							(start 0.2032 0.2794)
							(mid 0.239121 0.264521)
							(end 0.254 0.2286)
						)
						(arc
							(start 0.254 -0.2286)
							(mid 0.239121 -0.264521)
							(end 0.2032 -0.2794)
						)
					)
					(width 0)
					(fill yes)
				)
			)
		)
		(pad "2" smd custom
			(at 0 0.4318 180)
			(size 0.127 0.127)
			(layers "F.Cu" "F.Mask" "F.Paste")
			(net "GND")
			(options
				(clearance outline)
				(anchor circle)
			)
			(primitives
				(gr_poly
					(pts
						(arc
							(start -0.2032 -0.2794)
							(mid -0.239121 -0.264521)
							(end -0.254 -0.2286)
						)
						(arc
							(start -0.254 0.2286)
							(mid -0.239121 0.264521)
							(end -0.2032 0.2794)
						)
						(arc
							(start 0.2032 0.2794)
							(mid 0.239121 0.264521)
							(end 0.254 0.2286)
						)
						(arc
							(start 0.254 -0.2286)
							(mid 0.239121 -0.264521)
							(end 0.2032 -0.2794)
						)
					)
					(width 0)
					(fill yes)
				)
			)
		)
	)
	(footprint ""
		(layer "F.Cu")
		(at 191.643 -39.878 180)
		(property "Reference" "PR125"
			(at 0 0 180)
			(layer "F.SilkS")
			(hide yes)
			(effects
				(font
					(size 1.27 1.27)
				)
			)
		)
		(property "Value" "6K04R2F-GP"
			(at 1.7907 -1.1176 180)
			(unlocked yes)
			(layer "F.Fab")
			(hide yes)
			(effects
				(font
					(size 1.016 1.016)
					(thickness 0.1524)
				)
			)
		)
		(property "Device Type" "R402H16"
			(at 1.7907 -2.6416 180)
			(unlocked yes)
			(layer "F.Fab")
			(hide yes)
			(effects
				(font
					(size 1.016 1.016)
					(thickness 0.1524)
				)
			)
		)
		(duplicate_pad_numbers_are_jumpers no)
		(fp_rect
			(start -0.381 0.8382)
			(end 0.381 -0.8382)
			(stroke
				(width 0)
				(type default)
			)
			(fill no)
			(layer "F.CrtYd")
		)
		(fp_rect
			(start -0.381 0.8382)
			(end 0.381 -0.8382)
			(stroke
				(width 0)
				(type default)
			)
			(fill no)
			(layer "F.Fab")
		)
		(pad "1" smd custom
			(at 0 -0.4318 180)
			(size 0.127 0.127)
			(layers "F.Cu" "F.Mask" "F.Paste")
			(net "VR_PVDDR_A_PROG2")
			(options
				(clearance outline)
				(anchor circle)
			)
			(primitives
				(gr_poly
					(pts
						(arc
							(start -0.2032 -0.2794)
							(mid -0.239121 -0.264521)
							(end -0.254 -0.2286)
						)
						(arc
							(start -0.254 0.2286)
							(mid -0.239121 0.264521)
							(end -0.2032 0.2794)
						)
						(arc
							(start 0.2032 0.2794)
							(mid 0.239121 0.264521)
							(end 0.254 0.2286)
						)
						(arc
							(start 0.254 -0.2286)
							(mid 0.239121 -0.264521)
							(end 0.2032 -0.2794)
						)
					)
					(width 0)
					(fill yes)
				)
			)
		)
		(pad "2" smd custom
			(at 0 0.4318 180)
			(size 0.127 0.127)
			(layers "F.Cu" "F.Mask" "F.Paste")
			(net "GND")
			(options
				(clearance outline)
				(anchor circle)
			)
			(primitives
				(gr_poly
					(pts
						(arc
							(start -0.2032 -0.2794)
							(mid -0.239121 -0.264521)
							(end -0.254 -0.2286)
						)
						(arc
							(start -0.254 0.2286)
							(mid -0.239121 0.264521)
							(end -0.2032 0.2794)
						)
						(arc
							(start 0.2032 0.2794)
							(mid 0.239121 0.264521)
							(end 0.254 0.2286)
						)
						(arc
							(start 0.254 -0.2286)
							(mid 0.239121 -0.264521)
							(end 0.2032 -0.2794)
						)
					)
					(width 0)
					(fill yes)
				)
			)
		)
	)
	(footprint ""
		(layer "F.Cu")
		(at 204.7748 -24.638 90)
		(property "Reference" "TP16"
			(at 0 0 90)
			(layer "F.SilkS")
			(hide yes)
			(effects
				(font
					(size 1.27 1.27)
				)
			)
		)
		(property "Value" "TPAD32-GP"
			(at 0 -3.166364 90)
			(unlocked yes)
			(layer "F.Fab")
			(hide yes)
			(effects
				(font
					(size 1.016 1.016)
					(thickness 0.1524)
				)
			)
		)
		(property "Device Type" "TPAD32"
			(at 0 -4.690618 90)
			(unlocked yes)
			(layer "F.Fab")
			(hide yes)
			(effects
				(font
					(size 1.016 1.016)
					(thickness 0.1524)
				)
			)
		)
		(duplicate_pad_numbers_are_jumpers no)
		(fp_poly
			(pts
				(arc
					(start 0 0.7112)
					(mid 0 -0.7112)
					(end 0 0.7112)
				)
			)
			(stroke
				(width 0)
				(type default)
			)
			(fill no)
			(layer "F.CrtYd")
		)
		(fp_poly
			(pts
				(arc
					(start 0 0.7112)
					(mid 0 -0.7112)
					(end 0 0.7112)
				)
			)
			(stroke
				(width 0)
				(type default)
			)
			(fill no)
			(layer "F.Fab")
		)
		(pad "1" smd circle
			(at 0 0 90)
			(size 0.8128 0.8128)
			(layers "F.Cu" "F.Mask" "F.Paste")
			(net "JTAG_CPU_PLD_TDO")
		)
	)
	(footprint ""
		(layer "F.Cu")
		(at 61.9252 -51.8922)
		(property "Reference" "PC113"
			(at 0 0 0)
			(layer "F.SilkS")
			(hide yes)
			(effects
				(font
					(size 1.27 1.27)
				)
			)
		)
		(property "Value" "SC22U6D3V5MX-2GP"
			(at 0 -4.9022 0)
			(unlocked yes)
			(layer "F.Fab")
			(hide yes)
			(effects
				(font
					(size 1.016 1.016)
					(thickness 0.1524)
				)
			)
		)
		(property "Device Type" "C805H58"
			(at 0 -6.8072 0)
			(unlocked yes)
			(layer "F.Fab")
			(hide yes)
			(effects
				(font
					(size 1.016 1.016)
					(thickness 0.1524)
				)
			)
		)
		(duplicate_pad_numbers_are_jumpers no)
		(fp_line
			(start 0.6096 0)
			(end -0.6096 0)
			(stroke
				(width 0.3048)
				(type default)
			)
			(layer "F.SilkS")
		)
		(fp_poly
			(pts
				(xy -0.9017 1.4351) (xy 0.9017 1.4351) (xy 0.9017 -1.4351) (xy -0.9017 -1.4351)
			)
			(stroke
				(width 0)
				(type default)
			)
			(fill no)
			(layer "F.CrtYd")
		)
		(fp_poly
			(pts
				(xy 0.9017 1.4351) (xy 0.9017 -1.4351) (xy -0.9017 -1.4351) (xy -0.9017 1.4351)
			)
			(stroke
				(width 0)
				(type default)
			)
			(fill no)
			(layer "F.Fab")
		)
		(pad "1" smd rect
			(at 0 -0.8382)
			(size 1.5494 0.9398)
			(layers "F.Cu" "F.Mask" "F.Paste")
			(net "P1V0_STBY_VOUT")
		)
		(pad "2" smd rect
			(at 0 0.8382)
			(size 1.5494 0.9398)
			(layers "F.Cu" "F.Mask" "F.Paste")
			(net "GND")
		)
	)
	(footprint ""
		(layer "F.Cu")
		(at 22.7584 -50.5206)
		(property "Reference" "PR82"
			(at 0 0 0)
			(layer "F.SilkS")
			(hide yes)
			(effects
				(font
					(size 1.27 1.27)
				)
			)
		)
		(property "Value" "0R2J-2-GP"
			(at 1.7907 -1.1176 0)
			(unlocked yes)
			(layer "F.Fab")
			(hide yes)
			(effects
				(font
					(size 1.016 1.016)
					(thickness 0.1524)
				)
			)
		)
		(property "Device Type" "R402H16"
			(at 1.7907 -2.6416 0)
			(unlocked yes)
			(layer "F.Fab")
			(hide yes)
			(effects
				(font
					(size 1.016 1.016)
					(thickness 0.1524)
				)
			)
		)
		(duplicate_pad_numbers_are_jumpers no)
		(fp_rect
			(start -0.381 0.8382)
			(end 0.381 -0.8382)
			(stroke
				(width 0)
				(type default)
			)
			(fill no)
			(layer "F.CrtYd")
		)
		(fp_rect
			(start -0.381 0.8382)
			(end 0.381 -0.8382)
			(stroke
				(width 0)
				(type default)
			)
			(fill no)
			(layer "F.Fab")
		)
		(pad "1" smd custom
			(at 0 -0.4318)
			(size 0.127 0.127)
			(layers "F.Cu" "F.Mask" "F.Paste")
			(net "VR_PVCCP_VSEN")
			(options
				(clearance outline)
				(anchor circle)
			)
			(primitives
				(gr_poly
					(pts
						(arc
							(start -0.2032 -0.2794)
							(mid -0.239121 -0.264521)
							(end -0.254 -0.2286)
						)
						(arc
							(start -0.254 0.2286)
							(mid -0.239121 0.264521)
							(end -0.2032 0.2794)
						)
						(arc
							(start 0.2032 0.2794)
							(mid 0.239121 0.264521)
							(end 0.254 0.2286)
						)
						(arc
							(start 0.254 -0.2286)
							(mid 0.239121 -0.264521)
							(end 0.2032 -0.2794)
						)
					)
					(width 0)
					(fill yes)
				)
			)
		)
		(pad "2" smd custom
			(at 0 0.4318)
			(size 0.127 0.127)
			(layers "F.Cu" "F.Mask" "F.Paste")
			(net "VR_PVCCP_VSEN_R")
			(options
				(clearance outline)
				(anchor circle)
			)
			(primitives
				(gr_poly
					(pts
						(arc
							(start -0.2032 -0.2794)
							(mid -0.239121 -0.264521)
							(end -0.254 -0.2286)
						)
						(arc
							(start -0.254 0.2286)
							(mid -0.239121 0.264521)
							(end -0.2032 0.2794)
						)
						(arc
							(start 0.2032 0.2794)
							(mid 0.239121 0.264521)
							(end 0.254 0.2286)
						)
						(arc
							(start 0.254 -0.2286)
							(mid 0.239121 -0.264521)
							(end 0.2032 -0.2794)
						)
					)
					(width 0)
					(fill yes)
				)
			)
		)
	)
	(footprint ""
		(layer "F.Cu")
		(at 33.1724 -33.0454 180)
		(property "Reference" "R472"
			(at 0 0 180)
			(layer "F.SilkS")
			(hide yes)
			(effects
				(font
					(size 1.27 1.27)
				)
			)
		)
		(property "Value" "0R2J-2-GP"
			(at 1.7907 -1.1176 180)
			(unlocked yes)
			(layer "F.Fab")
			(hide yes)
			(effects
				(font
					(size 1.016 1.016)
					(thickness 0.1524)
				)
			)
		)
		(property "Device Type" "R402H16"
			(at 1.7907 -2.6416 180)
			(unlocked yes)
			(layer "F.Fab")
			(hide yes)
			(effects
				(font
					(size 1.016 1.016)
					(thickness 0.1524)
				)
			)
		)
		(duplicate_pad_numbers_are_jumpers no)
		(fp_rect
			(start -0.381 0.8382)
			(end 0.381 -0.8382)
			(stroke
				(width 0)
				(type default)
			)
			(fill no)
			(layer "F.CrtYd")
		)
		(fp_rect
			(start -0.381 0.8382)
			(end 0.381 -0.8382)
			(stroke
				(width 0)
				(type default)
			)
			(fill no)
			(layer "F.Fab")
		)
		(pad "1" smd custom
			(at 0 -0.4318 180)
			(size 0.127 0.127)
			(layers "F.Cu" "F.Mask" "F.Paste")
			(net "XDP_CPU_R_TDO")
			(options
				(clearance outline)
				(anchor circle)
			)
			(primitives
				(gr_poly
					(pts
						(arc
							(start -0.2032 -0.2794)
							(mid -0.239121 -0.264521)
							(end -0.254 -0.2286)
						)
						(arc
							(start -0.254 0.2286)
							(mid -0.239121 0.264521)
							(end -0.2032 0.2794)
						)
						(arc
							(start 0.2032 0.2794)
							(mid 0.239121 0.264521)
							(end 0.254 0.2286)
						)
						(arc
							(start 0.254 -0.2286)
							(mid 0.239121 -0.264521)
							(end 0.2032 -0.2794)
						)
					)
					(width 0)
					(fill yes)
				)
			)
		)
		(pad "2" smd custom
			(at 0 0.4318 180)
			(size 0.127 0.127)
			(layers "F.Cu" "F.Mask" "F.Paste")
			(net "XDP_SOC_CPU_TDO")
			(options
				(clearance outline)
				(anchor circle)
			)
			(primitives
				(gr_poly
					(pts
						(arc
							(start -0.2032 -0.2794)
							(mid -0.239121 -0.264521)
							(end -0.254 -0.2286)
						)
						(arc
							(start -0.254 0.2286)
							(mid -0.239121 0.264521)
							(end -0.2032 0.2794)
						)
						(arc
							(start 0.2032 0.2794)
							(mid 0.239121 0.264521)
							(end 0.254 0.2286)
						)
						(arc
							(start 0.254 -0.2286)
							(mid 0.239121 -0.264521)
							(end 0.2032 -0.2794)
						)
					)
					(width 0)
					(fill yes)
				)
			)
		)
	)
	(footprint ""
		(layer "F.Cu")
		(at 16.3576 -63.9064 180)
		(property "Reference" "PR34"
			(at 0 0 180)
			(layer "F.SilkS")
			(hide yes)
			(effects
				(font
					(size 1.27 1.27)
				)
			)
		)
		(property "Value" "5K9R2F-GP"
			(at 1.7907 -1.1176 180)
			(unlocked yes)
			(layer "F.Fab")
			(hide yes)
			(effects
				(font
					(size 1.016 1.016)
					(thickness 0.1524)
				)
			)
		)
		(property "Device Type" "R402H16"
			(at 1.7907 -2.6416 180)
			(unlocked yes)
			(layer "F.Fab")
			(hide yes)
			(effects
				(font
					(size 1.016 1.016)
					(thickness 0.1524)
				)
			)
		)
		(duplicate_pad_numbers_are_jumpers no)
		(fp_rect
			(start -0.381 0.8382)
			(end 0.381 -0.8382)
			(stroke
				(width 0)
				(type default)
			)
			(fill no)
			(layer "F.CrtYd")
		)
		(fp_rect
			(start -0.381 0.8382)
			(end 0.381 -0.8382)
			(stroke
				(width 0)
				(type default)
			)
			(fill no)
			(layer "F.Fab")
		)
		(pad "1" smd custom
			(at 0 -0.4318 180)
			(size 0.127 0.127)
			(layers "F.Cu" "F.Mask" "F.Paste")
			(net "VR_PVNN_IMON")
			(options
				(clearance outline)
				(anchor circle)
			)
			(primitives
				(gr_poly
					(pts
						(arc
							(start -0.2032 -0.2794)
							(mid -0.239121 -0.264521)
							(end -0.254 -0.2286)
						)
						(arc
							(start -0.254 0.2286)
							(mid -0.239121 0.264521)
							(end -0.2032 0.2794)
						)
						(arc
							(start 0.2032 0.2794)
							(mid 0.239121 0.264521)
							(end 0.254 0.2286)
						)
						(arc
							(start 0.254 -0.2286)
							(mid 0.239121 -0.264521)
							(end 0.2032 -0.2794)
						)
					)
					(width 0)
					(fill yes)
				)
			)
		)
		(pad "2" smd custom
			(at 0 0.4318 180)
			(size 0.127 0.127)
			(layers "F.Cu" "F.Mask" "F.Paste")
			(net "GND")
			(options
				(clearance outline)
				(anchor circle)
			)
			(primitives
				(gr_poly
					(pts
						(arc
							(start -0.2032 -0.2794)
							(mid -0.239121 -0.264521)
							(end -0.254 -0.2286)
						)
						(arc
							(start -0.254 0.2286)
							(mid -0.239121 0.264521)
							(end -0.2032 0.2794)
						)
						(arc
							(start 0.2032 0.2794)
							(mid 0.239121 0.264521)
							(end 0.254 0.2286)
						)
						(arc
							(start 0.254 -0.2286)
							(mid 0.239121 -0.264521)
							(end 0.2032 -0.2794)
						)
					)
					(width 0)
					(fill yes)
				)
			)
		)
	)
	(footprint ""
		(layer "F.Cu")
		(at 198.12 -6.35 -90)
		(property "Reference" "R388"
			(at 0 0 270)
			(layer "F.SilkS")
			(hide yes)
			(effects
				(font
					(size 1.27 1.27)
				)
			)
		)
		(property "Value" "4K7R2F-GP"
			(at 0.064008 -3.993896 270)
			(unlocked yes)
			(layer "F.Fab")
			(hide yes)
			(effects
				(font
					(size 1.016 1.016)
					(thickness 0.1524)
				)
			)
		)
		(property "Device Type" "R402H16"
			(at 0.064008 -5.517896 270)
			(unlocked yes)
			(layer "F.Fab")
			(hide yes)
			(effects
				(font
					(size 1.016 1.016)
					(thickness 0.1524)
				)
			)
		)
		(duplicate_pad_numbers_are_jumpers no)
		(fp_rect
			(start -0.381 0.8382)
			(end 0.381 -0.8382)
			(stroke
				(width 0)
				(type default)
			)
			(fill no)
			(layer "F.CrtYd")
		)
		(fp_rect
			(start -0.381 0.8382)
			(end 0.381 -0.8382)
			(stroke
				(width 0)
				(type default)
			)
			(fill no)
			(layer "F.Fab")
		)
		(pad "1" smd custom
			(at 0 -0.4318 270)
			(size 0.127 0.127)
			(layers "F.Cu" "F.Mask" "F.Paste")
			(net "P3V3_STBY")
			(options
				(clearance outline)
				(anchor circle)
			)
			(primitives
				(gr_poly
					(pts
						(arc
							(start -0.2032 -0.2794)
							(mid -0.239121 -0.264521)
							(end -0.254 -0.2286)
						)
						(arc
							(start -0.254 0.2286)
							(mid -0.239121 0.264521)
							(end -0.2032 0.2794)
						)
						(arc
							(start 0.2032 0.2794)
							(mid 0.239121 0.264521)
							(end 0.254 0.2286)
						)
						(arc
							(start 0.254 -0.2286)
							(mid 0.239121 -0.264521)
							(end 0.2032 -0.2794)
						)
					)
					(width 0)
					(fill yes)
				)
			)
		)
		(pad "2" smd custom
			(at 0 0.4318 270)
			(size 0.127 0.127)
			(layers "F.Cu" "F.Mask" "F.Paste")
			(net "CHB_1_SA0")
			(options
				(clearance outline)
				(anchor circle)
			)
			(primitives
				(gr_poly
					(pts
						(arc
							(start -0.2032 -0.2794)
							(mid -0.239121 -0.264521)
							(end -0.254 -0.2286)
						)
						(arc
							(start -0.254 0.2286)
							(mid -0.239121 0.264521)
							(end -0.2032 0.2794)
						)
						(arc
							(start 0.2032 0.2794)
							(mid 0.239121 0.264521)
							(end 0.254 0.2286)
						)
						(arc
							(start 0.254 -0.2286)
							(mid 0.239121 -0.264521)
							(end 0.2032 -0.2794)
						)
					)
					(width 0)
					(fill yes)
				)
			)
		)
	)
	(footprint ""
		(layer "F.Cu")
		(at 74.041 -32.131 -90)
		(property "Reference" "R371"
			(at 0 0 270)
			(layer "F.SilkS")
			(hide yes)
			(effects
				(font
					(size 1.27 1.27)
				)
			)
		)
		(property "Value" "1KR2F-3-GP"
			(at 1.7907 -1.1176 270)
			(unlocked yes)
			(layer "F.Fab")
			(hide yes)
			(effects
				(font
					(size 1.016 1.016)
					(thickness 0.1524)
				)
			)
		)
		(property "Device Type" "R402H16"
			(at 1.7907 -2.6416 270)
			(unlocked yes)
			(layer "F.Fab")
			(hide yes)
			(effects
				(font
					(size 1.016 1.016)
					(thickness 0.1524)
				)
			)
		)
		(duplicate_pad_numbers_are_jumpers no)
		(fp_rect
			(start -0.381 0.8382)
			(end 0.381 -0.8382)
			(stroke
				(width 0)
				(type default)
			)
			(fill no)
			(layer "F.CrtYd")
		)
		(fp_rect
			(start -0.381 0.8382)
			(end 0.381 -0.8382)
			(stroke
				(width 0)
				(type default)
			)
			(fill no)
			(layer "F.Fab")
		)
		(pad "1" smd custom
			(at 0 -0.4318 270)
			(size 0.127 0.127)
			(layers "F.Cu" "F.Mask" "F.Paste")
			(net "GBE_WOL")
			(options
				(clearance outline)
				(anchor circle)
			)
			(primitives
				(gr_poly
					(pts
						(arc
							(start -0.2032 -0.2794)
							(mid -0.239121 -0.264521)
							(end -0.254 -0.2286)
						)
						(arc
							(start -0.254 0.2286)
							(mid -0.239121 0.264521)
							(end -0.2032 0.2794)
						)
						(arc
							(start 0.2032 0.2794)
							(mid 0.239121 0.264521)
							(end 0.254 0.2286)
						)
						(arc
							(start 0.254 -0.2286)
							(mid 0.239121 -0.264521)
							(end 0.2032 -0.2794)
						)
					)
					(width 0)
					(fill yes)
				)
			)
		)
		(pad "2" smd custom
			(at 0 0.4318 270)
			(size 0.127 0.127)
			(layers "F.Cu" "F.Mask" "F.Paste")
			(net "GND")
			(options
				(clearance outline)
				(anchor circle)
			)
			(primitives
				(gr_poly
					(pts
						(arc
							(start -0.2032 -0.2794)
							(mid -0.239121 -0.264521)
							(end -0.254 -0.2286)
						)
						(arc
							(start -0.254 0.2286)
							(mid -0.239121 0.264521)
							(end -0.2032 0.2794)
						)
						(arc
							(start 0.2032 0.2794)
							(mid 0.239121 0.264521)
							(end 0.254 0.2286)
						)
						(arc
							(start 0.254 -0.2286)
							(mid 0.239121 -0.264521)
							(end 0.2032 -0.2794)
						)
					)
					(width 0)
					(fill yes)
				)
			)
		)
	)
	(footprint ""
		(layer "F.Cu")
		(at 34.163 -68.326 90)
		(property "Reference" "PR19"
			(at 0 0 90)
			(layer "F.SilkS")
			(hide yes)
			(effects
				(font
					(size 1.27 1.27)
				)
			)
		)
		(property "Value" "10KR2F-2-GP"
			(at 1.7907 -1.1176 90)
			(unlocked yes)
			(layer "F.Fab")
			(hide yes)
			(effects
				(font
					(size 1.016 1.016)
					(thickness 0.1524)
				)
			)
		)
		(property "Device Type" "R402H16"
			(at 1.7907 -2.6416 90)
			(unlocked yes)
			(layer "F.Fab")
			(hide yes)
			(effects
				(font
					(size 1.016 1.016)
					(thickness 0.1524)
				)
			)
		)
		(duplicate_pad_numbers_are_jumpers no)
		(fp_rect
			(start -0.381 0.8382)
			(end 0.381 -0.8382)
			(stroke
				(width 0)
				(type default)
			)
			(fill no)
			(layer "F.CrtYd")
		)
		(fp_rect
			(start -0.381 0.8382)
			(end 0.381 -0.8382)
			(stroke
				(width 0)
				(type default)
			)
			(fill no)
			(layer "F.Fab")
		)
		(pad "1" smd custom
			(at 0 -0.4318 90)
			(size 0.127 0.127)
			(layers "F.Cu" "F.Mask" "F.Paste")
			(net "VR_PVNN_LH_R")
			(options
				(clearance outline)
				(anchor circle)
			)
			(primitives
				(gr_poly
					(pts
						(arc
							(start -0.2032 -0.2794)
							(mid -0.239121 -0.264521)
							(end -0.254 -0.2286)
						)
						(arc
							(start -0.254 0.2286)
							(mid -0.239121 0.264521)
							(end -0.2032 0.2794)
						)
						(arc
							(start 0.2032 0.2794)
							(mid 0.239121 0.264521)
							(end 0.254 0.2286)
						)
						(arc
							(start 0.254 -0.2286)
							(mid 0.239121 -0.264521)
							(end 0.2032 -0.2794)
						)
					)
					(width 0)
					(fill yes)
				)
			)
		)
		(pad "2" smd custom
			(at 0 0.4318 90)
			(size 0.127 0.127)
			(layers "F.Cu" "F.Mask" "F.Paste")
			(net "GND")
			(options
				(clearance outline)
				(anchor circle)
			)
			(primitives
				(gr_poly
					(pts
						(arc
							(start -0.2032 -0.2794)
							(mid -0.239121 -0.264521)
							(end -0.254 -0.2286)
						)
						(arc
							(start -0.254 0.2286)
							(mid -0.239121 0.264521)
							(end -0.2032 0.2794)
						)
						(arc
							(start 0.2032 0.2794)
							(mid 0.239121 0.264521)
							(end 0.254 0.2286)
						)
						(arc
							(start 0.254 -0.2286)
							(mid 0.239121 -0.264521)
							(end 0.2032 -0.2794)
						)
					)
					(width 0)
					(fill yes)
				)
			)
		)
	)
	(footprint ""
		(layer "F.Cu")
		(at 69.3166 -42.2402 -90)
		(property "Reference" "R316"
			(at 0 0 270)
			(layer "F.SilkS")
			(hide yes)
			(effects
				(font
					(size 1.27 1.27)
				)
			)
		)
		(property "Value" "4K7R2F-GP"
			(at 0.064008 -3.993896 270)
			(unlocked yes)
			(layer "F.Fab")
			(hide yes)
			(effects
				(font
					(size 1.016 1.016)
					(thickness 0.1524)
				)
			)
		)
		(property "Device Type" "R402H16"
			(at 0.064008 -5.517896 270)
			(unlocked yes)
			(layer "F.Fab")
			(hide yes)
			(effects
				(font
					(size 1.016 1.016)
					(thickness 0.1524)
				)
			)
		)
		(duplicate_pad_numbers_are_jumpers no)
		(fp_rect
			(start -0.381 0.8382)
			(end 0.381 -0.8382)
			(stroke
				(width 0)
				(type default)
			)
			(fill no)
			(layer "F.CrtYd")
		)
		(fp_rect
			(start -0.381 0.8382)
			(end 0.381 -0.8382)
			(stroke
				(width 0)
				(type default)
			)
			(fill no)
			(layer "F.Fab")
		)
		(pad "1" smd custom
			(at 0 -0.4318 270)
			(size 0.127 0.127)
			(layers "F.Cu" "F.Mask" "F.Paste")
			(net "P3V3")
			(options
				(clearance outline)
				(anchor circle)
			)
			(primitives
				(gr_poly
					(pts
						(arc
							(start -0.2032 -0.2794)
							(mid -0.239121 -0.264521)
							(end -0.254 -0.2286)
						)
						(arc
							(start -0.254 0.2286)
							(mid -0.239121 0.264521)
							(end -0.2032 0.2794)
						)
						(arc
							(start 0.2032 0.2794)
							(mid 0.239121 0.264521)
							(end 0.254 0.2286)
						)
						(arc
							(start 0.254 -0.2286)
							(mid 0.239121 -0.264521)
							(end 0.2032 -0.2794)
						)
					)
					(width 0)
					(fill yes)
				)
			)
		)
		(pad "2" smd custom
			(at 0 0.4318 270)
			(size 0.127 0.127)
			(layers "F.Cu" "F.Mask" "F.Paste")
			(net "SMBUS_HOST_CLK")
			(options
				(clearance outline)
				(anchor circle)
			)
			(primitives
				(gr_poly
					(pts
						(arc
							(start -0.2032 -0.2794)
							(mid -0.239121 -0.264521)
							(end -0.254 -0.2286)
						)
						(arc
							(start -0.254 0.2286)
							(mid -0.239121 0.264521)
							(end -0.2032 0.2794)
						)
						(arc
							(start 0.2032 0.2794)
							(mid 0.239121 0.264521)
							(end 0.254 0.2286)
						)
						(arc
							(start 0.254 -0.2286)
							(mid 0.239121 -0.264521)
							(end 0.2032 -0.2794)
						)
					)
					(width 0)
					(fill yes)
				)
			)
		)
	)
	(footprint ""
		(layer "F.Cu")
		(at 26.416 -50.8 -90)
		(property "Reference" "PR73"
			(at 0 0 270)
			(layer "F.SilkS")
			(hide yes)
			(effects
				(font
					(size 1.27 1.27)
				)
			)
		)
		(property "Value" "11KR2F-L-GP"
			(at 1.7907 -1.1176 270)
			(unlocked yes)
			(layer "F.Fab")
			(hide yes)
			(effects
				(font
					(size 1.016 1.016)
					(thickness 0.1524)
				)
			)
		)
		(property "Device Type" "R402H16"
			(at 1.7907 -2.6416 270)
			(unlocked yes)
			(layer "F.Fab")
			(hide yes)
			(effects
				(font
					(size 1.016 1.016)
					(thickness 0.1524)
				)
			)
		)
		(duplicate_pad_numbers_are_jumpers no)
		(fp_rect
			(start -0.381 0.8382)
			(end 0.381 -0.8382)
			(stroke
				(width 0)
				(type default)
			)
			(fill no)
			(layer "F.CrtYd")
		)
		(fp_rect
			(start -0.381 0.8382)
			(end 0.381 -0.8382)
			(stroke
				(width 0)
				(type default)
			)
			(fill no)
			(layer "F.Fab")
		)
		(pad "1" smd custom
			(at 0 -0.4318 270)
			(size 0.127 0.127)
			(layers "F.Cu" "F.Mask" "F.Paste")
			(net "VR_PVCCP_ISUMP")
			(options
				(clearance outline)
				(anchor circle)
			)
			(primitives
				(gr_poly
					(pts
						(arc
							(start -0.2032 -0.2794)
							(mid -0.239121 -0.264521)
							(end -0.254 -0.2286)
						)
						(arc
							(start -0.254 0.2286)
							(mid -0.239121 0.264521)
							(end -0.2032 0.2794)
						)
						(arc
							(start 0.2032 0.2794)
							(mid 0.239121 0.264521)
							(end 0.254 0.2286)
						)
						(arc
							(start 0.254 -0.2286)
							(mid 0.239121 -0.264521)
							(end 0.2032 -0.2794)
						)
					)
					(width 0)
					(fill yes)
				)
			)
		)
		(pad "2" smd custom
			(at 0 0.4318 270)
			(size 0.127 0.127)
			(layers "F.Cu" "F.Mask" "F.Paste")
			(net "VR_PVCCP_ISUMN")
			(options
				(clearance outline)
				(anchor circle)
			)
			(primitives
				(gr_poly
					(pts
						(arc
							(start -0.2032 -0.2794)
							(mid -0.239121 -0.264521)
							(end -0.254 -0.2286)
						)
						(arc
							(start -0.254 0.2286)
							(mid -0.239121 0.264521)
							(end -0.2032 0.2794)
						)
						(arc
							(start 0.2032 0.2794)
							(mid 0.239121 0.264521)
							(end 0.254 0.2286)
						)
						(arc
							(start 0.254 -0.2286)
							(mid 0.239121 -0.264521)
							(end 0.2032 -0.2794)
						)
					)
					(width 0)
					(fill yes)
				)
			)
		)
	)
	(footprint ""
		(layer "F.Cu")
		(at 13.8938 -68.8594 180)
		(property "Reference" "C170"
			(at 0 0 180)
			(layer "F.SilkS")
			(hide yes)
			(effects
				(font
					(size 1.27 1.27)
				)
			)
		)
		(property "Value" "SCD1U16V2KX-3GP"
			(at 1.8923 -1.2065 180)
			(unlocked yes)
			(layer "F.Fab")
			(hide yes)
			(effects
				(font
					(size 1.016 1.016)
					(thickness 0.1524)
				)
			)
		)
		(property "Device Type" "C402H22"
			(at 1.8923 -2.7305 180)
			(unlocked yes)
			(layer "F.Fab")
			(hide yes)
			(effects
				(font
					(size 1.016 1.016)
					(thickness 0.1524)
				)
			)
		)
		(duplicate_pad_numbers_are_jumpers no)
		(fp_rect
			(start -0.381 0.7366)
			(end 0.381 -0.7366)
			(stroke
				(width 0)
				(type default)
			)
			(fill no)
			(layer "F.CrtYd")
		)
		(fp_rect
			(start -0.381 0.7366)
			(end 0.381 -0.7366)
			(stroke
				(width 0)
				(type default)
			)
			(fill no)
			(layer "F.Fab")
		)
		(pad "1" smd custom
			(at 0 -0.4572 180)
			(size 0.1143 0.1143)
			(layers "F.Cu" "F.Mask" "F.Paste")
			(net "P3V3")
			(options
				(clearance outline)
				(anchor circle)
			)
			(primitives
				(gr_poly
					(pts
						(arc
							(start -0.254 -0.1778)
							(mid -0.239121 -0.213721)
							(end -0.2032 -0.2286)
						)
						(arc
							(start 0.2032 -0.2286)
							(mid 0.239121 -0.213721)
							(end 0.254 -0.1778)
						)
						(arc
							(start 0.254 0.1778)
							(mid 0.239121 0.213721)
							(end 0.2032 0.2286)
						)
						(arc
							(start -0.2032 0.2286)
							(mid -0.239121 0.213721)
							(end -0.254 0.1778)
						)
					)
					(width 0)
					(fill yes)
				)
			)
		)
		(pad "2" smd custom
			(at 0 0.4572 180)
			(size 0.1143 0.1143)
			(layers "F.Cu" "F.Mask" "F.Paste")
			(net "GND")
			(options
				(clearance outline)
				(anchor circle)
			)
			(primitives
				(gr_poly
					(pts
						(arc
							(start -0.254 -0.1778)
							(mid -0.239121 -0.213721)
							(end -0.2032 -0.2286)
						)
						(arc
							(start 0.2032 -0.2286)
							(mid 0.239121 -0.213721)
							(end 0.254 -0.1778)
						)
						(arc
							(start 0.254 0.1778)
							(mid 0.239121 0.213721)
							(end 0.2032 0.2286)
						)
						(arc
							(start -0.2032 0.2286)
							(mid -0.239121 0.213721)
							(end -0.254 0.1778)
						)
					)
					(width 0)
					(fill yes)
				)
			)
		)
	)
	(footprint ""
		(layer "F.Cu")
		(at 151.003 -20.701)
		(property "Reference" "C54"
			(at 0 0 0)
			(layer "F.SilkS")
			(hide yes)
			(effects
				(font
					(size 1.27 1.27)
				)
			)
		)
		(property "Value" "SCD1U10V2KX-5GP"
			(at 1.1811 -2.7051 0)
			(unlocked yes)
			(layer "F.Fab")
			(hide yes)
			(effects
				(font
					(size 1.016 1.016)
					(thickness 0.1524)
				)
			)
		)
		(property "Device Type" "C402H22"
			(at 1.1811 -4.2291 0)
			(unlocked yes)
			(layer "F.Fab")
			(hide yes)
			(effects
				(font
					(size 1.016 1.016)
					(thickness 0.1524)
				)
			)
		)
		(duplicate_pad_numbers_are_jumpers no)
		(fp_rect
			(start -0.381 0.7366)
			(end 0.381 -0.7366)
			(stroke
				(width 0)
				(type default)
			)
			(fill no)
			(layer "F.CrtYd")
		)
		(fp_rect
			(start -0.381 0.7366)
			(end 0.381 -0.7366)
			(stroke
				(width 0)
				(type default)
			)
			(fill no)
			(layer "F.Fab")
		)
		(pad "1" smd custom
			(at 0 -0.4572)
			(size 0.1143 0.1143)
			(layers "F.Cu" "F.Mask" "F.Paste")
			(net "P2V5_STBY")
			(options
				(clearance outline)
				(anchor circle)
			)
			(primitives
				(gr_poly
					(pts
						(arc
							(start -0.254 -0.1778)
							(mid -0.239121 -0.213721)
							(end -0.2032 -0.2286)
						)
						(arc
							(start 0.2032 -0.2286)
							(mid 0.239121 -0.213721)
							(end 0.254 -0.1778)
						)
						(arc
							(start 0.254 0.1778)
							(mid 0.239121 0.213721)
							(end 0.2032 0.2286)
						)
						(arc
							(start -0.2032 0.2286)
							(mid -0.239121 0.213721)
							(end -0.254 0.1778)
						)
					)
					(width 0)
					(fill yes)
				)
			)
		)
		(pad "2" smd custom
			(at 0 0.4572)
			(size 0.1143 0.1143)
			(layers "F.Cu" "F.Mask" "F.Paste")
			(net "GND")
			(options
				(clearance outline)
				(anchor circle)
			)
			(primitives
				(gr_poly
					(pts
						(arc
							(start -0.254 -0.1778)
							(mid -0.239121 -0.213721)
							(end -0.2032 -0.2286)
						)
						(arc
							(start 0.2032 -0.2286)
							(mid 0.239121 -0.213721)
							(end 0.254 -0.1778)
						)
						(arc
							(start 0.254 0.1778)
							(mid 0.239121 0.213721)
							(end 0.2032 0.2286)
						)
						(arc
							(start -0.2032 0.2286)
							(mid -0.239121 0.213721)
							(end -0.254 0.1778)
						)
					)
					(width 0)
					(fill yes)
				)
			)
		)
	)
	(footprint ""
		(layer "F.Cu")
		(at 15.8496 -56.0832 -90)
		(property "Reference" "PR63"
			(at 0 0 270)
			(layer "F.SilkS")
			(hide yes)
			(effects
				(font
					(size 1.27 1.27)
				)
			)
		)
		(property "Value" "0R2J-2-GP"
			(at 1.7907 -1.1176 270)
			(unlocked yes)
			(layer "F.Fab")
			(hide yes)
			(effects
				(font
					(size 1.016 1.016)
					(thickness 0.1524)
				)
			)
		)
		(property "Device Type" "R402H16"
			(at 1.7907 -2.6416 270)
			(unlocked yes)
			(layer "F.Fab")
			(hide yes)
			(effects
				(font
					(size 1.016 1.016)
					(thickness 0.1524)
				)
			)
		)
		(duplicate_pad_numbers_are_jumpers no)
		(fp_rect
			(start -0.381 0.8382)
			(end 0.381 -0.8382)
			(stroke
				(width 0)
				(type default)
			)
			(fill no)
			(layer "F.CrtYd")
		)
		(fp_rect
			(start -0.381 0.8382)
			(end 0.381 -0.8382)
			(stroke
				(width 0)
				(type default)
			)
			(fill no)
			(layer "F.Fab")
		)
		(pad "1" smd custom
			(at 0 -0.4318 270)
			(size 0.127 0.127)
			(layers "F.Cu" "F.Mask" "F.Paste")
			(net "PWRGD_R_PVCCP")
			(options
				(clearance outline)
				(anchor circle)
			)
			(primitives
				(gr_poly
					(pts
						(arc
							(start -0.2032 -0.2794)
							(mid -0.239121 -0.264521)
							(end -0.254 -0.2286)
						)
						(arc
							(start -0.254 0.2286)
							(mid -0.239121 0.264521)
							(end -0.2032 0.2794)
						)
						(arc
							(start 0.2032 0.2794)
							(mid 0.239121 0.264521)
							(end 0.254 0.2286)
						)
						(arc
							(start 0.254 -0.2286)
							(mid 0.239121 -0.264521)
							(end 0.2032 -0.2794)
						)
					)
					(width 0)
					(fill yes)
				)
			)
		)
		(pad "2" smd custom
			(at 0 0.4318 270)
			(size 0.127 0.127)
			(layers "F.Cu" "F.Mask" "F.Paste")
			(net "PWRGD_PVCCP_VNN_PG")
			(options
				(clearance outline)
				(anchor circle)
			)
			(primitives
				(gr_poly
					(pts
						(arc
							(start -0.2032 -0.2794)
							(mid -0.239121 -0.264521)
							(end -0.254 -0.2286)
						)
						(arc
							(start -0.254 0.2286)
							(mid -0.239121 0.264521)
							(end -0.2032 0.2794)
						)
						(arc
							(start 0.2032 0.2794)
							(mid 0.239121 0.264521)
							(end 0.254 0.2286)
						)
						(arc
							(start 0.254 -0.2286)
							(mid 0.239121 -0.264521)
							(end 0.2032 -0.2794)
						)
					)
					(width 0)
					(fill yes)
				)
			)
		)
	)
	(footprint ""
		(layer "F.Cu")
		(at 167.894 -28.321 90)
		(property "Reference" "PR136"
			(at 0 0 90)
			(layer "F.SilkS")
			(hide yes)
			(effects
				(font
					(size 1.27 1.27)
				)
			)
		)
		(property "Value" "0R3J-6-GP"
			(at -0.0254 -2.5146 90)
			(unlocked yes)
			(layer "F.Fab")
			(hide yes)
			(effects
				(font
					(size 1.016 1.016)
					(thickness 0.1524)
				)
			)
		)
		(property "Device Type" "R603H22"
			(at -0.0254 -4.0386 90)
			(unlocked yes)
			(layer "F.Fab")
			(hide yes)
			(effects
				(font
					(size 1.016 1.016)
					(thickness 0.1524)
				)
			)
		)
		(duplicate_pad_numbers_are_jumpers no)
		(fp_line
			(start 0.4318 0)
			(end 0.2032 0)
			(stroke
				(width 0.2032)
				(type default)
			)
			(layer "F.SilkS")
		)
		(fp_line
			(start -0.2032 0)
			(end -0.4191 0)
			(stroke
				(width 0.2032)
				(type default)
			)
			(layer "F.SilkS")
		)
		(fp_rect
			(start -0.635 1.1811)
			(end 0.635 -1.1811)
			(stroke
				(width 0)
				(type default)
			)
			(fill no)
			(layer "F.CrtYd")
		)
		(fp_rect
			(start -0.635 1.1811)
			(end 0.635 -1.1811)
			(stroke
				(width 0)
				(type default)
			)
			(fill no)
			(layer "F.Fab")
		)
		(pad "1" smd custom
			(at 0 -0.6604 90)
			(size 0.19685 0.19685)
			(layers "F.Cu" "F.Mask" "F.Paste")
			(net "P1V2_FPGA_D")
			(options
				(clearance outline)
				(anchor circle)
			)
			(primitives
				(gr_poly
					(pts
						(arc
							(start 0.508 -0.2921)
							(mid 0.478242 -0.363942)
							(end 0.4064 -0.3937)
						)
						(arc
							(start -0.4064 -0.3937)
							(mid -0.478242 -0.363942)
							(end -0.508 -0.2921)
						)
						(arc
							(start -0.508 0.2921)
							(mid -0.478242 0.363942)
							(end -0.4064 0.3937)
						)
						(arc
							(start 0.4064 0.3937)
							(mid 0.478242 0.363942)
							(end 0.508 0.2921)
						)
					)
					(width 0)
					(fill yes)
				)
			)
		)
		(pad "2" smd custom
			(at 0 0.6604 90)
			(size 0.19685 0.19685)
			(layers "F.Cu" "F.Mask" "F.Paste")
			(net "P1V2_STBY_LDO_OUT2")
			(options
				(clearance outline)
				(anchor circle)
			)
			(primitives
				(gr_poly
					(pts
						(arc
							(start 0.508 -0.2921)
							(mid 0.478242 -0.363942)
							(end 0.4064 -0.3937)
						)
						(arc
							(start -0.4064 -0.3937)
							(mid -0.478242 -0.363942)
							(end -0.508 -0.2921)
						)
						(arc
							(start -0.508 0.2921)
							(mid -0.478242 0.363942)
							(end -0.4064 0.3937)
						)
						(arc
							(start 0.4064 0.3937)
							(mid 0.478242 0.363942)
							(end 0.508 0.2921)
						)
					)
					(width 0)
					(fill yes)
				)
			)
		)
	)
	(footprint ""
		(layer "F.Cu")
		(at 79.121 -65.913 180)
		(property "Reference" "R178"
			(at 0 0 180)
			(layer "F.SilkS")
			(hide yes)
			(effects
				(font
					(size 1.27 1.27)
				)
			)
		)
		(property "Value" "4K7R2F-GP"
			(at 1.7907 -1.1176 180)
			(unlocked yes)
			(layer "F.Fab")
			(hide yes)
			(effects
				(font
					(size 1.016 1.016)
					(thickness 0.1524)
				)
			)
		)
		(property "Device Type" "R402H16"
			(at 1.7907 -2.6416 180)
			(unlocked yes)
			(layer "F.Fab")
			(hide yes)
			(effects
				(font
					(size 1.016 1.016)
					(thickness 0.1524)
				)
			)
		)
		(duplicate_pad_numbers_are_jumpers no)
		(fp_rect
			(start -0.381 0.8382)
			(end 0.381 -0.8382)
			(stroke
				(width 0)
				(type default)
			)
			(fill no)
			(layer "F.CrtYd")
		)
		(fp_rect
			(start -0.381 0.8382)
			(end 0.381 -0.8382)
			(stroke
				(width 0)
				(type default)
			)
			(fill no)
			(layer "F.Fab")
		)
		(pad "1" smd custom
			(at 0 -0.4318 180)
			(size 0.127 0.127)
			(layers "F.Cu" "F.Mask" "F.Paste")
			(net "VOL1_SEN_ADDR1")
			(options
				(clearance outline)
				(anchor circle)
			)
			(primitives
				(gr_poly
					(pts
						(arc
							(start -0.2032 -0.2794)
							(mid -0.239121 -0.264521)
							(end -0.254 -0.2286)
						)
						(arc
							(start -0.254 0.2286)
							(mid -0.239121 0.264521)
							(end -0.2032 0.2794)
						)
						(arc
							(start 0.2032 0.2794)
							(mid 0.239121 0.264521)
							(end 0.254 0.2286)
						)
						(arc
							(start 0.254 -0.2286)
							(mid 0.239121 -0.264521)
							(end 0.2032 -0.2794)
						)
					)
					(width 0)
					(fill yes)
				)
			)
		)
		(pad "2" smd custom
			(at 0 0.4318 180)
			(size 0.127 0.127)
			(layers "F.Cu" "F.Mask" "F.Paste")
			(net "GND")
			(options
				(clearance outline)
				(anchor circle)
			)
			(primitives
				(gr_poly
					(pts
						(arc
							(start -0.2032 -0.2794)
							(mid -0.239121 -0.264521)
							(end -0.254 -0.2286)
						)
						(arc
							(start -0.254 0.2286)
							(mid -0.239121 0.264521)
							(end -0.2032 0.2794)
						)
						(arc
							(start 0.2032 0.2794)
							(mid 0.239121 0.264521)
							(end 0.254 0.2286)
						)
						(arc
							(start 0.254 -0.2286)
							(mid 0.239121 -0.264521)
							(end 0.2032 -0.2794)
						)
					)
					(width 0)
					(fill yes)
				)
			)
		)
	)
	(footprint ""
		(layer "F.Cu")
		(at 166.37 -48.006 -90)
		(property "Reference" "R212"
			(at 0 0 270)
			(layer "F.SilkS")
			(hide yes)
			(effects
				(font
					(size 1.27 1.27)
				)
			)
		)
		(property "Value" "0R2J-2-GP"
			(at 1.7907 -1.1176 270)
			(unlocked yes)
			(layer "F.Fab")
			(hide yes)
			(effects
				(font
					(size 1.016 1.016)
					(thickness 0.1524)
				)
			)
		)
		(property "Device Type" "R402H16"
			(at 1.7907 -2.6416 270)
			(unlocked yes)
			(layer "F.Fab")
			(hide yes)
			(effects
				(font
					(size 1.016 1.016)
					(thickness 0.1524)
				)
			)
		)
		(duplicate_pad_numbers_are_jumpers no)
		(fp_rect
			(start -0.381 0.8382)
			(end 0.381 -0.8382)
			(stroke
				(width 0)
				(type default)
			)
			(fill no)
			(layer "F.CrtYd")
		)
		(fp_rect
			(start -0.381 0.8382)
			(end 0.381 -0.8382)
			(stroke
				(width 0)
				(type default)
			)
			(fill no)
			(layer "F.Fab")
		)
		(pad "1" smd custom
			(at 0 -0.4318 270)
			(size 0.127 0.127)
			(layers "F.Cu" "F.Mask" "F.Paste")
			(net "XDP_SOC_CPU_TRST#")
			(options
				(clearance outline)
				(anchor circle)
			)
			(primitives
				(gr_poly
					(pts
						(arc
							(start -0.2032 -0.2794)
							(mid -0.239121 -0.264521)
							(end -0.254 -0.2286)
						)
						(arc
							(start -0.254 0.2286)
							(mid -0.239121 0.264521)
							(end -0.2032 0.2794)
						)
						(arc
							(start 0.2032 0.2794)
							(mid 0.239121 0.264521)
							(end 0.254 0.2286)
						)
						(arc
							(start 0.254 -0.2286)
							(mid 0.239121 -0.264521)
							(end 0.2032 -0.2794)
						)
					)
					(width 0)
					(fill yes)
				)
			)
		)
		(pad "2" smd custom
			(at 0 0.4318 270)
			(size 0.127 0.127)
			(layers "F.Cu" "F.Mask" "F.Paste")
			(net "XDP_SOC_CPU_TRST#_S")
			(options
				(clearance outline)
				(anchor circle)
			)
			(primitives
				(gr_poly
					(pts
						(arc
							(start -0.2032 -0.2794)
							(mid -0.239121 -0.264521)
							(end -0.254 -0.2286)
						)
						(arc
							(start -0.254 0.2286)
							(mid -0.239121 0.264521)
							(end -0.2032 0.2794)
						)
						(arc
							(start 0.2032 0.2794)
							(mid 0.239121 0.264521)
							(end 0.254 0.2286)
						)
						(arc
							(start 0.254 -0.2286)
							(mid 0.239121 -0.264521)
							(end 0.2032 -0.2794)
						)
					)
					(width 0)
					(fill yes)
				)
			)
		)
	)
	(footprint ""
		(layer "F.Cu")
		(at 151.2189 -49.0347 180)
		(property "Reference" "TP40"
			(at 0 0 180)
			(layer "F.SilkS")
			(hide yes)
			(effects
				(font
					(size 1.27 1.27)
				)
			)
		)
		(property "Value" "TPAD32-GP"
			(at 0 -3.166364 180)
			(unlocked yes)
			(layer "F.Fab")
			(hide yes)
			(effects
				(font
					(size 1.016 1.016)
					(thickness 0.1524)
				)
			)
		)
		(property "Device Type" "TPAD32"
			(at 0 -4.690618 180)
			(unlocked yes)
			(layer "F.Fab")
			(hide yes)
			(effects
				(font
					(size 1.016 1.016)
					(thickness 0.1524)
				)
			)
		)
		(duplicate_pad_numbers_are_jumpers no)
		(fp_poly
			(pts
				(arc
					(start -0.7112 0)
					(mid 0.7112 0)
					(end -0.7112 0)
				)
			)
			(stroke
				(width 0)
				(type default)
			)
			(fill no)
			(layer "F.CrtYd")
		)
		(fp_poly
			(pts
				(arc
					(start -0.7112 0)
					(mid 0.7112 0)
					(end -0.7112 0)
				)
			)
			(stroke
				(width 0)
				(type default)
			)
			(fill no)
			(layer "F.Fab")
		)
		(pad "1" smd circle
			(at 0 0 180)
			(size 0.8128 0.8128)
			(layers "F.Cu" "F.Mask" "F.Paste")
			(net "C_DATA0")
		)
	)
	(footprint ""
		(layer "F.Cu")
		(at 65.786 -12.954)
		(property "Reference" "R475"
			(at 0 0 0)
			(layer "F.SilkS")
			(hide yes)
			(effects
				(font
					(size 1.27 1.27)
				)
			)
		)
		(property "Value" "4K7R2F-GP"
			(at 1.7907 -1.1176 0)
			(unlocked yes)
			(layer "F.Fab")
			(hide yes)
			(effects
				(font
					(size 1.016 1.016)
					(thickness 0.1524)
				)
			)
		)
		(property "Device Type" "R402H16"
			(at 1.7907 -2.6416 0)
			(unlocked yes)
			(layer "F.Fab")
			(hide yes)
			(effects
				(font
					(size 1.016 1.016)
					(thickness 0.1524)
				)
			)
		)
		(duplicate_pad_numbers_are_jumpers no)
		(fp_rect
			(start -0.381 0.8382)
			(end 0.381 -0.8382)
			(stroke
				(width 0)
				(type default)
			)
			(fill no)
			(layer "F.CrtYd")
		)
		(fp_rect
			(start -0.381 0.8382)
			(end 0.381 -0.8382)
			(stroke
				(width 0)
				(type default)
			)
			(fill no)
			(layer "F.Fab")
		)
		(pad "1" smd custom
			(at 0 -0.4318)
			(size 0.127 0.127)
			(layers "F.Cu" "F.Mask" "F.Paste")
			(net "P3V3")
			(options
				(clearance outline)
				(anchor circle)
			)
			(primitives
				(gr_poly
					(pts
						(arc
							(start -0.2032 -0.2794)
							(mid -0.239121 -0.264521)
							(end -0.254 -0.2286)
						)
						(arc
							(start -0.254 0.2286)
							(mid -0.239121 0.264521)
							(end -0.2032 0.2794)
						)
						(arc
							(start 0.2032 0.2794)
							(mid 0.239121 0.264521)
							(end 0.254 0.2286)
						)
						(arc
							(start 0.254 -0.2286)
							(mid 0.239121 -0.264521)
							(end 0.2032 -0.2794)
						)
					)
					(width 0)
					(fill yes)
				)
			)
		)
		(pad "2" smd custom
			(at 0 0.4318)
			(size 0.127 0.127)
			(layers "F.Cu" "F.Mask" "F.Paste")
			(net "PMU_RESETBUTTON#")
			(options
				(clearance outline)
				(anchor circle)
			)
			(primitives
				(gr_poly
					(pts
						(arc
							(start -0.2032 -0.2794)
							(mid -0.239121 -0.264521)
							(end -0.254 -0.2286)
						)
						(arc
							(start -0.254 0.2286)
							(mid -0.239121 0.264521)
							(end -0.2032 0.2794)
						)
						(arc
							(start 0.2032 0.2794)
							(mid 0.239121 0.264521)
							(end 0.254 0.2286)
						)
						(arc
							(start 0.254 -0.2286)
							(mid 0.239121 -0.264521)
							(end 0.2032 -0.2794)
						)
					)
					(width 0)
					(fill yes)
				)
			)
		)
	)
	(footprint ""
		(layer "F.Cu")
		(at 71.247 -15.748 90)
		(property "Reference" "R461"
			(at 0 0 90)
			(layer "F.SilkS")
			(hide yes)
			(effects
				(font
					(size 1.27 1.27)
				)
			)
		)
		(property "Value" "4K7R2F-GP"
			(at 1.7907 -1.1176 90)
			(unlocked yes)
			(layer "F.Fab")
			(hide yes)
			(effects
				(font
					(size 1.016 1.016)
					(thickness 0.1524)
				)
			)
		)
		(property "Device Type" "R402H16"
			(at 1.7907 -2.6416 90)
			(unlocked yes)
			(layer "F.Fab")
			(hide yes)
			(effects
				(font
					(size 1.016 1.016)
					(thickness 0.1524)
				)
			)
		)
		(duplicate_pad_numbers_are_jumpers no)
		(fp_rect
			(start -0.381 0.8382)
			(end 0.381 -0.8382)
			(stroke
				(width 0)
				(type default)
			)
			(fill no)
			(layer "F.CrtYd")
		)
		(fp_rect
			(start -0.381 0.8382)
			(end 0.381 -0.8382)
			(stroke
				(width 0)
				(type default)
			)
			(fill no)
			(layer "F.Fab")
		)
		(pad "1" smd custom
			(at 0 -0.4318 90)
			(size 0.127 0.127)
			(layers "F.Cu" "F.Mask" "F.Paste")
			(net "P3V3_STBY")
			(options
				(clearance outline)
				(anchor circle)
			)
			(primitives
				(gr_poly
					(pts
						(arc
							(start -0.2032 -0.2794)
							(mid -0.239121 -0.264521)
							(end -0.254 -0.2286)
						)
						(arc
							(start -0.254 0.2286)
							(mid -0.239121 0.264521)
							(end -0.2032 0.2794)
						)
						(arc
							(start 0.2032 0.2794)
							(mid 0.239121 0.264521)
							(end 0.254 0.2286)
						)
						(arc
							(start 0.254 -0.2286)
							(mid 0.239121 -0.264521)
							(end 0.2032 -0.2794)
						)
					)
					(width 0)
					(fill yes)
				)
			)
		)
		(pad "2" smd custom
			(at 0 0.4318 90)
			(size 0.127 0.127)
			(layers "F.Cu" "F.Mask" "F.Paste")
			(net "BMC_I2C_ALERT#")
			(options
				(clearance outline)
				(anchor circle)
			)
			(primitives
				(gr_poly
					(pts
						(arc
							(start -0.2032 -0.2794)
							(mid -0.239121 -0.264521)
							(end -0.254 -0.2286)
						)
						(arc
							(start -0.254 0.2286)
							(mid -0.239121 0.264521)
							(end -0.2032 0.2794)
						)
						(arc
							(start 0.2032 0.2794)
							(mid 0.239121 0.264521)
							(end 0.254 0.2286)
						)
						(arc
							(start 0.254 -0.2286)
							(mid 0.239121 -0.264521)
							(end 0.2032 -0.2794)
						)
					)
					(width 0)
					(fill yes)
				)
			)
		)
	)
	(footprint ""
		(layer "F.Cu")
		(at 46.101 -18.415 90)
		(property "Reference" "R341"
			(at 0 0 90)
			(layer "F.SilkS")
			(hide yes)
			(effects
				(font
					(size 1.27 1.27)
				)
			)
		)
		(property "Value" "4K7R2F-GP"
			(at 0.064008 -3.993896 90)
			(unlocked yes)
			(layer "F.Fab")
			(hide yes)
			(effects
				(font
					(size 1.016 1.016)
					(thickness 0.1524)
				)
			)
		)
		(property "Device Type" "R402H16"
			(at 0.064008 -5.517896 90)
			(unlocked yes)
			(layer "F.Fab")
			(hide yes)
			(effects
				(font
					(size 1.016 1.016)
					(thickness 0.1524)
				)
			)
		)
		(duplicate_pad_numbers_are_jumpers no)
		(fp_rect
			(start -0.381 0.8382)
			(end 0.381 -0.8382)
			(stroke
				(width 0)
				(type default)
			)
			(fill no)
			(layer "F.CrtYd")
		)
		(fp_rect
			(start -0.381 0.8382)
			(end 0.381 -0.8382)
			(stroke
				(width 0)
				(type default)
			)
			(fill no)
			(layer "F.Fab")
		)
		(pad "1" smd custom
			(at 0 -0.4318 90)
			(size 0.127 0.127)
			(layers "F.Cu" "F.Mask" "F.Paste")
			(net "CLKBUFF_OE1#")
			(options
				(clearance outline)
				(anchor circle)
			)
			(primitives
				(gr_poly
					(pts
						(arc
							(start -0.2032 -0.2794)
							(mid -0.239121 -0.264521)
							(end -0.254 -0.2286)
						)
						(arc
							(start -0.254 0.2286)
							(mid -0.239121 0.264521)
							(end -0.2032 0.2794)
						)
						(arc
							(start 0.2032 0.2794)
							(mid 0.239121 0.264521)
							(end 0.254 0.2286)
						)
						(arc
							(start 0.254 -0.2286)
							(mid 0.239121 -0.264521)
							(end 0.2032 -0.2794)
						)
					)
					(width 0)
					(fill yes)
				)
			)
		)
		(pad "2" smd custom
			(at 0 0.4318 90)
			(size 0.127 0.127)
			(layers "F.Cu" "F.Mask" "F.Paste")
			(net "GND")
			(options
				(clearance outline)
				(anchor circle)
			)
			(primitives
				(gr_poly
					(pts
						(arc
							(start -0.2032 -0.2794)
							(mid -0.239121 -0.264521)
							(end -0.254 -0.2286)
						)
						(arc
							(start -0.254 0.2286)
							(mid -0.239121 0.264521)
							(end -0.2032 0.2794)
						)
						(arc
							(start 0.2032 0.2794)
							(mid 0.239121 0.264521)
							(end 0.254 0.2286)
						)
						(arc
							(start 0.254 -0.2286)
							(mid 0.239121 -0.264521)
							(end 0.2032 -0.2794)
						)
					)
					(width 0)
					(fill yes)
				)
			)
		)
	)
	(footprint ""
		(layer "F.Cu")
		(at 15.3924 -52.578)
		(property "Reference" "PC57"
			(at 0 0 0)
			(layer "F.SilkS")
			(hide yes)
			(effects
				(font
					(size 1.27 1.27)
				)
			)
		)
		(property "Value" "SC1KP50V2KX-1GP"
			(at 1.8923 -1.2065 0)
			(unlocked yes)
			(layer "F.Fab")
			(hide yes)
			(effects
				(font
					(size 1.016 1.016)
					(thickness 0.1524)
				)
			)
		)
		(property "Device Type" "C402H22"
			(at 1.8923 -2.7305 0)
			(unlocked yes)
			(layer "F.Fab")
			(hide yes)
			(effects
				(font
					(size 1.016 1.016)
					(thickness 0.1524)
				)
			)
		)
		(duplicate_pad_numbers_are_jumpers no)
		(fp_rect
			(start -0.381 0.7366)
			(end 0.381 -0.7366)
			(stroke
				(width 0)
				(type default)
			)
			(fill no)
			(layer "F.CrtYd")
		)
		(fp_rect
			(start -0.381 0.7366)
			(end 0.381 -0.7366)
			(stroke
				(width 0)
				(type default)
			)
			(fill no)
			(layer "F.Fab")
		)
		(pad "1" smd custom
			(at 0 -0.4572)
			(size 0.1143 0.1143)
			(layers "F.Cu" "F.Mask" "F.Paste")
			(net "VR_PVCCP_VW")
			(options
				(clearance outline)
				(anchor circle)
			)
			(primitives
				(gr_poly
					(pts
						(arc
							(start -0.254 -0.1778)
							(mid -0.239121 -0.213721)
							(end -0.2032 -0.2286)
						)
						(arc
							(start 0.2032 -0.2286)
							(mid 0.239121 -0.213721)
							(end 0.254 -0.1778)
						)
						(arc
							(start 0.254 0.1778)
							(mid 0.239121 0.213721)
							(end 0.2032 0.2286)
						)
						(arc
							(start -0.2032 0.2286)
							(mid -0.239121 0.213721)
							(end -0.254 0.1778)
						)
					)
					(width 0)
					(fill yes)
				)
			)
		)
		(pad "2" smd custom
			(at 0 0.4572)
			(size 0.1143 0.1143)
			(layers "F.Cu" "F.Mask" "F.Paste")
			(net "VR_PVCCP_COMP")
			(options
				(clearance outline)
				(anchor circle)
			)
			(primitives
				(gr_poly
					(pts
						(arc
							(start -0.254 -0.1778)
							(mid -0.239121 -0.213721)
							(end -0.2032 -0.2286)
						)
						(arc
							(start 0.2032 -0.2286)
							(mid 0.239121 -0.213721)
							(end 0.254 -0.1778)
						)
						(arc
							(start 0.254 0.1778)
							(mid 0.239121 0.213721)
							(end 0.2032 0.2286)
						)
						(arc
							(start -0.2032 0.2286)
							(mid -0.239121 0.213721)
							(end -0.254 0.1778)
						)
					)
					(width 0)
					(fill yes)
				)
			)
		)
	)
	(footprint ""
		(layer "F.Cu")
		(at 111.506 -19.177 -90)
		(property "Reference" "R168"
			(at 0 0 270)
			(layer "F.SilkS")
			(hide yes)
			(effects
				(font
					(size 1.27 1.27)
				)
			)
		)
		(property "Value" "100R3F-1-GP"
			(at -0.0254 -2.5146 270)
			(unlocked yes)
			(layer "F.Fab")
			(hide yes)
			(effects
				(font
					(size 1.016 1.016)
					(thickness 0.1524)
				)
			)
		)
		(property "Device Type" "R603H22"
			(at -0.0254 -4.0386 270)
			(unlocked yes)
			(layer "F.Fab")
			(hide yes)
			(effects
				(font
					(size 1.016 1.016)
					(thickness 0.1524)
				)
			)
		)
		(duplicate_pad_numbers_are_jumpers no)
		(fp_line
			(start -0.2032 0)
			(end -0.4191 0)
			(stroke
				(width 0.2032)
				(type default)
			)
			(layer "F.SilkS")
		)
		(fp_line
			(start 0.4318 0)
			(end 0.2032 0)
			(stroke
				(width 0.2032)
				(type default)
			)
			(layer "F.SilkS")
		)
		(fp_rect
			(start -0.635 1.1811)
			(end 0.635 -1.1811)
			(stroke
				(width 0)
				(type default)
			)
			(fill no)
			(layer "F.CrtYd")
		)
		(fp_rect
			(start -0.635 1.1811)
			(end 0.635 -1.1811)
			(stroke
				(width 0)
				(type default)
			)
			(fill no)
			(layer "F.Fab")
		)
		(pad "1" smd custom
			(at 0 -0.6604 270)
			(size 0.19685 0.19685)
			(layers "F.Cu" "F.Mask" "F.Paste")
			(net "M_B_MON1_P")
			(options
				(clearance outline)
				(anchor circle)
			)
			(primitives
				(gr_poly
					(pts
						(arc
							(start 0.508 -0.2921)
							(mid 0.478242 -0.363942)
							(end 0.4064 -0.3937)
						)
						(arc
							(start -0.4064 -0.3937)
							(mid -0.478242 -0.363942)
							(end -0.508 -0.2921)
						)
						(arc
							(start -0.508 0.2921)
							(mid -0.478242 0.363942)
							(end -0.4064 0.3937)
						)
						(arc
							(start 0.4064 0.3937)
							(mid 0.478242 0.363942)
							(end 0.508 0.2921)
						)
					)
					(width 0)
					(fill yes)
				)
			)
		)
		(pad "2" smd custom
			(at 0 0.6604 270)
			(size 0.19685 0.19685)
			(layers "F.Cu" "F.Mask" "F.Paste")
			(net "M_B_MON1_N")
			(options
				(clearance outline)
				(anchor circle)
			)
			(primitives
				(gr_poly
					(pts
						(arc
							(start 0.508 -0.2921)
							(mid 0.478242 -0.363942)
							(end 0.4064 -0.3937)
						)
						(arc
							(start -0.4064 -0.3937)
							(mid -0.478242 -0.363942)
							(end -0.508 -0.2921)
						)
						(arc
							(start -0.508 0.2921)
							(mid -0.478242 0.363942)
							(end -0.4064 0.3937)
						)
						(arc
							(start 0.4064 0.3937)
							(mid 0.478242 0.363942)
							(end 0.508 0.2921)
						)
					)
					(width 0)
					(fill yes)
				)
			)
		)
	)
	(footprint ""
		(layer "F.Cu")
		(at 64.77 -56.642)
		(property "Reference" "PR78"
			(at 0 0 0)
			(layer "F.SilkS")
			(hide yes)
			(effects
				(font
					(size 1.27 1.27)
				)
			)
		)
		(property "Value" "120R3F-L-GP"
			(at -0.0254 -2.5146 0)
			(unlocked yes)
			(layer "F.Fab")
			(hide yes)
			(effects
				(font
					(size 1.016 1.016)
					(thickness 0.1524)
				)
			)
		)
		(property "Device Type" "R603H22"
			(at -0.0254 -4.0386 0)
			(unlocked yes)
			(layer "F.Fab")
			(hide yes)
			(effects
				(font
					(size 1.016 1.016)
					(thickness 0.1524)
				)
			)
		)
		(duplicate_pad_numbers_are_jumpers no)
		(fp_line
			(start -0.2032 0)
			(end -0.4191 0)
			(stroke
				(width 0.2032)
				(type default)
			)
			(layer "F.SilkS")
		)
		(fp_line
			(start 0.4318 0)
			(end 0.2032 0)
			(stroke
				(width 0.2032)
				(type default)
			)
			(layer "F.SilkS")
		)
		(fp_rect
			(start -0.635 1.1811)
			(end 0.635 -1.1811)
			(stroke
				(width 0)
				(type default)
			)
			(fill no)
			(layer "F.CrtYd")
		)
		(fp_rect
			(start -0.635 1.1811)
			(end 0.635 -1.1811)
			(stroke
				(width 0)
				(type default)
			)
			(fill no)
			(layer "F.Fab")
		)
		(pad "1" smd custom
			(at 0 -0.6604)
			(size 0.19685 0.19685)
			(layers "F.Cu" "F.Mask" "F.Paste")
			(net "PVCCP")
			(options
				(clearance outline)
				(anchor circle)
			)
			(primitives
				(gr_poly
					(pts
						(arc
							(start 0.508 -0.2921)
							(mid 0.478242 -0.363942)
							(end 0.4064 -0.3937)
						)
						(arc
							(start -0.4064 -0.3937)
							(mid -0.478242 -0.363942)
							(end -0.508 -0.2921)
						)
						(arc
							(start -0.508 0.2921)
							(mid -0.478242 0.363942)
							(end -0.4064 0.3937)
						)
						(arc
							(start 0.4064 0.3937)
							(mid 0.478242 0.363942)
							(end 0.508 0.2921)
						)
					)
					(width 0)
					(fill yes)
				)
			)
		)
		(pad "2" smd custom
			(at 0 0.6604)
			(size 0.19685 0.19685)
			(layers "F.Cu" "F.Mask" "F.Paste")
			(net "GND")
			(options
				(clearance outline)
				(anchor circle)
			)
			(primitives
				(gr_poly
					(pts
						(arc
							(start 0.508 -0.2921)
							(mid 0.478242 -0.363942)
							(end 0.4064 -0.3937)
						)
						(arc
							(start -0.4064 -0.3937)
							(mid -0.478242 -0.363942)
							(end -0.508 -0.2921)
						)
						(arc
							(start -0.508 0.2921)
							(mid -0.478242 0.363942)
							(end -0.4064 0.3937)
						)
						(arc
							(start 0.4064 0.3937)
							(mid 0.478242 0.363942)
							(end 0.508 0.2921)
						)
					)
					(width 0)
					(fill yes)
				)
			)
		)
	)
	(footprint ""
		(layer "F.Cu")
		(at 40.767 -65.278 90)
		(property "Reference" "PL1"
			(at 0 0 90)
			(layer "F.SilkS")
			(hide yes)
			(effects
				(font
					(size 1.27 1.27)
				)
			)
		)
		(property "Value" "COIL-1UH-50-GP"
			(at -5.289296 -6.964934 90)
			(unlocked yes)
			(layer "F.Fab")
			(hide yes)
			(effects
				(font
					(size 1.016 1.016)
					(thickness 0.1524)
				)
			)
		)
		(property "Device Type" "L7467-1432-1H119"
			(at -5.289296 -8.488934 90)
			(unlocked yes)
			(layer "F.Fab")
			(hide yes)
			(effects
				(font
					(size 1.016 1.016)
					(thickness 0.1524)
				)
			)
		)
		(duplicate_pad_numbers_are_jumpers no)
		(fp_rect
			(start -3.6068 4.2164)
			(end 3.6068 -4.2164)
			(stroke
				(width 0)
				(type default)
			)
			(fill no)
			(layer "F.CrtYd")
		)
		(fp_rect
			(start -3.6068 4.2164)
			(end 3.6068 -4.2164)
			(stroke
				(width 0)
				(type default)
			)
			(fill no)
			(layer "F.Fab")
		)
		(pad "1" smd rect
			(at 0 -3.06197 90)
			(size 3.4544 2.032)
			(layers "F.Cu" "F.Mask" "F.Paste")
			(net "VR_PVNN_PHASE")
		)
		(pad "2" smd rect
			(at 0 3.06197 90)
			(size 3.4544 2.032)
			(layers "F.Cu" "F.Mask" "F.Paste")
			(net "PVNN")
		)
	)
	(footprint ""
		(layer "F.Cu")
		(at 40.2082 -46.6598)
		(property "Reference" "U7"
			(at 0 0 0)
			(layer "F.SilkS")
			(hide yes)
			(effects
				(font
					(size 1.27 1.27)
				)
			)
		)
		(property "Value" "SN74LVC1G14DCKR-GP"
			(at 0 -8.0772 0)
			(unlocked yes)
			(layer "F.Fab")
			(hide yes)
			(effects
				(font
					(size 1.016 1.016)
					(thickness 0.1524)
				)
			)
		)
		(property "Device Type" "SC70-5H44"
			(at 0 -9.6012 0)
			(unlocked yes)
			(layer "F.Fab")
			(hide yes)
			(effects
				(font
					(size 1.016 1.016)
					(thickness 0.1524)
				)
			)
		)
		(duplicate_pad_numbers_are_jumpers no)
		(fp_line
			(start -1.0033 -0.3302)
			(end 1.0033 -0.3302)
			(stroke
				(width 0.1524)
				(type default)
			)
			(layer "F.SilkS")
		)
		(fp_line
			(start -1.0033 0.3302)
			(end -1.0033 -0.3302)
			(stroke
				(width 0.1524)
				(type default)
			)
			(layer "F.SilkS")
		)
		(fp_line
			(start 1.0033 -0.3302)
			(end 1.0033 0.3302)
			(stroke
				(width 0.1524)
				(type default)
			)
			(layer "F.SilkS")
		)
		(fp_line
			(start 1.0033 0.3302)
			(end -1.0033 0.3302)
			(stroke
				(width 0.1524)
				(type default)
			)
			(layer "F.SilkS")
		)
		(fp_poly
			(pts
				(xy -1.0033 1.4859) (xy -1.0033 0.8001) (xy -1.1811 0.8001) (xy -1.1811 -0.8001) (xy -1.0033 -0.8001)
				(xy -1.0033 -1.4859) (xy 1.0033 -1.4859) (xy 1.0033 -0.8001) (xy 1.1811 -0.8001) (xy 1.1811 0.8001)
				(xy 1.0033 0.8001) (xy 1.0033 1.4859) (xy 0.2921 1.4859) (xy 0.2921 0.8001) (xy -0.2921 0.8001)
				(xy -0.2921 1.4859)
			)
			(stroke
				(width 0)
				(type default)
			)
			(fill no)
			(layer "F.CrtYd")
		)
		(fp_poly
			(pts
				(xy -1.0033 1.4859) (xy -1.0033 0.8001) (xy -1.1811 0.8001) (xy -1.1811 -0.8001) (xy -1.0033 -0.8001)
				(xy -1.0033 -1.4859) (xy 1.0033 -1.4859) (xy 1.0033 -0.8001) (xy 1.1811 -0.8001) (xy 1.1811 0.8001)
				(xy 1.0033 0.8001) (xy 1.0033 1.4859) (xy 0.2921 1.4859) (xy 0.2921 0.8001) (xy -0.2921 0.8001)
				(xy -0.2921 1.4859)
			)
			(stroke
				(width 0)
				(type default)
			)
			(fill no)
			(layer "F.Fab")
		)
		(pad "1" smd rect
			(at 0.65024 -0.93472)
			(size 0.3556 0.762)
			(layers "F.Cu" "F.Mask" "F.Paste")
			(net "Net_447")
		)
		(pad "2" smd rect
			(at 0 -0.93472)
			(size 0.3556 0.762)
			(layers "F.Cu" "F.Mask" "F.Paste")
			(net "P3V3_CPU_DELAY_IN")
		)
		(pad "3" smd rect
			(at -0.65024 -0.93472)
			(size 0.3556 0.762)
			(layers "F.Cu" "F.Mask" "F.Paste")
			(net "GND")
		)
		(pad "4" smd rect
			(at -0.65024 0.93472)
			(size 0.3556 0.762)
			(layers "F.Cu" "F.Mask" "F.Paste")
			(net "P3V3_CPU_PG_S1")
		)
		(pad "5" smd rect
			(at 0.65024 0.93472)
			(size 0.3556 0.762)
			(layers "F.Cu" "F.Mask" "F.Paste")
			(net "P3V3_STBY")
		)
	)
	(footprint ""
		(layer "F.Cu")
		(at 15.113 -69.215 90)
		(property "Reference" "R305"
			(at 0 0 90)
			(layer "F.SilkS")
			(hide yes)
			(effects
				(font
					(size 1.27 1.27)
				)
			)
		)
		(property "Value" "300R2F-GP"
			(at 1.7907 -1.1176 90)
			(unlocked yes)
			(layer "F.Fab")
			(hide yes)
			(effects
				(font
					(size 1.016 1.016)
					(thickness 0.1524)
				)
			)
		)
		(property "Device Type" "R402H16"
			(at 1.7907 -2.6416 90)
			(unlocked yes)
			(layer "F.Fab")
			(hide yes)
			(effects
				(font
					(size 1.016 1.016)
					(thickness 0.1524)
				)
			)
		)
		(duplicate_pad_numbers_are_jumpers no)
		(fp_rect
			(start -0.381 0.8382)
			(end 0.381 -0.8382)
			(stroke
				(width 0)
				(type default)
			)
			(fill no)
			(layer "F.CrtYd")
		)
		(fp_rect
			(start -0.381 0.8382)
			(end 0.381 -0.8382)
			(stroke
				(width 0)
				(type default)
			)
			(fill no)
			(layer "F.Fab")
		)
		(pad "1" smd custom
			(at 0 -0.4318 90)
			(size 0.127 0.127)
			(layers "F.Cu" "F.Mask" "F.Paste")
			(net "P3V3")
			(options
				(clearance outline)
				(anchor circle)
			)
			(primitives
				(gr_poly
					(pts
						(arc
							(start -0.2032 -0.2794)
							(mid -0.239121 -0.264521)
							(end -0.254 -0.2286)
						)
						(arc
							(start -0.254 0.2286)
							(mid -0.239121 0.264521)
							(end -0.2032 0.2794)
						)
						(arc
							(start 0.2032 0.2794)
							(mid 0.239121 0.264521)
							(end 0.254 0.2286)
						)
						(arc
							(start 0.254 -0.2286)
							(mid 0.239121 -0.264521)
							(end 0.2032 -0.2794)
						)
					)
					(width 0)
					(fill yes)
				)
			)
		)
		(pad "2" smd custom
			(at 0 0.4318 90)
			(size 0.127 0.127)
			(layers "F.Cu" "F.Mask" "F.Paste")
			(net "LED_NGFF_DAS_R")
			(options
				(clearance outline)
				(anchor circle)
			)
			(primitives
				(gr_poly
					(pts
						(arc
							(start -0.2032 -0.2794)
							(mid -0.239121 -0.264521)
							(end -0.254 -0.2286)
						)
						(arc
							(start -0.254 0.2286)
							(mid -0.239121 0.264521)
							(end -0.2032 0.2794)
						)
						(arc
							(start 0.2032 0.2794)
							(mid 0.239121 0.264521)
							(end 0.254 0.2286)
						)
						(arc
							(start 0.254 -0.2286)
							(mid 0.239121 -0.264521)
							(end 0.2032 -0.2794)
						)
					)
					(width 0)
					(fill yes)
				)
			)
		)
	)
	(footprint ""
		(layer "F.Cu")
		(at 57.404 -56.769)
		(property "Reference" "PC145"
			(at 0 0 0)
			(layer "F.SilkS")
			(hide yes)
			(effects
				(font
					(size 1.27 1.27)
				)
			)
		)
		(property "Value" "SC47U6D3V5MX-1-GP"
			(at -0.0762 -6.1214 0)
			(unlocked yes)
			(layer "F.Fab")
			(hide yes)
			(effects
				(font
					(size 1.016 1.016)
					(thickness 0.1524)
				)
			)
		)
		(property "Device Type" "C805H54"
			(at -0.0762 -8.1534 0)
			(unlocked yes)
			(layer "F.Fab")
			(hide yes)
			(effects
				(font
					(size 1.016 1.016)
					(thickness 0.1524)
				)
			)
		)
		(duplicate_pad_numbers_are_jumpers no)
		(fp_line
			(start 0.6096 0)
			(end -0.6096 0)
			(stroke
				(width 0.3048)
				(type default)
			)
			(layer "F.SilkS")
		)
		(fp_poly
			(pts
				(xy -0.9017 1.4351) (xy 0.9017 1.4351) (xy 0.9017 -1.4351) (xy -0.9017 -1.4351)
			)
			(stroke
				(width 0)
				(type default)
			)
			(fill no)
			(layer "F.CrtYd")
		)
		(fp_poly
			(pts
				(xy 0.9017 1.4351) (xy 0.9017 -1.4351) (xy -0.9017 -1.4351) (xy -0.9017 1.4351)
			)
			(stroke
				(width 0)
				(type default)
			)
			(fill no)
			(layer "F.Fab")
		)
		(pad "1" smd rect
			(at 0 -0.8382)
			(size 1.5494 0.9398)
			(layers "F.Cu" "F.Mask" "F.Paste")
			(net "PVCCP")
		)
		(pad "2" smd rect
			(at 0 0.8382)
			(size 1.5494 0.9398)
			(layers "F.Cu" "F.Mask" "F.Paste")
			(net "GND")
		)
	)
	(footprint ""
		(layer "F.Cu")
		(at 15.8496 -53.7972 -90)
		(property "Reference" "PR48"
			(at 0 0 270)
			(layer "F.SilkS")
			(hide yes)
			(effects
				(font
					(size 1.27 1.27)
				)
			)
		)
		(property "Value" "0R2J-2-GP"
			(at 1.7907 -1.1176 270)
			(unlocked yes)
			(layer "F.Fab")
			(hide yes)
			(effects
				(font
					(size 1.016 1.016)
					(thickness 0.1524)
				)
			)
		)
		(property "Device Type" "R402H16"
			(at 1.7907 -2.6416 270)
			(unlocked yes)
			(layer "F.Fab")
			(hide yes)
			(effects
				(font
					(size 1.016 1.016)
					(thickness 0.1524)
				)
			)
		)
		(duplicate_pad_numbers_are_jumpers no)
		(fp_rect
			(start -0.381 0.8382)
			(end 0.381 -0.8382)
			(stroke
				(width 0)
				(type default)
			)
			(fill no)
			(layer "F.CrtYd")
		)
		(fp_rect
			(start -0.381 0.8382)
			(end 0.381 -0.8382)
			(stroke
				(width 0)
				(type default)
			)
			(fill no)
			(layer "F.Fab")
		)
		(pad "1" smd custom
			(at 0 -0.4318 270)
			(size 0.127 0.127)
			(layers "F.Cu" "F.Mask" "F.Paste")
			(net "PVCCP_PVNN_R_VRHOT#")
			(options
				(clearance outline)
				(anchor circle)
			)
			(primitives
				(gr_poly
					(pts
						(arc
							(start -0.2032 -0.2794)
							(mid -0.239121 -0.264521)
							(end -0.254 -0.2286)
						)
						(arc
							(start -0.254 0.2286)
							(mid -0.239121 0.264521)
							(end -0.2032 0.2794)
						)
						(arc
							(start 0.2032 0.2794)
							(mid 0.239121 0.264521)
							(end 0.254 0.2286)
						)
						(arc
							(start 0.254 -0.2286)
							(mid 0.239121 -0.264521)
							(end 0.2032 -0.2794)
						)
					)
					(width 0)
					(fill yes)
				)
			)
		)
		(pad "2" smd custom
			(at 0 0.4318 270)
			(size 0.127 0.127)
			(layers "F.Cu" "F.Mask" "F.Paste")
			(net "PVCCP_PVNN_VRHOT#")
			(options
				(clearance outline)
				(anchor circle)
			)
			(primitives
				(gr_poly
					(pts
						(arc
							(start -0.2032 -0.2794)
							(mid -0.239121 -0.264521)
							(end -0.254 -0.2286)
						)
						(arc
							(start -0.254 0.2286)
							(mid -0.239121 0.264521)
							(end -0.2032 0.2794)
						)
						(arc
							(start 0.2032 0.2794)
							(mid 0.239121 0.264521)
							(end 0.254 0.2286)
						)
						(arc
							(start 0.254 -0.2286)
							(mid 0.239121 -0.264521)
							(end 0.2032 -0.2794)
						)
					)
					(width 0)
					(fill yes)
				)
			)
		)
	)
	(footprint ""
		(layer "F.Cu")
		(at 170.688 -33.655 -90)
		(property "Reference" "PU8"
			(at 0 0 270)
			(layer "F.SilkS")
			(hide yes)
			(effects
				(font
					(size 1.27 1.27)
				)
			)
		)
		(property "Value" "LD1117AG-12-AA3-A-R-GP"
			(at -0.0508 -10.3632 270)
			(unlocked yes)
			(layer "F.Fab")
			(hide yes)
			(effects
				(font
					(size 1.016 1.016)
					(thickness 0.1524)
				)
			)
		)
		(property "Device Type" "SOT-223H71"
			(at -0.1524 -12.3952 270)
			(unlocked yes)
			(layer "F.Fab")
			(hide yes)
			(effects
				(font
					(size 1.016 1.016)
					(thickness 0.1524)
				)
			)
		)
		(duplicate_pad_numbers_are_jumpers no)
		(fp_poly
			(pts
				(xy -2.3749 1.0922) (xy -1.9431 1.524) (xy -2.8067 1.524)
			)
			(stroke
				(width 0)
				(type default)
			)
			(fill yes)
			(layer "F.SilkS")
		)
		(fp_poly
			(pts
				(xy 3.048 1.0795) (xy 3.048 -0.8001) (xy 3.5052 -0.8001) (xy 3.5052 -4.8133) (xy 1.8796 -4.8133)
				(xy 1.8796 -6.6675) (xy -1.8796 -6.6675) (xy -1.8796 -4.8133) (xy -3.5052 -4.8133) (xy -3.5052 -0.8001)
				(xy -3.048 -0.8001) (xy -3.048 1.0795)
			)
			(stroke
				(width 0)
				(type default)
			)
			(fill no)
			(layer "F.CrtYd")
		)
		(fp_poly
			(pts
				(xy 3.048 1.0795) (xy 3.048 -0.5207) (xy 3.048 -0.6731) (xy 3.048 -0.8001) (xy 3.5052 -0.8001) (xy 3.5052 -4.6863)
				(xy 3.5052 -4.8133) (xy 1.905 -4.8133) (xy 1.8796 -4.8133) (xy 1.8796 -6.6675) (xy -1.8796 -6.6675)
				(xy -1.8796 -4.8133) (xy -1.905 -4.8133) (xy -3.5052 -4.8133) (xy -3.5052 -4.6863) (xy -3.5052 -0.8001)
				(xy -3.048 -0.8001) (xy -3.048 -0.6731) (xy -3.048 1.0795)
			)
			(stroke
				(width 0)
				(type default)
			)
			(fill no)
			(layer "F.Fab")
		)
		(pad "1" smd rect
			(at -2.286 0 270)
			(size 1.27 1.905)
			(layers "F.Cu" "F.Mask" "F.Paste")
			(net "GND")
		)
		(pad "2" smd custom
			(at 0 0 270)
			(size 0.8763 0.8763)
			(layers "F.Cu" "F.Mask" "F.Paste")
			(net "P1V2_STBY_LDO_OUT1")
			(options
				(clearance outline)
				(anchor circle)
			)
			(primitives
				(gr_poly
					(pts
						(xy 1.7526 -1.8415) (xy 0.381 -1.8415) (xy 0.381 1.8415) (xy 0.635 1.8415) (xy 0.635 3.7465) (xy -0.635 3.7465)
						(xy -0.635 1.8415) (xy -0.381 1.8415) (xy -0.381 -1.8415) (xy -1.7526 -1.8415) (xy -1.7526 -3.7465)
						(xy 1.7526 -3.7465)
					)
					(width 0)
					(fill yes)
				)
			)
		)
		(pad "3" smd rect
			(at 2.286 0 270)
			(size 1.27 1.905)
			(layers "F.Cu" "F.Mask" "F.Paste")
			(net "P1V8_STBY_LDO_IN1")
		)
	)
	(footprint ""
		(layer "F.Cu")
		(at 5.715 -39.6748 90)
		(property "Reference" "PL9"
			(at 0 0 90)
			(layer "F.SilkS")
			(hide yes)
			(effects
				(font
					(size 1.27 1.27)
				)
			)
		)
		(property "Value" "BLM21PG220SN1DGP"
			(at 0.0381 -2.7178 90)
			(unlocked yes)
			(layer "F.Fab")
			(hide yes)
			(effects
				(font
					(size 1.016 1.016)
					(thickness 0.1524)
				)
			)
		)
		(property "Device Type" "L20125H42"
			(at 0.0381 -4.2418 90)
			(unlocked yes)
			(layer "F.Fab")
			(hide yes)
			(effects
				(font
					(size 1.016 1.016)
					(thickness 0.1524)
				)
			)
		)
		(duplicate_pad_numbers_are_jumpers no)
		(fp_line
			(start 0.5461 -0.1397)
			(end -0.5461 -0.1397)
			(stroke
				(width 0.1524)
				(type default)
			)
			(layer "F.SilkS")
		)
		(fp_line
			(start -0.5461 -0.1397)
			(end -0.5461 0.1397)
			(stroke
				(width 0.1524)
				(type default)
			)
			(layer "F.SilkS")
		)
		(fp_line
			(start -0.5461 0)
			(end 0.5461 0)
			(stroke
				(width 0.1524)
				(type default)
			)
			(layer "F.SilkS")
		)
		(fp_line
			(start 0.5461 0.1397)
			(end 0.5461 -0.1397)
			(stroke
				(width 0.1524)
				(type default)
			)
			(layer "F.SilkS")
		)
		(fp_line
			(start -0.5461 0.1397)
			(end 0.5461 0.1397)
			(stroke
				(width 0.1524)
				(type default)
			)
			(layer "F.SilkS")
		)
		(fp_poly
			(pts
				(xy -0.8001 1.4351) (xy 0.8001 1.4351) (xy 0.8001 -1.4351) (xy -0.8001 -1.4351)
			)
			(stroke
				(width 0)
				(type default)
			)
			(fill no)
			(layer "F.CrtYd")
		)
		(fp_rect
			(start -0.8001 1.4351)
			(end 0.8001 -1.4351)
			(stroke
				(width 0)
				(type default)
			)
			(fill no)
			(layer "F.Fab")
		)
		(pad "1" smd rect
			(at 0 -0.8382 90)
			(size 1.3462 0.9398)
			(layers "F.Cu" "F.Mask" "F.Paste")
			(net "P12V")
		)
		(pad "2" smd rect
			(at 0 0.8382 90)
			(size 1.3462 0.9398)
			(layers "F.Cu" "F.Mask" "F.Paste")
			(net "P3V3_STBY_VIN")
		)
	)
	(footprint ""
		(layer "F.Cu")
		(at 160.401 -25.527)
		(property "Reference" "SW2"
			(at 0 0 0)
			(layer "F.SilkS")
			(hide yes)
			(effects
				(font
					(size 1.27 1.27)
				)
			)
		)
		(property "Value" "SW-DIP-2P-1-GP"
			(at -2.7178 -1.8796 0)
			(unlocked yes)
			(layer "F.Fab")
			(hide yes)
			(effects
				(font
					(size 1.016 1.016)
					(thickness 0.1524)
				)
			)
		)
		(property "Device Type" "EM-01-V"
			(at -2.7178 -3.4036 0)
			(unlocked yes)
			(layer "F.Fab")
			(hide yes)
			(effects
				(font
					(size 1.016 1.016)
					(thickness 0.1524)
				)
			)
		)
		(duplicate_pad_numbers_are_jumpers no)
		(fp_line
			(start 0 -2.286)
			(end 0 -2.794)
			(stroke
				(width 0.1524)
				(type default)
			)
			(layer "F.SilkS")
		)
		(fp_line
			(start 0 1.778)
			(end 0.635 -1.778)
			(stroke
				(width 0.1524)
				(type default)
			)
			(layer "F.SilkS")
		)
		(fp_line
			(start 0 2.286)
			(end 0 2.794)
			(stroke
				(width 0.1524)
				(type default)
			)
			(layer "F.SilkS")
		)
		(fp_circle
			(center 0 -2.032)
			(end 0.254 -2.032)
			(stroke
				(width 0.1524)
				(type default)
			)
			(fill no)
			(layer "F.SilkS")
		)
		(fp_circle
			(center 0 2.032)
			(end 0.254 2.032)
			(stroke
				(width 0.1524)
				(type default)
			)
			(fill no)
			(layer "F.SilkS")
		)
		(fp_poly
			(pts
				(xy -0.00889 -5.541264) (xy 0.62611 -6.176264) (xy -0.64389 -6.176264)
			)
			(stroke
				(width 0)
				(type default)
			)
			(fill yes)
			(layer "F.SilkS")
		)
		(fp_rect
			(start -1.4732 5.5372)
			(end 1.4732 -5.5372)
			(stroke
				(width 0)
				(type default)
			)
			(fill no)
			(layer "F.CrtYd")
		)
		(fp_rect
			(start -1.4732 5.5372)
			(end 1.4732 -5.5372)
			(stroke
				(width 0)
				(type default)
			)
			(fill no)
			(layer "F.Fab")
		)
		(pad "1" smd rect
			(at 0 -4.400042)
			(size 1.0922 2.0066)
			(layers "F.Cu" "F.Mask" "F.Paste")
			(net "DISABLE_H")
		)
		(pad "2" smd rect
			(at 0 4.400042)
			(size 1.0922 2.0066)
			(layers "F.Cu" "F.Mask" "F.Paste")
			(net "DISABLE")
		)
	)
	(footprint ""
		(layer "F.Cu")
		(at 142.748 -19.685)
		(property "Reference" "LED2"
			(at 0 0 0)
			(layer "F.SilkS")
			(hide yes)
			(effects
				(font
					(size 1.27 1.27)
				)
			)
		)
		(property "Value" "LED-YG-51-GP"
			(at -2.6924 -1.4224 0)
			(unlocked yes)
			(layer "F.Fab")
			(hide yes)
			(effects
				(font
					(size 1.016 1.016)
					(thickness 0.1524)
				)
			)
		)
		(property "Device Type" "LED1608AKH40"
			(at -2.6924 -2.9464 0)
			(unlocked yes)
			(layer "F.Fab")
			(hide yes)
			(effects
				(font
					(size 1.016 1.016)
					(thickness 0.1524)
				)
			)
		)
		(duplicate_pad_numbers_are_jumpers no)
		(fp_line
			(start -0.5334 1.3081)
			(end 0.5334 1.3081)
			(stroke
				(width 0.254)
				(type default)
			)
			(layer "F.SilkS")
		)
		(fp_rect
			(start -0.6604 1.1811)
			(end 0.6604 -1.1811)
			(stroke
				(width 0)
				(type default)
			)
			(fill no)
			(layer "F.CrtYd")
		)
		(fp_rect
			(start -0.6604 1.1811)
			(end 0.6604 -1.1811)
			(stroke
				(width 0)
				(type default)
			)
			(fill no)
			(layer "F.Fab")
		)
		(pad "A" smd rect
			(at 0 -0.652526)
			(size 1.0668 0.8128)
			(layers "F.Cu" "F.Mask" "F.Paste")
			(net "C_CONF_DONE")
		)
		(pad "K" smd rect
			(at 0 0.652526)
			(size 1.0668 0.8128)
			(layers "F.Cu" "F.Mask" "F.Paste")
			(net "GND")
		)
	)
	(footprint ""
		(layer "F.Cu")
		(at 182.753 -34.798 -90)
		(property "Reference" "PR138"
			(at 0 0 270)
			(layer "F.SilkS")
			(hide yes)
			(effects
				(font
					(size 1.27 1.27)
				)
			)
		)
		(property "Value" "10KR2F-2-GP"
			(at 1.7907 -1.1176 270)
			(unlocked yes)
			(layer "F.Fab")
			(hide yes)
			(effects
				(font
					(size 1.016 1.016)
					(thickness 0.1524)
				)
			)
		)
		(property "Device Type" "R402H16"
			(at 1.7907 -2.6416 270)
			(unlocked yes)
			(layer "F.Fab")
			(hide yes)
			(effects
				(font
					(size 1.016 1.016)
					(thickness 0.1524)
				)
			)
		)
		(duplicate_pad_numbers_are_jumpers no)
		(fp_rect
			(start -0.381 0.8382)
			(end 0.381 -0.8382)
			(stroke
				(width 0)
				(type default)
			)
			(fill no)
			(layer "F.CrtYd")
		)
		(fp_rect
			(start -0.381 0.8382)
			(end 0.381 -0.8382)
			(stroke
				(width 0)
				(type default)
			)
			(fill no)
			(layer "F.Fab")
		)
		(pad "1" smd custom
			(at 0 -0.4318 270)
			(size 0.127 0.127)
			(layers "F.Cu" "F.Mask" "F.Paste")
			(net "PWRGD_PVDDR_PG")
			(options
				(clearance outline)
				(anchor circle)
			)
			(primitives
				(gr_poly
					(pts
						(arc
							(start -0.2032 -0.2794)
							(mid -0.239121 -0.264521)
							(end -0.254 -0.2286)
						)
						(arc
							(start -0.254 0.2286)
							(mid -0.239121 0.264521)
							(end -0.2032 0.2794)
						)
						(arc
							(start 0.2032 0.2794)
							(mid 0.239121 0.264521)
							(end 0.254 0.2286)
						)
						(arc
							(start 0.254 -0.2286)
							(mid 0.239121 -0.264521)
							(end 0.2032 -0.2794)
						)
					)
					(width 0)
					(fill yes)
				)
			)
		)
		(pad "2" smd custom
			(at 0 0.4318 270)
			(size 0.127 0.127)
			(layers "F.Cu" "F.Mask" "F.Paste")
			(net "P3V3_STBY")
			(options
				(clearance outline)
				(anchor circle)
			)
			(primitives
				(gr_poly
					(pts
						(arc
							(start -0.2032 -0.2794)
							(mid -0.239121 -0.264521)
							(end -0.254 -0.2286)
						)
						(arc
							(start -0.254 0.2286)
							(mid -0.239121 0.264521)
							(end -0.2032 0.2794)
						)
						(arc
							(start 0.2032 0.2794)
							(mid 0.239121 0.264521)
							(end 0.254 0.2286)
						)
						(arc
							(start 0.254 -0.2286)
							(mid 0.239121 -0.264521)
							(end 0.2032 -0.2794)
						)
					)
					(width 0)
					(fill yes)
				)
			)
		)
	)
	(footprint ""
		(layer "F.Cu")
		(at 135.509 -18.796)
		(property "Reference" "R52"
			(at 0 0 0)
			(layer "F.SilkS")
			(hide yes)
			(effects
				(font
					(size 1.27 1.27)
				)
			)
		)
		(property "Value" "0R2J-2-GP"
			(at 0.064008 -3.993896 0)
			(unlocked yes)
			(layer "F.Fab")
			(hide yes)
			(effects
				(font
					(size 1.016 1.016)
					(thickness 0.1524)
				)
			)
		)
		(property "Device Type" "R402H16"
			(at 0.064008 -5.517896 0)
			(unlocked yes)
			(layer "F.Fab")
			(hide yes)
			(effects
				(font
					(size 1.016 1.016)
					(thickness 0.1524)
				)
			)
		)
		(duplicate_pad_numbers_are_jumpers no)
		(fp_rect
			(start -0.381 0.8382)
			(end 0.381 -0.8382)
			(stroke
				(width 0)
				(type default)
			)
			(fill no)
			(layer "F.CrtYd")
		)
		(fp_rect
			(start -0.381 0.8382)
			(end 0.381 -0.8382)
			(stroke
				(width 0)
				(type default)
			)
			(fill no)
			(layer "F.Fab")
		)
		(pad "1" smd custom
			(at 0 -0.4318)
			(size 0.127 0.127)
			(layers "F.Cu" "F.Mask" "F.Paste")
			(net "POWER_CONTROL")
			(options
				(clearance outline)
				(anchor circle)
			)
			(primitives
				(gr_poly
					(pts
						(arc
							(start -0.2032 -0.2794)
							(mid -0.239121 -0.264521)
							(end -0.254 -0.2286)
						)
						(arc
							(start -0.254 0.2286)
							(mid -0.239121 0.264521)
							(end -0.2032 0.2794)
						)
						(arc
							(start 0.2032 0.2794)
							(mid 0.239121 0.264521)
							(end 0.254 0.2286)
						)
						(arc
							(start 0.254 -0.2286)
							(mid 0.239121 -0.264521)
							(end 0.2032 -0.2794)
						)
					)
					(width 0)
					(fill yes)
				)
			)
		)
		(pad "2" smd custom
			(at 0 0.4318)
			(size 0.127 0.127)
			(layers "F.Cu" "F.Mask" "F.Paste")
			(net "FPGA_PWRBTN#")
			(options
				(clearance outline)
				(anchor circle)
			)
			(primitives
				(gr_poly
					(pts
						(arc
							(start -0.2032 -0.2794)
							(mid -0.239121 -0.264521)
							(end -0.254 -0.2286)
						)
						(arc
							(start -0.254 0.2286)
							(mid -0.239121 0.264521)
							(end -0.2032 0.2794)
						)
						(arc
							(start 0.2032 0.2794)
							(mid 0.239121 0.264521)
							(end 0.254 0.2286)
						)
						(arc
							(start 0.254 -0.2286)
							(mid 0.239121 -0.264521)
							(end 0.2032 -0.2794)
						)
					)
					(width 0)
					(fill yes)
				)
			)
		)
	)
	(footprint ""
		(layer "F.Cu")
		(at 73.66 -27.178 -90)
		(property "Reference" "R352"
			(at 0 0 270)
			(layer "F.SilkS")
			(hide yes)
			(effects
				(font
					(size 1.27 1.27)
				)
			)
		)
		(property "Value" "0R2J-2-GP"
			(at 0.064008 -3.993896 270)
			(unlocked yes)
			(layer "F.Fab")
			(hide yes)
			(effects
				(font
					(size 1.016 1.016)
					(thickness 0.1524)
				)
			)
		)
		(property "Device Type" "R402H16"
			(at 0.064008 -5.517896 270)
			(unlocked yes)
			(layer "F.Fab")
			(hide yes)
			(effects
				(font
					(size 1.016 1.016)
					(thickness 0.1524)
				)
			)
		)
		(duplicate_pad_numbers_are_jumpers no)
		(fp_rect
			(start -0.381 0.8382)
			(end 0.381 -0.8382)
			(stroke
				(width 0)
				(type default)
			)
			(fill no)
			(layer "F.CrtYd")
		)
		(fp_rect
			(start -0.381 0.8382)
			(end 0.381 -0.8382)
			(stroke
				(width 0)
				(type default)
			)
			(fill no)
			(layer "F.Fab")
		)
		(pad "1" smd custom
			(at 0 -0.4318 270)
			(size 0.127 0.127)
			(layers "F.Cu" "F.Mask" "F.Paste")
			(net "CPU_RSMRST_R#")
			(options
				(clearance outline)
				(anchor circle)
			)
			(primitives
				(gr_poly
					(pts
						(arc
							(start -0.2032 -0.2794)
							(mid -0.239121 -0.264521)
							(end -0.254 -0.2286)
						)
						(arc
							(start -0.254 0.2286)
							(mid -0.239121 0.264521)
							(end -0.2032 0.2794)
						)
						(arc
							(start 0.2032 0.2794)
							(mid 0.239121 0.264521)
							(end 0.254 0.2286)
						)
						(arc
							(start 0.254 -0.2286)
							(mid 0.239121 -0.264521)
							(end 0.2032 -0.2794)
						)
					)
					(width 0)
					(fill yes)
				)
			)
		)
		(pad "2" smd custom
			(at 0 0.4318 270)
			(size 0.127 0.127)
			(layers "F.Cu" "F.Mask" "F.Paste")
			(net "CPU_RSMRST#")
			(options
				(clearance outline)
				(anchor circle)
			)
			(primitives
				(gr_poly
					(pts
						(arc
							(start -0.2032 -0.2794)
							(mid -0.239121 -0.264521)
							(end -0.254 -0.2286)
						)
						(arc
							(start -0.254 0.2286)
							(mid -0.239121 0.264521)
							(end -0.2032 0.2794)
						)
						(arc
							(start 0.2032 0.2794)
							(mid 0.239121 0.264521)
							(end 0.254 0.2286)
						)
						(arc
							(start 0.254 -0.2286)
							(mid 0.239121 -0.264521)
							(end 0.2032 -0.2794)
						)
					)
					(width 0)
					(fill yes)
				)
			)
		)
	)
	(footprint ""
		(layer "F.Cu")
		(at 19.5834 -67.1576 180)
		(property "Reference" "PC17"
			(at 0 0 180)
			(layer "F.SilkS")
			(hide yes)
			(effects
				(font
					(size 1.27 1.27)
				)
			)
		)
		(property "Value" "SCD022U16V2KX-3GP"
			(at 1.8923 -1.2065 180)
			(unlocked yes)
			(layer "F.Fab")
			(hide yes)
			(effects
				(font
					(size 1.016 1.016)
					(thickness 0.1524)
				)
			)
		)
		(property "Device Type" "C402H22"
			(at 1.8923 -2.7305 180)
			(unlocked yes)
			(layer "F.Fab")
			(hide yes)
			(effects
				(font
					(size 1.016 1.016)
					(thickness 0.1524)
				)
			)
		)
		(duplicate_pad_numbers_are_jumpers no)
		(fp_rect
			(start -0.381 0.7366)
			(end 0.381 -0.7366)
			(stroke
				(width 0)
				(type default)
			)
			(fill no)
			(layer "F.CrtYd")
		)
		(fp_rect
			(start -0.381 0.7366)
			(end 0.381 -0.7366)
			(stroke
				(width 0)
				(type default)
			)
			(fill no)
			(layer "F.Fab")
		)
		(pad "1" smd custom
			(at 0 -0.4572 180)
			(size 0.1143 0.1143)
			(layers "F.Cu" "F.Mask" "F.Paste")
			(net "VR_PVNN_ISUMN")
			(options
				(clearance outline)
				(anchor circle)
			)
			(primitives
				(gr_poly
					(pts
						(arc
							(start -0.254 -0.1778)
							(mid -0.239121 -0.213721)
							(end -0.2032 -0.2286)
						)
						(arc
							(start 0.2032 -0.2286)
							(mid 0.239121 -0.213721)
							(end 0.254 -0.1778)
						)
						(arc
							(start 0.254 0.1778)
							(mid 0.239121 0.213721)
							(end 0.2032 0.2286)
						)
						(arc
							(start -0.2032 0.2286)
							(mid -0.239121 0.213721)
							(end -0.254 0.1778)
						)
					)
					(width 0)
					(fill yes)
				)
			)
		)
		(pad "2" smd custom
			(at 0 0.4572 180)
			(size 0.1143 0.1143)
			(layers "F.Cu" "F.Mask" "F.Paste")
			(net "VR_PVNN_ISUMP")
			(options
				(clearance outline)
				(anchor circle)
			)
			(primitives
				(gr_poly
					(pts
						(arc
							(start -0.254 -0.1778)
							(mid -0.239121 -0.213721)
							(end -0.2032 -0.2286)
						)
						(arc
							(start 0.2032 -0.2286)
							(mid 0.239121 -0.213721)
							(end 0.254 -0.1778)
						)
						(arc
							(start 0.254 0.1778)
							(mid 0.239121 0.213721)
							(end 0.2032 0.2286)
						)
						(arc
							(start -0.2032 0.2286)
							(mid -0.239121 0.213721)
							(end -0.254 0.1778)
						)
					)
					(width 0)
					(fill yes)
				)
			)
		)
	)
	(footprint ""
		(layer "F.Cu")
		(at 53.721 -68.072 180)
		(property "Reference" "PC31"
			(at 0 0 180)
			(layer "F.SilkS")
			(hide yes)
			(effects
				(font
					(size 1.27 1.27)
				)
			)
		)
		(property "Value" "SC47U6D3V5MX-1-GP"
			(at 0 -4.9022 180)
			(unlocked yes)
			(layer "F.Fab")
			(hide yes)
			(effects
				(font
					(size 1.016 1.016)
					(thickness 0.1524)
				)
			)
		)
		(property "Device Type" "C805H54"
			(at 0 -6.8072 180)
			(unlocked yes)
			(layer "F.Fab")
			(hide yes)
			(effects
				(font
					(size 1.016 1.016)
					(thickness 0.1524)
				)
			)
		)
		(duplicate_pad_numbers_are_jumpers no)
		(fp_line
			(start 0.6096 0)
			(end -0.6096 0)
			(stroke
				(width 0.3048)
				(type default)
			)
			(layer "F.SilkS")
		)
		(fp_poly
			(pts
				(xy -0.9017 1.4351) (xy 0.9017 1.4351) (xy 0.9017 -1.4351) (xy -0.9017 -1.4351)
			)
			(stroke
				(width 0)
				(type default)
			)
			(fill no)
			(layer "F.CrtYd")
		)
		(fp_poly
			(pts
				(xy 0.9017 1.4351) (xy 0.9017 -1.4351) (xy -0.9017 -1.4351) (xy -0.9017 1.4351)
			)
			(stroke
				(width 0)
				(type default)
			)
			(fill no)
			(layer "F.Fab")
		)
		(pad "1" smd rect
			(at 0 -0.8382 180)
			(size 1.5494 0.9398)
			(layers "F.Cu" "F.Mask" "F.Paste")
			(net "PVNN")
		)
		(pad "2" smd rect
			(at 0 0.8382 180)
			(size 1.5494 0.9398)
			(layers "F.Cu" "F.Mask" "F.Paste")
			(net "GND")
		)
	)
	(footprint ""
		(layer "F.Cu")
		(at 161.925 -59.309)
		(property "Reference" "C367"
			(at 0 0 0)
			(layer "F.SilkS")
			(hide yes)
			(effects
				(font
					(size 1.27 1.27)
				)
			)
		)
		(property "Value" "SC47U6D3V5MX-1-GP"
			(at 0 -4.9022 0)
			(unlocked yes)
			(layer "F.Fab")
			(hide yes)
			(effects
				(font
					(size 1.016 1.016)
					(thickness 0.1524)
				)
			)
		)
		(property "Device Type" "C805H54"
			(at 0 -6.8072 0)
			(unlocked yes)
			(layer "F.Fab")
			(hide yes)
			(effects
				(font
					(size 1.016 1.016)
					(thickness 0.1524)
				)
			)
		)
		(duplicate_pad_numbers_are_jumpers no)
		(fp_line
			(start 0.6096 0)
			(end -0.6096 0)
			(stroke
				(width 0.3048)
				(type default)
			)
			(layer "F.SilkS")
		)
		(fp_poly
			(pts
				(xy -0.9017 1.4351) (xy 0.9017 1.4351) (xy 0.9017 -1.4351) (xy -0.9017 -1.4351)
			)
			(stroke
				(width 0)
				(type default)
			)
			(fill no)
			(layer "F.CrtYd")
		)
		(fp_poly
			(pts
				(xy 0.9017 1.4351) (xy 0.9017 -1.4351) (xy -0.9017 -1.4351) (xy -0.9017 1.4351)
			)
			(stroke
				(width 0)
				(type default)
			)
			(fill no)
			(layer "F.Fab")
		)
		(pad "1" smd rect
			(at 0 -0.8382)
			(size 1.5494 0.9398)
			(layers "F.Cu" "F.Mask" "F.Paste")
			(net "PV_VDDR")
		)
		(pad "2" smd rect
			(at 0 0.8382)
			(size 1.5494 0.9398)
			(layers "F.Cu" "F.Mask" "F.Paste")
			(net "GND")
		)
	)
	(footprint ""
		(layer "F.Cu")
		(at 15.8496 -60.6552 -90)
		(property "Reference" "PR40"
			(at 0 0 270)
			(layer "F.SilkS")
			(hide yes)
			(effects
				(font
					(size 1.27 1.27)
				)
			)
		)
		(property "Value" "10D7R2F-GP"
			(at 1.7907 -1.1176 270)
			(unlocked yes)
			(layer "F.Fab")
			(hide yes)
			(effects
				(font
					(size 1.016 1.016)
					(thickness 0.1524)
				)
			)
		)
		(property "Device Type" "R402H16"
			(at 1.7907 -2.6416 270)
			(unlocked yes)
			(layer "F.Fab")
			(hide yes)
			(effects
				(font
					(size 1.016 1.016)
					(thickness 0.1524)
				)
			)
		)
		(duplicate_pad_numbers_are_jumpers no)
		(fp_rect
			(start -0.381 0.8382)
			(end 0.381 -0.8382)
			(stroke
				(width 0)
				(type default)
			)
			(fill no)
			(layer "F.CrtYd")
		)
		(fp_rect
			(start -0.381 0.8382)
			(end 0.381 -0.8382)
			(stroke
				(width 0)
				(type default)
			)
			(fill no)
			(layer "F.Fab")
		)
		(pad "1" smd custom
			(at 0 -0.4318 270)
			(size 0.127 0.127)
			(layers "F.Cu" "F.Mask" "F.Paste")
			(net "VR_95831_SDA")
			(options
				(clearance outline)
				(anchor circle)
			)
			(primitives
				(gr_poly
					(pts
						(arc
							(start -0.2032 -0.2794)
							(mid -0.239121 -0.264521)
							(end -0.254 -0.2286)
						)
						(arc
							(start -0.254 0.2286)
							(mid -0.239121 0.264521)
							(end -0.2032 0.2794)
						)
						(arc
							(start 0.2032 0.2794)
							(mid 0.239121 0.264521)
							(end 0.254 0.2286)
						)
						(arc
							(start 0.254 -0.2286)
							(mid 0.239121 -0.264521)
							(end 0.2032 -0.2794)
						)
					)
					(width 0)
					(fill yes)
				)
			)
		)
		(pad "2" smd custom
			(at 0 0.4318 270)
			(size 0.127 0.127)
			(layers "F.Cu" "F.Mask" "F.Paste")
			(net "SVID_CPU_DATA")
			(options
				(clearance outline)
				(anchor circle)
			)
			(primitives
				(gr_poly
					(pts
						(arc
							(start -0.2032 -0.2794)
							(mid -0.239121 -0.264521)
							(end -0.254 -0.2286)
						)
						(arc
							(start -0.254 0.2286)
							(mid -0.239121 0.264521)
							(end -0.2032 0.2794)
						)
						(arc
							(start 0.2032 0.2794)
							(mid 0.239121 0.264521)
							(end 0.254 0.2286)
						)
						(arc
							(start 0.254 -0.2286)
							(mid 0.239121 -0.264521)
							(end 0.2032 -0.2794)
						)
					)
					(width 0)
					(fill yes)
				)
			)
		)
	)
	(footprint ""
		(layer "F.Cu")
		(at 28.067 -58.0136 -90)
		(property "Reference" "PR44"
			(at 0 0 270)
			(layer "F.SilkS")
			(hide yes)
			(effects
				(font
					(size 1.27 1.27)
				)
			)
		)
		(property "Value" "0R2J-2-GP"
			(at 1.7907 -1.1176 270)
			(unlocked yes)
			(layer "F.Fab")
			(hide yes)
			(effects
				(font
					(size 1.016 1.016)
					(thickness 0.1524)
				)
			)
		)
		(property "Device Type" "R402H16"
			(at 1.7907 -2.6416 270)
			(unlocked yes)
			(layer "F.Fab")
			(hide yes)
			(effects
				(font
					(size 1.016 1.016)
					(thickness 0.1524)
				)
			)
		)
		(duplicate_pad_numbers_are_jumpers no)
		(fp_rect
			(start -0.381 0.8382)
			(end 0.381 -0.8382)
			(stroke
				(width 0)
				(type default)
			)
			(fill no)
			(layer "F.CrtYd")
		)
		(fp_rect
			(start -0.381 0.8382)
			(end 0.381 -0.8382)
			(stroke
				(width 0)
				(type default)
			)
			(fill no)
			(layer "F.Fab")
		)
		(pad "1" smd custom
			(at 0 -0.4318 270)
			(size 0.127 0.127)
			(layers "F.Cu" "F.Mask" "F.Paste")
			(net "VR_PVCCP_PVNN_VDD")
			(options
				(clearance outline)
				(anchor circle)
			)
			(primitives
				(gr_poly
					(pts
						(arc
							(start -0.2032 -0.2794)
							(mid -0.239121 -0.264521)
							(end -0.254 -0.2286)
						)
						(arc
							(start -0.254 0.2286)
							(mid -0.239121 0.264521)
							(end -0.2032 0.2794)
						)
						(arc
							(start 0.2032 0.2794)
							(mid 0.239121 0.264521)
							(end 0.254 0.2286)
						)
						(arc
							(start 0.254 -0.2286)
							(mid 0.239121 -0.264521)
							(end 0.2032 -0.2794)
						)
					)
					(width 0)
					(fill yes)
				)
			)
		)
		(pad "2" smd custom
			(at 0 0.4318 270)
			(size 0.127 0.127)
			(layers "F.Cu" "F.Mask" "F.Paste")
			(net "VR_PVCCP_PWM3")
			(options
				(clearance outline)
				(anchor circle)
			)
			(primitives
				(gr_poly
					(pts
						(arc
							(start -0.2032 -0.2794)
							(mid -0.239121 -0.264521)
							(end -0.254 -0.2286)
						)
						(arc
							(start -0.254 0.2286)
							(mid -0.239121 0.264521)
							(end -0.2032 0.2794)
						)
						(arc
							(start 0.2032 0.2794)
							(mid 0.239121 0.264521)
							(end 0.254 0.2286)
						)
						(arc
							(start 0.254 -0.2286)
							(mid 0.239121 -0.264521)
							(end 0.2032 -0.2794)
						)
					)
					(width 0)
					(fill yes)
				)
			)
		)
	)
	(footprint ""
		(layer "F.Cu")
		(at 117.475 -64.389 180)
		(property "Reference" "R225"
			(at 0 0 180)
			(layer "F.SilkS")
			(hide yes)
			(effects
				(font
					(size 1.27 1.27)
				)
			)
		)
		(property "Value" "0R2J-2-GP"
			(at 0.064008 -3.993896 180)
			(unlocked yes)
			(layer "F.Fab")
			(hide yes)
			(effects
				(font
					(size 1.016 1.016)
					(thickness 0.1524)
				)
			)
		)
		(property "Device Type" "R402H16"
			(at 0.064008 -5.517896 180)
			(unlocked yes)
			(layer "F.Fab")
			(hide yes)
			(effects
				(font
					(size 1.016 1.016)
					(thickness 0.1524)
				)
			)
		)
		(duplicate_pad_numbers_are_jumpers no)
		(fp_rect
			(start -0.381 0.8382)
			(end 0.381 -0.8382)
			(stroke
				(width 0)
				(type default)
			)
			(fill no)
			(layer "F.CrtYd")
		)
		(fp_rect
			(start -0.381 0.8382)
			(end 0.381 -0.8382)
			(stroke
				(width 0)
				(type default)
			)
			(fill no)
			(layer "F.Fab")
		)
		(pad "1" smd custom
			(at 0 -0.4318 180)
			(size 0.127 0.127)
			(layers "F.Cu" "F.Mask" "F.Paste")
			(net "SMB_M_A1_R_DATA")
			(options
				(clearance outline)
				(anchor circle)
			)
			(primitives
				(gr_poly
					(pts
						(arc
							(start -0.2032 -0.2794)
							(mid -0.239121 -0.264521)
							(end -0.254 -0.2286)
						)
						(arc
							(start -0.254 0.2286)
							(mid -0.239121 0.264521)
							(end -0.2032 0.2794)
						)
						(arc
							(start 0.2032 0.2794)
							(mid 0.239121 0.264521)
							(end 0.254 0.2286)
						)
						(arc
							(start 0.254 -0.2286)
							(mid 0.239121 -0.264521)
							(end 0.2032 -0.2794)
						)
					)
					(width 0)
					(fill yes)
				)
			)
		)
		(pad "2" smd custom
			(at 0 0.4318 180)
			(size 0.127 0.127)
			(layers "F.Cu" "F.Mask" "F.Paste")
			(net "SMB_HOST_LV_DATA")
			(options
				(clearance outline)
				(anchor circle)
			)
			(primitives
				(gr_poly
					(pts
						(arc
							(start -0.2032 -0.2794)
							(mid -0.239121 -0.264521)
							(end -0.254 -0.2286)
						)
						(arc
							(start -0.254 0.2286)
							(mid -0.239121 0.264521)
							(end -0.2032 0.2794)
						)
						(arc
							(start 0.2032 0.2794)
							(mid 0.239121 0.264521)
							(end 0.254 0.2286)
						)
						(arc
							(start 0.254 -0.2286)
							(mid 0.239121 -0.264521)
							(end 0.2032 -0.2794)
						)
					)
					(width 0)
					(fill yes)
				)
			)
		)
	)
	(footprint ""
		(layer "F.Cu")
		(at 111.506 -20.193 -90)
		(property "Reference" "R161"
			(at 0 0 270)
			(layer "F.SilkS")
			(hide yes)
			(effects
				(font
					(size 1.27 1.27)
				)
			)
		)
		(property "Value" "100R2F-L1-GP-U"
			(at 0.064008 -3.993896 270)
			(unlocked yes)
			(layer "F.Fab")
			(hide yes)
			(effects
				(font
					(size 1.016 1.016)
					(thickness 0.1524)
				)
			)
		)
		(property "Device Type" "R402H14"
			(at 0.064008 -5.517896 270)
			(unlocked yes)
			(layer "F.Fab")
			(hide yes)
			(effects
				(font
					(size 1.016 1.016)
					(thickness 0.1524)
				)
			)
		)
		(duplicate_pad_numbers_are_jumpers no)
		(fp_rect
			(start -0.381 0.8382)
			(end 0.381 -0.8382)
			(stroke
				(width 0)
				(type default)
			)
			(fill no)
			(layer "F.CrtYd")
		)
		(fp_rect
			(start -0.381 0.8382)
			(end 0.381 -0.8382)
			(stroke
				(width 0)
				(type default)
			)
			(fill no)
			(layer "F.Fab")
		)
		(pad "1" smd custom
			(at 0 -0.4318 270)
			(size 0.127 0.127)
			(layers "F.Cu" "F.Mask" "F.Paste")
			(net "M_B_MON1_P")
			(options
				(clearance outline)
				(anchor circle)
			)
			(primitives
				(gr_poly
					(pts
						(arc
							(start -0.2032 -0.2794)
							(mid -0.239121 -0.264521)
							(end -0.254 -0.2286)
						)
						(arc
							(start -0.254 0.2286)
							(mid -0.239121 0.264521)
							(end -0.2032 0.2794)
						)
						(arc
							(start 0.2032 0.2794)
							(mid 0.239121 0.264521)
							(end 0.254 0.2286)
						)
						(arc
							(start 0.254 -0.2286)
							(mid 0.239121 -0.264521)
							(end 0.2032 -0.2794)
						)
					)
					(width 0)
					(fill yes)
				)
			)
		)
		(pad "2" smd custom
			(at 0 0.4318 270)
			(size 0.127 0.127)
			(layers "F.Cu" "F.Mask" "F.Paste")
			(net "M_B_MON1_N")
			(options
				(clearance outline)
				(anchor circle)
			)
			(primitives
				(gr_poly
					(pts
						(arc
							(start -0.2032 -0.2794)
							(mid -0.239121 -0.264521)
							(end -0.254 -0.2286)
						)
						(arc
							(start -0.254 0.2286)
							(mid -0.239121 0.264521)
							(end -0.2032 0.2794)
						)
						(arc
							(start 0.2032 0.2794)
							(mid 0.239121 0.264521)
							(end 0.254 0.2286)
						)
						(arc
							(start 0.254 -0.2286)
							(mid 0.239121 -0.264521)
							(end 0.2032 -0.2794)
						)
					)
					(width 0)
					(fill yes)
				)
			)
		)
	)
	(footprint ""
		(layer "F.Cu")
		(at 157.48 -23.876)
		(property "Reference" "TP62"
			(at 0 0 0)
			(layer "F.SilkS")
			(hide yes)
			(effects
				(font
					(size 1.27 1.27)
				)
			)
		)
		(property "Value" "TPAD28-1-GP-U"
			(at 0.0508 -1.9304 0)
			(unlocked yes)
			(layer "F.Fab")
			(hide yes)
			(effects
				(font
					(size 1.016 1.016)
					(thickness 0.1524)
				)
			)
		)
		(property "Device Type" "TPAD28-1-U"
			(at 0.0508 -3.4544 0)
			(unlocked yes)
			(layer "F.Fab")
			(hide yes)
			(effects
				(font
					(size 1.016 1.016)
					(thickness 0.1524)
				)
			)
		)
		(duplicate_pad_numbers_are_jumpers no)
		(fp_poly
			(pts
				(arc
					(start 0.3556 0)
					(mid -0.3556 0)
					(end 0.3556 0)
				)
			)
			(stroke
				(width 0)
				(type default)
			)
			(fill no)
			(layer "F.CrtYd")
		)
		(fp_poly
			(pts
				(arc
					(start 0.9525 0)
					(mid -0.9525 0)
					(end 0.9525 0)
				)
			)
			(stroke
				(width 0)
				(type default)
			)
			(fill no)
			(layer "F.Fab")
		)
		(pad "1" smd circle
			(at 0 0)
			(size 0.7112 0.7112)
			(layers "F.Cu" "F.Mask" "F.Paste")
			(net "TP_FPGA_P112")
		)
	)
	(footprint ""
		(layer "F.Cu")
		(at 18.542 -33.147)
		(property "Reference" "PC174"
			(at 0 0 0)
			(layer "F.SilkS")
			(hide yes)
			(effects
				(font
					(size 1.27 1.27)
				)
			)
		)
		(property "Value" "SC1KP50V2KX-1GP"
			(at 1.8923 -1.2065 0)
			(unlocked yes)
			(layer "F.Fab")
			(hide yes)
			(effects
				(font
					(size 1.016 1.016)
					(thickness 0.1524)
				)
			)
		)
		(property "Device Type" "C402H22"
			(at 1.8923 -2.7305 0)
			(unlocked yes)
			(layer "F.Fab")
			(hide yes)
			(effects
				(font
					(size 1.016 1.016)
					(thickness 0.1524)
				)
			)
		)
		(duplicate_pad_numbers_are_jumpers no)
		(fp_rect
			(start -0.381 0.7366)
			(end 0.381 -0.7366)
			(stroke
				(width 0)
				(type default)
			)
			(fill no)
			(layer "F.CrtYd")
		)
		(fp_rect
			(start -0.381 0.7366)
			(end 0.381 -0.7366)
			(stroke
				(width 0)
				(type default)
			)
			(fill no)
			(layer "F.Fab")
		)
		(pad "1" smd custom
			(at 0 -0.4572)
			(size 0.1143 0.1143)
			(layers "F.Cu" "F.Mask" "F.Paste")
			(net "P3V3_STBY_LL_R")
			(options
				(clearance outline)
				(anchor circle)
			)
			(primitives
				(gr_poly
					(pts
						(arc
							(start -0.254 -0.1778)
							(mid -0.239121 -0.213721)
							(end -0.2032 -0.2286)
						)
						(arc
							(start 0.2032 -0.2286)
							(mid 0.239121 -0.213721)
							(end 0.254 -0.1778)
						)
						(arc
							(start 0.254 0.1778)
							(mid 0.239121 0.213721)
							(end 0.2032 0.2286)
						)
						(arc
							(start -0.2032 0.2286)
							(mid -0.239121 0.213721)
							(end -0.254 0.1778)
						)
					)
					(width 0)
					(fill yes)
				)
			)
		)
		(pad "2" smd custom
			(at 0 0.4572)
			(size 0.1143 0.1143)
			(layers "F.Cu" "F.Mask" "F.Paste")
			(net "P3V3_STBY_VFB")
			(options
				(clearance outline)
				(anchor circle)
			)
			(primitives
				(gr_poly
					(pts
						(arc
							(start -0.254 -0.1778)
							(mid -0.239121 -0.213721)
							(end -0.2032 -0.2286)
						)
						(arc
							(start 0.2032 -0.2286)
							(mid 0.239121 -0.213721)
							(end 0.254 -0.1778)
						)
						(arc
							(start 0.254 0.1778)
							(mid 0.239121 0.213721)
							(end 0.2032 0.2286)
						)
						(arc
							(start -0.2032 0.2286)
							(mid -0.239121 0.213721)
							(end -0.254 0.1778)
						)
					)
					(width 0)
					(fill yes)
				)
			)
		)
	)
	(footprint ""
		(layer "F.Cu")
		(at 114.808 -71.12)
		(property "Reference" "R229"
			(at 0 0 0)
			(layer "F.SilkS")
			(hide yes)
			(effects
				(font
					(size 1.27 1.27)
				)
			)
		)
		(property "Value" "4K7R2F-GP"
			(at 0.064008 -3.993896 0)
			(unlocked yes)
			(layer "F.Fab")
			(hide yes)
			(effects
				(font
					(size 1.016 1.016)
					(thickness 0.1524)
				)
			)
		)
		(property "Device Type" "R402H16"
			(at 0.064008 -5.517896 0)
			(unlocked yes)
			(layer "F.Fab")
			(hide yes)
			(effects
				(font
					(size 1.016 1.016)
					(thickness 0.1524)
				)
			)
		)
		(duplicate_pad_numbers_are_jumpers no)
		(fp_rect
			(start -0.381 0.8382)
			(end 0.381 -0.8382)
			(stroke
				(width 0)
				(type default)
			)
			(fill no)
			(layer "F.CrtYd")
		)
		(fp_rect
			(start -0.381 0.8382)
			(end 0.381 -0.8382)
			(stroke
				(width 0)
				(type default)
			)
			(fill no)
			(layer "F.Fab")
		)
		(pad "1" smd custom
			(at 0 -0.4318)
			(size 0.127 0.127)
			(layers "F.Cu" "F.Mask" "F.Paste")
			(net "CHA_1_SA1")
			(options
				(clearance outline)
				(anchor circle)
			)
			(primitives
				(gr_poly
					(pts
						(arc
							(start -0.2032 -0.2794)
							(mid -0.239121 -0.264521)
							(end -0.254 -0.2286)
						)
						(arc
							(start -0.254 0.2286)
							(mid -0.239121 0.264521)
							(end -0.2032 0.2794)
						)
						(arc
							(start 0.2032 0.2794)
							(mid 0.239121 0.264521)
							(end 0.254 0.2286)
						)
						(arc
							(start 0.254 -0.2286)
							(mid 0.239121 -0.264521)
							(end 0.2032 -0.2794)
						)
					)
					(width 0)
					(fill yes)
				)
			)
		)
		(pad "2" smd custom
			(at 0 0.4318)
			(size 0.127 0.127)
			(layers "F.Cu" "F.Mask" "F.Paste")
			(net "GND")
			(options
				(clearance outline)
				(anchor circle)
			)
			(primitives
				(gr_poly
					(pts
						(arc
							(start -0.2032 -0.2794)
							(mid -0.239121 -0.264521)
							(end -0.254 -0.2286)
						)
						(arc
							(start -0.254 0.2286)
							(mid -0.239121 0.264521)
							(end -0.2032 0.2794)
						)
						(arc
							(start 0.2032 0.2794)
							(mid 0.239121 0.264521)
							(end 0.254 0.2286)
						)
						(arc
							(start 0.254 -0.2286)
							(mid 0.239121 -0.264521)
							(end 0.2032 -0.2794)
						)
					)
					(width 0)
					(fill yes)
				)
			)
		)
	)
	(footprint ""
		(layer "F.Cu")
		(at 142.748 -21.59 180)
		(property "Reference" "TP42"
			(at 0 0 180)
			(layer "F.SilkS")
			(hide yes)
			(effects
				(font
					(size 1.27 1.27)
				)
			)
		)
		(property "Value" "TPAD32-GP"
			(at 0 -3.166364 180)
			(unlocked yes)
			(layer "F.Fab")
			(hide yes)
			(effects
				(font
					(size 1.016 1.016)
					(thickness 0.1524)
				)
			)
		)
		(property "Device Type" "TPAD32"
			(at 0 -4.690618 180)
			(unlocked yes)
			(layer "F.Fab")
			(hide yes)
			(effects
				(font
					(size 1.016 1.016)
					(thickness 0.1524)
				)
			)
		)
		(duplicate_pad_numbers_are_jumpers no)
		(fp_poly
			(pts
				(arc
					(start -0.7112 0)
					(mid 0.7112 0)
					(end -0.7112 0)
				)
			)
			(stroke
				(width 0)
				(type default)
			)
			(fill no)
			(layer "F.CrtYd")
		)
		(fp_poly
			(pts
				(arc
					(start -0.7112 0)
					(mid 0.7112 0)
					(end -0.7112 0)
				)
			)
			(stroke
				(width 0)
				(type default)
			)
			(fill no)
			(layer "F.Fab")
		)
		(pad "1" smd circle
			(at 0 0 180)
			(size 0.8128 0.8128)
			(layers "F.Cu" "F.Mask" "F.Paste")
			(net "C_CONF_DONE")
		)
	)
	(footprint ""
		(layer "F.Cu")
		(at 73.787 -20.32)
		(property "Reference" "R443"
			(at 0 0 0)
			(layer "F.SilkS")
			(hide yes)
			(effects
				(font
					(size 1.27 1.27)
				)
			)
		)
		(property "Value" "0R2J-2-GP"
			(at 1.7907 -1.1176 0)
			(unlocked yes)
			(layer "F.Fab")
			(hide yes)
			(effects
				(font
					(size 1.016 1.016)
					(thickness 0.1524)
				)
			)
		)
		(property "Device Type" "R402H16"
			(at 1.7907 -2.6416 0)
			(unlocked yes)
			(layer "F.Fab")
			(hide yes)
			(effects
				(font
					(size 1.016 1.016)
					(thickness 0.1524)
				)
			)
		)
		(duplicate_pad_numbers_are_jumpers no)
		(fp_rect
			(start -0.381 0.8382)
			(end 0.381 -0.8382)
			(stroke
				(width 0)
				(type default)
			)
			(fill no)
			(layer "F.CrtYd")
		)
		(fp_rect
			(start -0.381 0.8382)
			(end 0.381 -0.8382)
			(stroke
				(width 0)
				(type default)
			)
			(fill no)
			(layer "F.Fab")
		)
		(pad "1" smd custom
			(at 0 -0.4318)
			(size 0.127 0.127)
			(layers "F.Cu" "F.Mask" "F.Paste")
			(net "CPU_RXD")
			(options
				(clearance outline)
				(anchor circle)
			)
			(primitives
				(gr_poly
					(pts
						(arc
							(start -0.2032 -0.2794)
							(mid -0.239121 -0.264521)
							(end -0.254 -0.2286)
						)
						(arc
							(start -0.254 0.2286)
							(mid -0.239121 0.264521)
							(end -0.2032 0.2794)
						)
						(arc
							(start 0.2032 0.2794)
							(mid 0.239121 0.264521)
							(end 0.254 0.2286)
						)
						(arc
							(start 0.254 -0.2286)
							(mid 0.239121 -0.264521)
							(end 0.2032 -0.2794)
						)
					)
					(width 0)
					(fill yes)
				)
			)
		)
		(pad "2" smd custom
			(at 0 0.4318)
			(size 0.127 0.127)
			(layers "F.Cu" "F.Mask" "F.Paste")
			(net "GF_CPU_RXD")
			(options
				(clearance outline)
				(anchor circle)
			)
			(primitives
				(gr_poly
					(pts
						(arc
							(start -0.2032 -0.2794)
							(mid -0.239121 -0.264521)
							(end -0.254 -0.2286)
						)
						(arc
							(start -0.254 0.2286)
							(mid -0.239121 0.264521)
							(end -0.2032 0.2794)
						)
						(arc
							(start 0.2032 0.2794)
							(mid 0.239121 0.264521)
							(end 0.254 0.2286)
						)
						(arc
							(start 0.254 -0.2286)
							(mid 0.239121 -0.264521)
							(end 0.2032 -0.2794)
						)
					)
					(width 0)
					(fill yes)
				)
			)
		)
	)
	(footprint ""
		(layer "F.Cu")
		(at 143.891 -57.658 -90)
		(property "Reference" "C10"
			(at 0 0 270)
			(layer "F.SilkS")
			(hide yes)
			(effects
				(font
					(size 1.27 1.27)
				)
			)
		)
		(property "Value" "SCD1U10V2KX-5GP"
			(at 1.1811 -2.7051 270)
			(unlocked yes)
			(layer "F.Fab")
			(hide yes)
			(effects
				(font
					(size 1.016 1.016)
					(thickness 0.1524)
				)
			)
		)
		(property "Device Type" "C402H22"
			(at 1.1811 -4.2291 270)
			(unlocked yes)
			(layer "F.Fab")
			(hide yes)
			(effects
				(font
					(size 1.016 1.016)
					(thickness 0.1524)
				)
			)
		)
		(duplicate_pad_numbers_are_jumpers no)
		(fp_rect
			(start -0.381 0.7366)
			(end 0.381 -0.7366)
			(stroke
				(width 0)
				(type default)
			)
			(fill no)
			(layer "F.CrtYd")
		)
		(fp_rect
			(start -0.381 0.7366)
			(end 0.381 -0.7366)
			(stroke
				(width 0)
				(type default)
			)
			(fill no)
			(layer "F.Fab")
		)
		(pad "1" smd custom
			(at 0 -0.4572 270)
			(size 0.1143 0.1143)
			(layers "F.Cu" "F.Mask" "F.Paste")
			(net "GND")
			(options
				(clearance outline)
				(anchor circle)
			)
			(primitives
				(gr_poly
					(pts
						(arc
							(start -0.254 -0.1778)
							(mid -0.239121 -0.213721)
							(end -0.2032 -0.2286)
						)
						(arc
							(start 0.2032 -0.2286)
							(mid 0.239121 -0.213721)
							(end 0.254 -0.1778)
						)
						(arc
							(start 0.254 0.1778)
							(mid 0.239121 0.213721)
							(end 0.2032 0.2286)
						)
						(arc
							(start -0.2032 0.2286)
							(mid -0.239121 0.213721)
							(end -0.254 0.1778)
						)
					)
					(width 0)
					(fill yes)
				)
			)
		)
		(pad "2" smd custom
			(at 0 0.4572 270)
			(size 0.1143 0.1143)
			(layers "F.Cu" "F.Mask" "F.Paste")
			(net "P3V3_STBY")
			(options
				(clearance outline)
				(anchor circle)
			)
			(primitives
				(gr_poly
					(pts
						(arc
							(start -0.254 -0.1778)
							(mid -0.239121 -0.213721)
							(end -0.2032 -0.2286)
						)
						(arc
							(start 0.2032 -0.2286)
							(mid 0.239121 -0.213721)
							(end 0.254 -0.1778)
						)
						(arc
							(start 0.254 0.1778)
							(mid 0.239121 0.213721)
							(end 0.2032 0.2286)
						)
						(arc
							(start -0.2032 0.2286)
							(mid -0.239121 0.213721)
							(end -0.254 0.1778)
						)
					)
					(width 0)
					(fill yes)
				)
			)
		)
	)
	(footprint ""
		(layer "F.Cu")
		(at 74.041 -30.734 90)
		(property "Reference" "R347"
			(at 0 0 90)
			(layer "F.SilkS")
			(hide yes)
			(effects
				(font
					(size 1.27 1.27)
				)
			)
		)
		(property "Value" "1KR2F-3-GP"
			(at 0.064008 -3.993896 90)
			(unlocked yes)
			(layer "F.Fab")
			(hide yes)
			(effects
				(font
					(size 1.016 1.016)
					(thickness 0.1524)
				)
			)
		)
		(property "Device Type" "R402H16"
			(at 0.064008 -5.517896 90)
			(unlocked yes)
			(layer "F.Fab")
			(hide yes)
			(effects
				(font
					(size 1.016 1.016)
					(thickness 0.1524)
				)
			)
		)
		(duplicate_pad_numbers_are_jumpers no)
		(fp_rect
			(start -0.381 0.8382)
			(end 0.381 -0.8382)
			(stroke
				(width 0)
				(type default)
			)
			(fill no)
			(layer "F.CrtYd")
		)
		(fp_rect
			(start -0.381 0.8382)
			(end 0.381 -0.8382)
			(stroke
				(width 0)
				(type default)
			)
			(fill no)
			(layer "F.Fab")
		)
		(pad "1" smd custom
			(at 0 -0.4318 90)
			(size 0.127 0.127)
			(layers "F.Cu" "F.Mask" "F.Paste")
			(net "DDR3_DRAM_PWROK")
			(options
				(clearance outline)
				(anchor circle)
			)
			(primitives
				(gr_poly
					(pts
						(arc
							(start -0.2032 -0.2794)
							(mid -0.239121 -0.264521)
							(end -0.254 -0.2286)
						)
						(arc
							(start -0.254 0.2286)
							(mid -0.239121 0.264521)
							(end -0.2032 0.2794)
						)
						(arc
							(start 0.2032 0.2794)
							(mid 0.239121 0.264521)
							(end 0.254 0.2286)
						)
						(arc
							(start 0.254 -0.2286)
							(mid 0.239121 -0.264521)
							(end 0.2032 -0.2794)
						)
					)
					(width 0)
					(fill yes)
				)
			)
		)
		(pad "2" smd custom
			(at 0 0.4318 90)
			(size 0.127 0.127)
			(layers "F.Cu" "F.Mask" "F.Paste")
			(net "PMU_SLP_S45#")
			(options
				(clearance outline)
				(anchor circle)
			)
			(primitives
				(gr_poly
					(pts
						(arc
							(start -0.2032 -0.2794)
							(mid -0.239121 -0.264521)
							(end -0.254 -0.2286)
						)
						(arc
							(start -0.254 0.2286)
							(mid -0.239121 0.264521)
							(end -0.2032 0.2794)
						)
						(arc
							(start 0.2032 0.2794)
							(mid 0.239121 0.264521)
							(end 0.254 0.2286)
						)
						(arc
							(start 0.254 -0.2286)
							(mid 0.239121 -0.264521)
							(end 0.2032 -0.2794)
						)
					)
					(width 0)
					(fill yes)
				)
			)
		)
	)
	(footprint ""
		(layer "F.Cu")
		(at 4.572 -50.419 180)
		(property "Reference" "C4"
			(at 0 0 180)
			(layer "F.SilkS")
			(hide yes)
			(effects
				(font
					(size 1.27 1.27)
				)
			)
		)
		(property "Value" "SCD1U16V2KX-3GP"
			(at 1.1811 -2.7051 180)
			(unlocked yes)
			(layer "F.Fab")
			(hide yes)
			(effects
				(font
					(size 1.016 1.016)
					(thickness 0.1524)
				)
			)
		)
		(property "Device Type" "C402H22"
			(at 1.1811 -4.2291 180)
			(unlocked yes)
			(layer "F.Fab")
			(hide yes)
			(effects
				(font
					(size 1.016 1.016)
					(thickness 0.1524)
				)
			)
		)
		(duplicate_pad_numbers_are_jumpers no)
		(fp_rect
			(start -0.381 0.7366)
			(end 0.381 -0.7366)
			(stroke
				(width 0)
				(type default)
			)
			(fill no)
			(layer "F.CrtYd")
		)
		(fp_rect
			(start -0.381 0.7366)
			(end 0.381 -0.7366)
			(stroke
				(width 0)
				(type default)
			)
			(fill no)
			(layer "F.Fab")
		)
		(pad "1" smd custom
			(at 0 -0.4572 180)
			(size 0.1143 0.1143)
			(layers "F.Cu" "F.Mask" "F.Paste")
			(net "P3V3_STBY")
			(options
				(clearance outline)
				(anchor circle)
			)
			(primitives
				(gr_poly
					(pts
						(arc
							(start -0.254 -0.1778)
							(mid -0.239121 -0.213721)
							(end -0.2032 -0.2286)
						)
						(arc
							(start 0.2032 -0.2286)
							(mid 0.239121 -0.213721)
							(end 0.254 -0.1778)
						)
						(arc
							(start 0.254 0.1778)
							(mid 0.239121 0.213721)
							(end 0.2032 0.2286)
						)
						(arc
							(start -0.2032 0.2286)
							(mid -0.239121 0.213721)
							(end -0.254 0.1778)
						)
					)
					(width 0)
					(fill yes)
				)
			)
		)
		(pad "2" smd custom
			(at 0 0.4572 180)
			(size 0.1143 0.1143)
			(layers "F.Cu" "F.Mask" "F.Paste")
			(net "GND")
			(options
				(clearance outline)
				(anchor circle)
			)
			(primitives
				(gr_poly
					(pts
						(arc
							(start -0.254 -0.1778)
							(mid -0.239121 -0.213721)
							(end -0.2032 -0.2286)
						)
						(arc
							(start 0.2032 -0.2286)
							(mid 0.239121 -0.213721)
							(end 0.254 -0.1778)
						)
						(arc
							(start 0.254 0.1778)
							(mid 0.239121 0.213721)
							(end 0.2032 0.2286)
						)
						(arc
							(start -0.2032 0.2286)
							(mid -0.239121 0.213721)
							(end -0.254 0.1778)
						)
					)
					(width 0)
					(fill yes)
				)
			)
		)
	)
	(footprint ""
		(layer "F.Cu")
		(at 74.295 -13.462 90)
		(property "Reference" "Q15"
			(at 0 0 90)
			(layer "F.SilkS")
			(hide yes)
			(effects
				(font
					(size 1.27 1.27)
				)
			)
		)
		(property "Value" "2N7002A-7-GP"
			(at -4.3561 -5.7912 90)
			(unlocked yes)
			(layer "F.Fab")
			(hide yes)
			(effects
				(font
					(size 1.016 1.016)
					(thickness 0.1524)
				)
			)
		)
		(property "Device Type" "SOT23DGS2D4H48"
			(at -4.3561 -7.3152 90)
			(unlocked yes)
			(layer "F.Fab")
			(hide yes)
			(effects
				(font
					(size 1.016 1.016)
					(thickness 0.1524)
				)
			)
		)
		(duplicate_pad_numbers_are_jumpers no)
		(fp_line
			(start 1.7145 -0.4445)
			(end -1.7145 -0.4445)
			(stroke
				(width 0.1524)
				(type default)
			)
			(layer "F.SilkS")
		)
		(fp_line
			(start -1.7145 -0.4445)
			(end -1.7145 0.4445)
			(stroke
				(width 0.1524)
				(type default)
			)
			(layer "F.SilkS")
		)
		(fp_line
			(start 1.7145 0.4445)
			(end 1.7145 -0.4445)
			(stroke
				(width 0.1524)
				(type default)
			)
			(layer "F.SilkS")
		)
		(fp_line
			(start -1.7145 0.4445)
			(end 1.7145 0.4445)
			(stroke
				(width 0.1524)
				(type default)
			)
			(layer "F.SilkS")
		)
		(fp_poly
			(pts
				(xy -1.4224 1.5621) (xy -1.4224 0.9017) (xy -1.7145 0.9017) (xy -1.7145 -0.9017) (xy -0.4699 -0.9017)
				(xy -0.4699 -1.5621) (xy 0.4699 -1.5621) (xy 0.4699 -0.9017) (xy 1.7145 -0.9017) (xy 1.7145 0.9017)
				(xy 1.4224 0.9017) (xy 1.4224 1.5621) (xy 0.4826 1.5621) (xy 0.4826 0.9017) (xy -0.4826 0.9017)
				(xy -0.4826 1.5621)
			)
			(stroke
				(width 0)
				(type default)
			)
			(fill no)
			(layer "F.CrtYd")
		)
		(fp_poly
			(pts
				(xy -1.4224 1.5621) (xy -1.4224 0.9017) (xy -1.7145 0.9017) (xy -1.7145 -0.9017) (xy -0.4699 -0.9017)
				(xy -0.4699 -1.5621) (xy 0.4699 -1.5621) (xy 0.4699 -0.9017) (xy 1.7145 -0.9017) (xy 1.7145 0.9017)
				(xy 1.4224 0.9017) (xy 1.4224 1.5621) (xy 0.4826 1.5621) (xy 0.4826 0.9017) (xy -0.4826 0.9017)
				(xy -0.4826 1.5621)
			)
			(stroke
				(width 0)
				(type default)
			)
			(fill no)
			(layer "F.Fab")
		)
		(pad "D" smd custom
			(at 0 -1.069086 90)
			(size 0.17145 0.17145)
			(layers "F.Cu" "F.Mask" "F.Paste")
			(net "PCIE_GF_I2C_ALERT#")
			(options
				(clearance outline)
				(anchor circle)
			)
			(primitives
				(gr_poly
					(pts
						(arc
							(start -0.1397 0.3683)
							(mid -0.283384 0.308784)
							(end -0.3429 0.1651)
						)
						(arc
							(start -0.3429 -0.1651)
							(mid -0.283384 -0.308784)
							(end -0.1397 -0.3683)
						)
						(arc
							(start 0.1397 -0.3683)
							(mid 0.283384 -0.308784)
							(end 0.3429 -0.1651)
						)
						(arc
							(start 0.3429 0.1651)
							(mid 0.283384 0.308784)
							(end 0.1397 0.3683)
						)
					)
					(width 0)
					(fill yes)
				)
			)
		)
		(pad "G" smd custom
			(at -0.94996 1.069086 90)
			(size 0.17145 0.17145)
			(layers "F.Cu" "F.Mask" "F.Paste")
			(net "PICE_GF_I2C_SW_EN")
			(options
				(clearance outline)
				(anchor circle)
			)
			(primitives
				(gr_poly
					(pts
						(arc
							(start -0.1397 0.3683)
							(mid -0.283384 0.308784)
							(end -0.3429 0.1651)
						)
						(arc
							(start -0.3429 -0.1651)
							(mid -0.283384 -0.308784)
							(end -0.1397 -0.3683)
						)
						(arc
							(start 0.1397 -0.3683)
							(mid 0.283384 -0.308784)
							(end 0.3429 -0.1651)
						)
						(arc
							(start 0.3429 0.1651)
							(mid 0.283384 0.308784)
							(end 0.1397 0.3683)
						)
					)
					(width 0)
					(fill yes)
				)
			)
		)
		(pad "S" smd custom
			(at 0.94996 1.069086 90)
			(size 0.17145 0.17145)
			(layers "F.Cu" "F.Mask" "F.Paste")
			(net "BMC_I2C_ALERT#")
			(options
				(clearance outline)
				(anchor circle)
			)
			(primitives
				(gr_poly
					(pts
						(arc
							(start -0.1397 0.3683)
							(mid -0.283384 0.308784)
							(end -0.3429 0.1651)
						)
						(arc
							(start -0.3429 -0.1651)
							(mid -0.283384 -0.308784)
							(end -0.1397 -0.3683)
						)
						(arc
							(start 0.1397 -0.3683)
							(mid 0.283384 -0.308784)
							(end 0.3429 -0.1651)
						)
						(arc
							(start 0.3429 0.1651)
							(mid 0.283384 0.308784)
							(end 0.1397 0.3683)
						)
					)
					(width 0)
					(fill yes)
				)
			)
		)
	)
	(footprint ""
		(layer "F.Cu")
		(at 184.404 -46.101 180)
		(property "Reference" "R218"
			(at 0 0 180)
			(layer "F.SilkS")
			(hide yes)
			(effects
				(font
					(size 1.27 1.27)
				)
			)
		)
		(property "Value" "0R2J-2-GP"
			(at 0.064008 -3.993896 180)
			(unlocked yes)
			(layer "F.Fab")
			(hide yes)
			(effects
				(font
					(size 1.016 1.016)
					(thickness 0.1524)
				)
			)
		)
		(property "Device Type" "R402H16"
			(at 0.064008 -5.517896 180)
			(unlocked yes)
			(layer "F.Fab")
			(hide yes)
			(effects
				(font
					(size 1.016 1.016)
					(thickness 0.1524)
				)
			)
		)
		(duplicate_pad_numbers_are_jumpers no)
		(fp_rect
			(start -0.381 0.8382)
			(end 0.381 -0.8382)
			(stroke
				(width 0)
				(type default)
			)
			(fill no)
			(layer "F.CrtYd")
		)
		(fp_rect
			(start -0.381 0.8382)
			(end 0.381 -0.8382)
			(stroke
				(width 0)
				(type default)
			)
			(fill no)
			(layer "F.Fab")
		)
		(pad "1" smd custom
			(at 0 -0.4318 180)
			(size 0.127 0.127)
			(layers "F.Cu" "F.Mask" "F.Paste")
			(net "SMB_HOST_LV_DATA")
			(options
				(clearance outline)
				(anchor circle)
			)
			(primitives
				(gr_poly
					(pts
						(arc
							(start -0.2032 -0.2794)
							(mid -0.239121 -0.264521)
							(end -0.254 -0.2286)
						)
						(arc
							(start -0.254 0.2286)
							(mid -0.239121 0.264521)
							(end -0.2032 0.2794)
						)
						(arc
							(start 0.2032 0.2794)
							(mid 0.239121 0.264521)
							(end 0.254 0.2286)
						)
						(arc
							(start 0.254 -0.2286)
							(mid 0.239121 -0.264521)
							(end 0.2032 -0.2794)
						)
					)
					(width 0)
					(fill yes)
				)
			)
		)
		(pad "2" smd custom
			(at 0 0.4318 180)
			(size 0.127 0.127)
			(layers "F.Cu" "F.Mask" "F.Paste")
			(net "SMB_DPOT_DATA")
			(options
				(clearance outline)
				(anchor circle)
			)
			(primitives
				(gr_poly
					(pts
						(arc
							(start -0.2032 -0.2794)
							(mid -0.239121 -0.264521)
							(end -0.254 -0.2286)
						)
						(arc
							(start -0.254 0.2286)
							(mid -0.239121 0.264521)
							(end -0.2032 0.2794)
						)
						(arc
							(start 0.2032 0.2794)
							(mid 0.239121 0.264521)
							(end 0.254 0.2286)
						)
						(arc
							(start 0.254 -0.2286)
							(mid 0.239121 -0.264521)
							(end 0.2032 -0.2794)
						)
					)
					(width 0)
					(fill yes)
				)
			)
		)
	)
	(footprint ""
		(layer "F.Cu")
		(at 185.039 -14.986 90)
		(property "Reference" "PC118"
			(at 0 0 90)
			(layer "F.SilkS")
			(hide yes)
			(effects
				(font
					(size 1.27 1.27)
				)
			)
		)
		(property "Value" "SC10U6D3V3MX-GP"
			(at 0 -2.8194 90)
			(unlocked yes)
			(layer "F.Fab")
			(hide yes)
			(effects
				(font
					(size 1.016 1.016)
					(thickness 0.1524)
				)
			)
		)
		(property "Device Type" "C603H38"
			(at 0 -4.3434 90)
			(unlocked yes)
			(layer "F.Fab")
			(hide yes)
			(effects
				(font
					(size 1.016 1.016)
					(thickness 0.1524)
				)
			)
		)
		(duplicate_pad_numbers_are_jumpers no)
		(fp_line
			(start -0.4064 0)
			(end 0.4064 0)
			(stroke
				(width 0.2286)
				(type default)
			)
			(layer "F.SilkS")
		)
		(fp_rect
			(start -0.635 1.1811)
			(end 0.635 -1.1811)
			(stroke
				(width 0)
				(type default)
			)
			(fill no)
			(layer "F.CrtYd")
		)
		(fp_rect
			(start -0.635 1.1811)
			(end 0.635 -1.1811)
			(stroke
				(width 0)
				(type default)
			)
			(fill no)
			(layer "F.Fab")
		)
		(pad "1" smd custom
			(at 0 -0.6604 90)
			(size 0.19685 0.19685)
			(layers "F.Cu" "F.Mask" "F.Paste")
			(net "GND")
			(options
				(clearance outline)
				(anchor circle)
			)
			(primitives
				(gr_poly
					(pts
						(arc
							(start 0.508 -0.2921)
							(mid 0.478242 -0.363942)
							(end 0.4064 -0.3937)
						)
						(arc
							(start -0.4064 -0.3937)
							(mid -0.478242 -0.363942)
							(end -0.508 -0.2921)
						)
						(arc
							(start -0.508 0.2921)
							(mid -0.478242 0.363942)
							(end -0.4064 0.3937)
						)
						(arc
							(start 0.4064 0.3937)
							(mid 0.478242 0.363942)
							(end 0.508 0.2921)
						)
					)
					(width 0)
					(fill yes)
				)
			)
		)
		(pad "2" smd custom
			(at 0 0.6604 90)
			(size 0.19685 0.19685)
			(layers "F.Cu" "F.Mask" "F.Paste")
			(net "PV_VTT_DDR_B")
			(options
				(clearance outline)
				(anchor circle)
			)
			(primitives
				(gr_poly
					(pts
						(arc
							(start 0.508 -0.2921)
							(mid 0.478242 -0.363942)
							(end 0.4064 -0.3937)
						)
						(arc
							(start -0.4064 -0.3937)
							(mid -0.478242 -0.363942)
							(end -0.508 -0.2921)
						)
						(arc
							(start -0.508 0.2921)
							(mid -0.478242 0.363942)
							(end -0.4064 0.3937)
						)
						(arc
							(start 0.4064 0.3937)
							(mid 0.478242 0.363942)
							(end 0.508 0.2921)
						)
					)
					(width 0)
					(fill yes)
				)
			)
		)
	)
	(footprint ""
		(layer "F.Cu")
		(at 74.1172 -61.4426 -90)
		(property "Reference" "U19"
			(at 0 0 270)
			(layer "F.SilkS")
			(hide yes)
			(effects
				(font
					(size 1.27 1.27)
				)
			)
		)
		(property "Value" "ADS7828E-2K5-GP"
			(at 0.127 -12.573 270)
			(unlocked yes)
			(layer "F.Fab")
			(hide yes)
			(effects
				(font
					(size 1.016 1.016)
					(thickness 0.1524)
				)
			)
		)
		(property "Device Type" "TSOIC16H48"
			(at 0.1016 -14.5796 270)
			(unlocked yes)
			(layer "F.Fab")
			(hide yes)
			(effects
				(font
					(size 1.016 1.016)
					(thickness 0.1524)
				)
			)
		)
		(duplicate_pad_numbers_are_jumpers no)
		(fp_line
			(start -2.7305 1.8288)
			(end -2.7305 3.4544)
			(stroke
				(width 0.254)
				(type default)
			)
			(layer "F.SilkS")
		)
		(fp_line
			(start -2.6797 1.778)
			(end -2.6797 -1.778)
			(stroke
				(width 0.1524)
				(type default)
			)
			(layer "F.SilkS")
		)
		(fp_line
			(start 2.37617 1.778)
			(end -2.6797 1.778)
			(stroke
				(width 0.1524)
				(type default)
			)
			(layer "F.SilkS")
		)
		(fp_line
			(start -2.2987 0.0254)
			(end -2.6797 0.4064)
			(stroke
				(width 0.1524)
				(type default)
			)
			(layer "F.SilkS")
		)
		(fp_line
			(start -2.6797 -0.3556)
			(end -2.2987 0.0254)
			(stroke
				(width 0.1524)
				(type default)
			)
			(layer "F.SilkS")
		)
		(fp_line
			(start -2.6797 -1.778)
			(end 2.37617 -1.778)
			(stroke
				(width 0.1524)
				(type default)
			)
			(layer "F.SilkS")
		)
		(fp_line
			(start 2.37617 -1.778)
			(end 2.37617 1.778)
			(stroke
				(width 0.1524)
				(type default)
			)
			(layer "F.SilkS")
		)
		(fp_poly
			(pts
				(xy -2.45237 1.778) (xy 2.37617 1.778) (xy 2.37617 -1.778) (xy -2.45237 -1.778)
			)
			(stroke
				(width 0)
				(type default)
			)
			(fill yes)
			(layer "F.SilkS")
		)
		(fp_rect
			(start -2.7559 3.5814)
			(end 2.7559 -3.5814)
			(stroke
				(width 0)
				(type default)
			)
			(fill no)
			(layer "F.CrtYd")
		)
		(fp_rect
			(start -2.7559 3.5814)
			(end 2.7559 -3.5814)
			(stroke
				(width 0)
				(type default)
			)
			(fill no)
			(layer "F.Fab")
		)
		(pad "1" smd rect
			(at -2.27457 2.7559 270)
			(size 0.3556 1.397)
			(layers "F.Cu" "F.Mask" "F.Paste")
			(net "P12V_SENSE")
		)
		(pad "2" smd rect
			(at -1.6256 2.7559 270)
			(size 0.3556 1.397)
			(layers "F.Cu" "F.Mask" "F.Paste")
			(net "P3V3_STBY_SENSE")
		)
		(pad "3" smd rect
			(at -0.97536 2.7559 270)
			(size 0.3556 1.397)
			(layers "F.Cu" "F.Mask" "F.Paste")
			(net "P3V3_SENSE")
		)
		(pad "4" smd rect
			(at -0.32512 2.7559 270)
			(size 0.3556 1.397)
			(layers "F.Cu" "F.Mask" "F.Paste")
			(net "P1V8_SENSE")
		)
		(pad "5" smd rect
			(at 0.32512 2.7559 270)
			(size 0.3556 1.397)
			(layers "F.Cu" "F.Mask" "F.Paste")
			(net "PVCCP_SENSE")
		)
		(pad "6" smd rect
			(at 0.97536 2.7559 270)
			(size 0.3556 1.397)
			(layers "F.Cu" "F.Mask" "F.Paste")
			(net "PVNN_SENSE")
		)
		(pad "7" smd rect
			(at 1.6256 2.7559 270)
			(size 0.3556 1.397)
			(layers "F.Cu" "F.Mask" "F.Paste")
			(net "P1V0_SENSE")
		)
		(pad "8" smd rect
			(at 2.27457 2.7559 270)
			(size 0.3556 1.397)
			(layers "F.Cu" "F.Mask" "F.Paste")
			(net "PV_VDDR_SENSE")
		)
		(pad "9" smd rect
			(at 2.27457 -2.7559 270)
			(size 0.3556 1.397)
			(layers "F.Cu" "F.Mask" "F.Paste")
			(net "GND")
		)
		(pad "10" smd rect
			(at 1.6256 -2.7559 270)
			(size 0.3556 1.397)
			(layers "F.Cu" "F.Mask" "F.Paste")
			(net "VOL1_SEN_VREF")
		)
		(pad "11" smd rect
			(at 0.97536 -2.7559 270)
			(size 0.3556 1.397)
			(layers "F.Cu" "F.Mask" "F.Paste")
			(net "GND")
		)
		(pad "12" smd rect
			(at 0.32512 -2.7559 270)
			(size 0.3556 1.397)
			(layers "F.Cu" "F.Mask" "F.Paste")
			(net "VOL1_SEN_ADDR0")
		)
		(pad "13" smd rect
			(at -0.32512 -2.7559 270)
			(size 0.3556 1.397)
			(layers "F.Cu" "F.Mask" "F.Paste")
			(net "VOL1_SEN_ADDR1")
		)
		(pad "14" smd rect
			(at -0.97536 -2.7559 270)
			(size 0.3556 1.397)
			(layers "F.Cu" "F.Mask" "F.Paste")
			(net "VOL1_SEN_CLK")
		)
		(pad "15" smd rect
			(at -1.6256 -2.7559 270)
			(size 0.3556 1.397)
			(layers "F.Cu" "F.Mask" "F.Paste")
			(net "VOL1_SEN_DATA")
		)
		(pad "16" smd rect
			(at -2.27457 -2.7559 270)
			(size 0.3556 1.397)
			(layers "F.Cu" "F.Mask" "F.Paste")
			(net "P3V3_STBY")
		)
	)
	(footprint ""
		(layer "F.Cu")
		(at 12.1412 -54.0258 90)
		(property "Reference" "C55"
			(at 0 0 90)
			(layer "F.SilkS")
			(hide yes)
			(effects
				(font
					(size 1.27 1.27)
				)
			)
		)
		(property "Value" "SCD1U16V2KX-3GP"
			(at 1.1811 -2.7051 90)
			(unlocked yes)
			(layer "F.Fab")
			(hide yes)
			(effects
				(font
					(size 1.016 1.016)
					(thickness 0.1524)
				)
			)
		)
		(property "Device Type" "C402H22"
			(at 1.1811 -4.2291 90)
			(unlocked yes)
			(layer "F.Fab")
			(hide yes)
			(effects
				(font
					(size 1.016 1.016)
					(thickness 0.1524)
				)
			)
		)
		(duplicate_pad_numbers_are_jumpers no)
		(fp_rect
			(start -0.381 0.7366)
			(end 0.381 -0.7366)
			(stroke
				(width 0)
				(type default)
			)
			(fill no)
			(layer "F.CrtYd")
		)
		(fp_rect
			(start -0.381 0.7366)
			(end 0.381 -0.7366)
			(stroke
				(width 0)
				(type default)
			)
			(fill no)
			(layer "F.Fab")
		)
		(pad "1" smd custom
			(at 0 -0.4572 90)
			(size 0.1143 0.1143)
			(layers "F.Cu" "F.Mask" "F.Paste")
			(net "P2E_CPU_NGFF_C_RX_DN12")
			(options
				(clearance outline)
				(anchor circle)
			)
			(primitives
				(gr_poly
					(pts
						(arc
							(start -0.254 -0.1778)
							(mid -0.239121 -0.213721)
							(end -0.2032 -0.2286)
						)
						(arc
							(start 0.2032 -0.2286)
							(mid 0.239121 -0.213721)
							(end 0.254 -0.1778)
						)
						(arc
							(start 0.254 0.1778)
							(mid 0.239121 0.213721)
							(end 0.2032 0.2286)
						)
						(arc
							(start -0.2032 0.2286)
							(mid -0.239121 0.213721)
							(end -0.254 0.1778)
						)
					)
					(width 0)
					(fill yes)
				)
			)
		)
		(pad "2" smd custom
			(at 0 0.4572 90)
			(size 0.1143 0.1143)
			(layers "F.Cu" "F.Mask" "F.Paste")
			(net "P2E_CPU_NGFF_RX_DN12")
			(options
				(clearance outline)
				(anchor circle)
			)
			(primitives
				(gr_poly
					(pts
						(arc
							(start -0.254 -0.1778)
							(mid -0.239121 -0.213721)
							(end -0.2032 -0.2286)
						)
						(arc
							(start 0.2032 -0.2286)
							(mid 0.239121 -0.213721)
							(end 0.254 -0.1778)
						)
						(arc
							(start 0.254 0.1778)
							(mid 0.239121 0.213721)
							(end 0.2032 0.2286)
						)
						(arc
							(start -0.2032 0.2286)
							(mid -0.239121 0.213721)
							(end -0.254 0.1778)
						)
					)
					(width 0)
					(fill yes)
				)
			)
		)
	)
	(footprint ""
		(layer "F.Cu")
		(at 132.842 -59.944 90)
		(property "Reference" "PC45"
			(at 0 0 90)
			(layer "F.SilkS")
			(hide yes)
			(effects
				(font
					(size 1.27 1.27)
				)
			)
		)
		(property "Value" "SC10U6D3V3MX-GP"
			(at 0 -2.8194 90)
			(unlocked yes)
			(layer "F.Fab")
			(hide yes)
			(effects
				(font
					(size 1.016 1.016)
					(thickness 0.1524)
				)
			)
		)
		(property "Device Type" "C603H38"
			(at 0 -4.3434 90)
			(unlocked yes)
			(layer "F.Fab")
			(hide yes)
			(effects
				(font
					(size 1.016 1.016)
					(thickness 0.1524)
				)
			)
		)
		(duplicate_pad_numbers_are_jumpers no)
		(fp_line
			(start -0.4064 0)
			(end 0.4064 0)
			(stroke
				(width 0.2286)
				(type default)
			)
			(layer "F.SilkS")
		)
		(fp_rect
			(start -0.635 1.1811)
			(end 0.635 -1.1811)
			(stroke
				(width 0)
				(type default)
			)
			(fill no)
			(layer "F.CrtYd")
		)
		(fp_rect
			(start -0.635 1.1811)
			(end 0.635 -1.1811)
			(stroke
				(width 0)
				(type default)
			)
			(fill no)
			(layer "F.Fab")
		)
		(pad "1" smd custom
			(at 0 -0.6604 90)
			(size 0.19685 0.19685)
			(layers "F.Cu" "F.Mask" "F.Paste")
			(net "GND")
			(options
				(clearance outline)
				(anchor circle)
			)
			(primitives
				(gr_poly
					(pts
						(arc
							(start 0.508 -0.2921)
							(mid 0.478242 -0.363942)
							(end 0.4064 -0.3937)
						)
						(arc
							(start -0.4064 -0.3937)
							(mid -0.478242 -0.363942)
							(end -0.508 -0.2921)
						)
						(arc
							(start -0.508 0.2921)
							(mid -0.478242 0.363942)
							(end -0.4064 0.3937)
						)
						(arc
							(start 0.4064 0.3937)
							(mid 0.478242 0.363942)
							(end 0.508 0.2921)
						)
					)
					(width 0)
					(fill yes)
				)
			)
		)
		(pad "2" smd custom
			(at 0 0.6604 90)
			(size 0.19685 0.19685)
			(layers "F.Cu" "F.Mask" "F.Paste")
			(net "PV_VDDR")
			(options
				(clearance outline)
				(anchor circle)
			)
			(primitives
				(gr_poly
					(pts
						(arc
							(start 0.508 -0.2921)
							(mid 0.478242 -0.363942)
							(end 0.4064 -0.3937)
						)
						(arc
							(start -0.4064 -0.3937)
							(mid -0.478242 -0.363942)
							(end -0.508 -0.2921)
						)
						(arc
							(start -0.508 0.2921)
							(mid -0.478242 0.363942)
							(end -0.4064 0.3937)
						)
						(arc
							(start 0.4064 0.3937)
							(mid 0.478242 0.363942)
							(end 0.508 0.2921)
						)
					)
					(width 0)
					(fill yes)
				)
			)
		)
	)
	(footprint ""
		(layer "F.Cu")
		(at 154.813 -50.927 180)
		(property "Reference" "TP39"
			(at 0 0 180)
			(layer "F.SilkS")
			(hide yes)
			(effects
				(font
					(size 1.27 1.27)
				)
			)
		)
		(property "Value" "TPAD32-GP"
			(at 0 -3.166364 180)
			(unlocked yes)
			(layer "F.Fab")
			(hide yes)
			(effects
				(font
					(size 1.016 1.016)
					(thickness 0.1524)
				)
			)
		)
		(property "Device Type" "TPAD32"
			(at 0 -4.690618 180)
			(unlocked yes)
			(layer "F.Fab")
			(hide yes)
			(effects
				(font
					(size 1.016 1.016)
					(thickness 0.1524)
				)
			)
		)
		(duplicate_pad_numbers_are_jumpers no)
		(fp_poly
			(pts
				(arc
					(start -0.7112 0)
					(mid 0.7112 0)
					(end -0.7112 0)
				)
			)
			(stroke
				(width 0)
				(type default)
			)
			(fill no)
			(layer "F.CrtYd")
		)
		(fp_poly
			(pts
				(arc
					(start -0.7112 0)
					(mid 0.7112 0)
					(end -0.7112 0)
				)
			)
			(stroke
				(width 0)
				(type default)
			)
			(fill no)
			(layer "F.Fab")
		)
		(pad "1" smd circle
			(at 0 0 180)
			(size 0.8128 0.8128)
			(layers "F.Cu" "F.Mask" "F.Paste")
			(net "C_ASDO")
		)
	)
	(footprint ""
		(layer "F.Cu")
		(at 70.612 -50.038 -90)
		(property "Reference" "Q5"
			(at 0 0 270)
			(layer "F.SilkS")
			(hide yes)
			(effects
				(font
					(size 1.27 1.27)
				)
			)
		)
		(property "Value" "2N7002A-7-GP"
			(at -4.3561 -5.7912 270)
			(unlocked yes)
			(layer "F.Fab")
			(hide yes)
			(effects
				(font
					(size 1.016 1.016)
					(thickness 0.1524)
				)
			)
		)
		(property "Device Type" "SOT23DGS2D4H48"
			(at -4.3561 -7.3152 270)
			(unlocked yes)
			(layer "F.Fab")
			(hide yes)
			(effects
				(font
					(size 1.016 1.016)
					(thickness 0.1524)
				)
			)
		)
		(duplicate_pad_numbers_are_jumpers no)
		(fp_line
			(start -1.7145 0.4445)
			(end 1.7145 0.4445)
			(stroke
				(width 0.1524)
				(type default)
			)
			(layer "F.SilkS")
		)
		(fp_line
			(start 1.7145 0.4445)
			(end 1.7145 -0.4445)
			(stroke
				(width 0.1524)
				(type default)
			)
			(layer "F.SilkS")
		)
		(fp_line
			(start -1.7145 -0.4445)
			(end -1.7145 0.4445)
			(stroke
				(width 0.1524)
				(type default)
			)
			(layer "F.SilkS")
		)
		(fp_line
			(start 1.7145 -0.4445)
			(end -1.7145 -0.4445)
			(stroke
				(width 0.1524)
				(type default)
			)
			(layer "F.SilkS")
		)
		(fp_poly
			(pts
				(xy -1.4224 1.5621) (xy -1.4224 0.9017) (xy -1.7145 0.9017) (xy -1.7145 -0.9017) (xy -0.4699 -0.9017)
				(xy -0.4699 -1.5621) (xy 0.4699 -1.5621) (xy 0.4699 -0.9017) (xy 1.7145 -0.9017) (xy 1.7145 0.9017)
				(xy 1.4224 0.9017) (xy 1.4224 1.5621) (xy 0.4826 1.5621) (xy 0.4826 0.9017) (xy -0.4826 0.9017)
				(xy -0.4826 1.5621)
			)
			(stroke
				(width 0)
				(type default)
			)
			(fill no)
			(layer "F.CrtYd")
		)
		(fp_poly
			(pts
				(xy -1.4224 1.5621) (xy -1.4224 0.9017) (xy -1.7145 0.9017) (xy -1.7145 -0.9017) (xy -0.4699 -0.9017)
				(xy -0.4699 -1.5621) (xy 0.4699 -1.5621) (xy 0.4699 -0.9017) (xy 1.7145 -0.9017) (xy 1.7145 0.9017)
				(xy 1.4224 0.9017) (xy 1.4224 1.5621) (xy 0.4826 1.5621) (xy 0.4826 0.9017) (xy -0.4826 0.9017)
				(xy -0.4826 1.5621)
			)
			(stroke
				(width 0)
				(type default)
			)
			(fill no)
			(layer "F.Fab")
		)
		(pad "D" smd custom
			(at 0 -1.069086 270)
			(size 0.17145 0.17145)
			(layers "F.Cu" "F.Mask" "F.Paste")
			(net "BEEP_LED_D")
			(options
				(clearance outline)
				(anchor circle)
			)
			(primitives
				(gr_poly
					(pts
						(arc
							(start -0.1397 0.3683)
							(mid -0.283384 0.308784)
							(end -0.3429 0.1651)
						)
						(arc
							(start -0.3429 -0.1651)
							(mid -0.283384 -0.308784)
							(end -0.1397 -0.3683)
						)
						(arc
							(start 0.1397 -0.3683)
							(mid 0.283384 -0.308784)
							(end 0.3429 -0.1651)
						)
						(arc
							(start 0.3429 0.1651)
							(mid 0.283384 0.308784)
							(end 0.1397 0.3683)
						)
					)
					(width 0)
					(fill yes)
				)
			)
		)
		(pad "G" smd custom
			(at -0.94996 1.069086 270)
			(size 0.17145 0.17145)
			(layers "F.Cu" "F.Mask" "F.Paste")
			(net "CPU_BEEP_LED")
			(options
				(clearance outline)
				(anchor circle)
			)
			(primitives
				(gr_poly
					(pts
						(arc
							(start -0.1397 0.3683)
							(mid -0.283384 0.308784)
							(end -0.3429 0.1651)
						)
						(arc
							(start -0.3429 -0.1651)
							(mid -0.283384 -0.308784)
							(end -0.1397 -0.3683)
						)
						(arc
							(start 0.1397 -0.3683)
							(mid 0.283384 -0.308784)
							(end 0.3429 -0.1651)
						)
						(arc
							(start 0.3429 0.1651)
							(mid 0.283384 0.308784)
							(end 0.1397 0.3683)
						)
					)
					(width 0)
					(fill yes)
				)
			)
		)
		(pad "S" smd custom
			(at 0.94996 1.069086 270)
			(size 0.17145 0.17145)
			(layers "F.Cu" "F.Mask" "F.Paste")
			(net "GND")
			(options
				(clearance outline)
				(anchor circle)
			)
			(primitives
				(gr_poly
					(pts
						(arc
							(start -0.1397 0.3683)
							(mid -0.283384 0.308784)
							(end -0.3429 0.1651)
						)
						(arc
							(start -0.3429 -0.1651)
							(mid -0.283384 -0.308784)
							(end -0.1397 -0.3683)
						)
						(arc
							(start 0.1397 -0.3683)
							(mid 0.283384 -0.308784)
							(end 0.3429 -0.1651)
						)
						(arc
							(start 0.3429 0.1651)
							(mid 0.283384 0.308784)
							(end 0.1397 0.3683)
						)
					)
					(width 0)
					(fill yes)
				)
			)
		)
	)
	(footprint ""
		(layer "F.Cu")
		(at 187.198 -39.878 180)
		(property "Reference" "PC86"
			(at 0 0 180)
			(layer "F.SilkS")
			(hide yes)
			(effects
				(font
					(size 1.27 1.27)
				)
			)
		)
		(property "Value" "SC1KP50V2KX-1GP"
			(at 1.8923 -1.2065 180)
			(unlocked yes)
			(layer "F.Fab")
			(hide yes)
			(effects
				(font
					(size 1.016 1.016)
					(thickness 0.1524)
				)
			)
		)
		(property "Device Type" "C402H22"
			(at 1.8923 -2.7305 180)
			(unlocked yes)
			(layer "F.Fab")
			(hide yes)
			(effects
				(font
					(size 1.016 1.016)
					(thickness 0.1524)
				)
			)
		)
		(duplicate_pad_numbers_are_jumpers no)
		(fp_rect
			(start -0.381 0.7366)
			(end 0.381 -0.7366)
			(stroke
				(width 0)
				(type default)
			)
			(fill no)
			(layer "F.CrtYd")
		)
		(fp_rect
			(start -0.381 0.7366)
			(end 0.381 -0.7366)
			(stroke
				(width 0)
				(type default)
			)
			(fill no)
			(layer "F.Fab")
		)
		(pad "1" smd custom
			(at 0 -0.4572 180)
			(size 0.1143 0.1143)
			(layers "F.Cu" "F.Mask" "F.Paste")
			(net "VR_PVDDR_A_IAUTO")
			(options
				(clearance outline)
				(anchor circle)
			)
			(primitives
				(gr_poly
					(pts
						(arc
							(start -0.254 -0.1778)
							(mid -0.239121 -0.213721)
							(end -0.2032 -0.2286)
						)
						(arc
							(start 0.2032 -0.2286)
							(mid 0.239121 -0.213721)
							(end 0.254 -0.1778)
						)
						(arc
							(start 0.254 0.1778)
							(mid 0.239121 0.213721)
							(end 0.2032 0.2286)
						)
						(arc
							(start -0.2032 0.2286)
							(mid -0.239121 0.213721)
							(end -0.254 0.1778)
						)
					)
					(width 0)
					(fill yes)
				)
			)
		)
		(pad "2" smd custom
			(at 0 0.4572 180)
			(size 0.1143 0.1143)
			(layers "F.Cu" "F.Mask" "F.Paste")
			(net "GND")
			(options
				(clearance outline)
				(anchor circle)
			)
			(primitives
				(gr_poly
					(pts
						(arc
							(start -0.254 -0.1778)
							(mid -0.239121 -0.213721)
							(end -0.2032 -0.2286)
						)
						(arc
							(start 0.2032 -0.2286)
							(mid 0.239121 -0.213721)
							(end 0.254 -0.1778)
						)
						(arc
							(start 0.254 0.1778)
							(mid 0.239121 0.213721)
							(end 0.2032 0.2286)
						)
						(arc
							(start -0.2032 0.2286)
							(mid -0.239121 0.213721)
							(end -0.254 0.1778)
						)
					)
					(width 0)
					(fill yes)
				)
			)
		)
	)
	(footprint ""
		(layer "F.Cu")
		(at 12.1285 -64.897 -90)
		(property "Reference" "C158"
			(at 0 0 270)
			(layer "F.SilkS")
			(hide yes)
			(effects
				(font
					(size 1.27 1.27)
				)
			)
		)
		(property "Value" "SC10U6D3V5KX-4GP"
			(at 0 -4.9022 270)
			(unlocked yes)
			(layer "F.Fab")
			(hide yes)
			(effects
				(font
					(size 1.016 1.016)
					(thickness 0.1524)
				)
			)
		)
		(property "Device Type" "C805H58"
			(at 0 -6.8072 270)
			(unlocked yes)
			(layer "F.Fab")
			(hide yes)
			(effects
				(font
					(size 1.016 1.016)
					(thickness 0.1524)
				)
			)
		)
		(duplicate_pad_numbers_are_jumpers no)
		(fp_line
			(start 0.6096 0)
			(end -0.6096 0)
			(stroke
				(width 0.3048)
				(type default)
			)
			(layer "F.SilkS")
		)
		(fp_poly
			(pts
				(xy -0.9017 1.4351) (xy 0.9017 1.4351) (xy 0.9017 -1.4351) (xy -0.9017 -1.4351)
			)
			(stroke
				(width 0)
				(type default)
			)
			(fill no)
			(layer "F.CrtYd")
		)
		(fp_poly
			(pts
				(xy 0.9017 1.4351) (xy 0.9017 -1.4351) (xy -0.9017 -1.4351) (xy -0.9017 1.4351)
			)
			(stroke
				(width 0)
				(type default)
			)
			(fill no)
			(layer "F.Fab")
		)
		(pad "1" smd rect
			(at 0 -0.8382 270)
			(size 1.5494 0.9398)
			(layers "F.Cu" "F.Mask" "F.Paste")
			(net "P3V3")
		)
		(pad "2" smd rect
			(at 0 0.8382 270)
			(size 1.5494 0.9398)
			(layers "F.Cu" "F.Mask" "F.Paste")
			(net "GND")
		)
	)
	(footprint ""
		(layer "F.Cu")
		(at 27.0764 -55.6514 90)
		(property "Reference" "PR58"
			(at 0 0 90)
			(layer "F.SilkS")
			(hide yes)
			(effects
				(font
					(size 1.27 1.27)
				)
			)
		)
		(property "Value" "0R3J-0-U-GP"
			(at -0.0254 -2.0193 90)
			(unlocked yes)
			(layer "F.Fab")
			(hide yes)
			(effects
				(font
					(size 1.016 1.016)
					(thickness 0.1524)
				)
			)
		)
		(property "Device Type" "R603H22"
			(at -0.0254 -3.5433 90)
			(unlocked yes)
			(layer "F.Fab")
			(hide yes)
			(effects
				(font
					(size 1.016 1.016)
					(thickness 0.1524)
				)
			)
		)
		(duplicate_pad_numbers_are_jumpers no)
		(fp_line
			(start 0.4318 0)
			(end 0.2032 0)
			(stroke
				(width 0.2032)
				(type default)
			)
			(layer "F.SilkS")
		)
		(fp_line
			(start -0.2032 0)
			(end -0.4191 0)
			(stroke
				(width 0.2032)
				(type default)
			)
			(layer "F.SilkS")
		)
		(fp_rect
			(start -0.635 1.1811)
			(end 0.635 -1.1811)
			(stroke
				(width 0)
				(type default)
			)
			(fill no)
			(layer "F.CrtYd")
		)
		(fp_rect
			(start -0.635 1.1811)
			(end 0.635 -1.1811)
			(stroke
				(width 0)
				(type default)
			)
			(fill no)
			(layer "F.Fab")
		)
		(pad "1" smd custom
			(at 0 -0.6604 90)
			(size 0.19685 0.19685)
			(layers "F.Cu" "F.Mask" "F.Paste")
			(net "VR_PVCCP_GH")
			(options
				(clearance outline)
				(anchor circle)
			)
			(primitives
				(gr_poly
					(pts
						(arc
							(start 0.508 -0.2921)
							(mid 0.478242 -0.363942)
							(end 0.4064 -0.3937)
						)
						(arc
							(start -0.4064 -0.3937)
							(mid -0.478242 -0.363942)
							(end -0.508 -0.2921)
						)
						(arc
							(start -0.508 0.2921)
							(mid -0.478242 0.363942)
							(end -0.4064 0.3937)
						)
						(arc
							(start 0.4064 0.3937)
							(mid 0.478242 0.363942)
							(end 0.508 0.2921)
						)
					)
					(width 0)
					(fill yes)
				)
			)
		)
		(pad "2" smd custom
			(at 0 0.6604 90)
			(size 0.19685 0.19685)
			(layers "F.Cu" "F.Mask" "F.Paste")
			(net "VR_PVCCP_GH_R")
			(options
				(clearance outline)
				(anchor circle)
			)
			(primitives
				(gr_poly
					(pts
						(arc
							(start 0.508 -0.2921)
							(mid 0.478242 -0.363942)
							(end 0.4064 -0.3937)
						)
						(arc
							(start -0.4064 -0.3937)
							(mid -0.478242 -0.363942)
							(end -0.508 -0.2921)
						)
						(arc
							(start -0.508 0.2921)
							(mid -0.478242 0.363942)
							(end -0.4064 0.3937)
						)
						(arc
							(start 0.4064 0.3937)
							(mid 0.478242 0.363942)
							(end 0.508 0.2921)
						)
					)
					(width 0)
					(fill yes)
				)
			)
		)
	)
	(footprint ""
		(layer "F.Cu")
		(at 59.309 -56.769)
		(property "Reference" "PC59"
			(at 0 0 0)
			(layer "F.SilkS")
			(hide yes)
			(effects
				(font
					(size 1.27 1.27)
				)
			)
		)
		(property "Value" "SC47U6D3V5MX-1-GP"
			(at -0.0762 -6.1214 0)
			(unlocked yes)
			(layer "F.Fab")
			(hide yes)
			(effects
				(font
					(size 1.016 1.016)
					(thickness 0.1524)
				)
			)
		)
		(property "Device Type" "C805H54"
			(at -0.0762 -8.1534 0)
			(unlocked yes)
			(layer "F.Fab")
			(hide yes)
			(effects
				(font
					(size 1.016 1.016)
					(thickness 0.1524)
				)
			)
		)
		(duplicate_pad_numbers_are_jumpers no)
		(fp_line
			(start 0.6096 0)
			(end -0.6096 0)
			(stroke
				(width 0.3048)
				(type default)
			)
			(layer "F.SilkS")
		)
		(fp_poly
			(pts
				(xy -0.9017 1.4351) (xy 0.9017 1.4351) (xy 0.9017 -1.4351) (xy -0.9017 -1.4351)
			)
			(stroke
				(width 0)
				(type default)
			)
			(fill no)
			(layer "F.CrtYd")
		)
		(fp_poly
			(pts
				(xy 0.9017 1.4351) (xy 0.9017 -1.4351) (xy -0.9017 -1.4351) (xy -0.9017 1.4351)
			)
			(stroke
				(width 0)
				(type default)
			)
			(fill no)
			(layer "F.Fab")
		)
		(pad "1" smd rect
			(at 0 -0.8382)
			(size 1.5494 0.9398)
			(layers "F.Cu" "F.Mask" "F.Paste")
			(net "PVCCP")
		)
		(pad "2" smd rect
			(at 0 0.8382)
			(size 1.5494 0.9398)
			(layers "F.Cu" "F.Mask" "F.Paste")
			(net "GND")
		)
	)
	(footprint ""
		(layer "F.Cu")
		(at 45.212 -15.494 -90)
		(property "Reference" "L11"
			(at 0 0 270)
			(layer "F.SilkS")
			(hide yes)
			(effects
				(font
					(size 1.27 1.27)
				)
			)
		)
		(property "Value" "BLM18PG330SN1D-GP"
			(at -0.0254 -2.0193 270)
			(unlocked yes)
			(layer "F.Fab")
			(hide yes)
			(effects
				(font
					(size 1.016 1.016)
					(thickness 0.1524)
				)
			)
		)
		(property "Device Type" "L1608-UH38"
			(at -0.0254 -3.5433 270)
			(unlocked yes)
			(layer "F.Fab")
			(hide yes)
			(effects
				(font
					(size 1.016 1.016)
					(thickness 0.1524)
				)
			)
		)
		(duplicate_pad_numbers_are_jumpers no)
		(fp_line
			(start -0.4064 0)
			(end 0.4064 0)
			(stroke
				(width 0.2032)
				(type default)
			)
			(layer "F.SilkS")
		)
		(fp_rect
			(start -0.635 1.1811)
			(end 0.635 -1.1811)
			(stroke
				(width 0)
				(type default)
			)
			(fill no)
			(layer "F.CrtYd")
		)
		(fp_rect
			(start -0.635 1.1811)
			(end 0.635 -1.1811)
			(stroke
				(width 0)
				(type default)
			)
			(fill no)
			(layer "F.Fab")
		)
		(pad "1" smd custom
			(at 0 -0.6604 270)
			(size 0.19685 0.19685)
			(layers "F.Cu" "F.Mask" "F.Paste")
			(net "P3V3")
			(options
				(clearance outline)
				(anchor circle)
			)
			(primitives
				(gr_poly
					(pts
						(arc
							(start 0.508 -0.2921)
							(mid 0.478242 -0.363942)
							(end 0.4064 -0.3937)
						)
						(arc
							(start -0.4064 -0.3937)
							(mid -0.478242 -0.363942)
							(end -0.508 -0.2921)
						)
						(arc
							(start -0.508 0.2921)
							(mid -0.478242 0.363942)
							(end -0.4064 0.3937)
						)
						(arc
							(start 0.4064 0.3937)
							(mid 0.478242 0.363942)
							(end 0.508 0.2921)
						)
					)
					(width 0)
					(fill yes)
				)
			)
		)
		(pad "2" smd custom
			(at 0 0.6604 270)
			(size 0.19685 0.19685)
			(layers "F.Cu" "F.Mask" "F.Paste")
			(net "P3V3_VDD_CLKBUFF_R")
			(options
				(clearance outline)
				(anchor circle)
			)
			(primitives
				(gr_poly
					(pts
						(arc
							(start 0.508 -0.2921)
							(mid 0.478242 -0.363942)
							(end 0.4064 -0.3937)
						)
						(arc
							(start -0.4064 -0.3937)
							(mid -0.478242 -0.363942)
							(end -0.508 -0.2921)
						)
						(arc
							(start -0.508 0.2921)
							(mid -0.478242 0.363942)
							(end -0.4064 0.3937)
						)
						(arc
							(start 0.4064 0.3937)
							(mid 0.478242 0.363942)
							(end 0.508 0.2921)
						)
					)
					(width 0)
					(fill yes)
				)
			)
		)
	)
	(footprint ""
		(layer "F.Cu")
		(at 156.464 -28.956 180)
		(property "Reference" "R141"
			(at 0 0 180)
			(layer "F.SilkS")
			(hide yes)
			(effects
				(font
					(size 1.27 1.27)
				)
			)
		)
		(property "Value" "4K7R2F-GP"
			(at 0.064008 -3.993896 180)
			(unlocked yes)
			(layer "F.Fab")
			(hide yes)
			(effects
				(font
					(size 1.016 1.016)
					(thickness 0.1524)
				)
			)
		)
		(property "Device Type" "R402H16"
			(at 0.064008 -5.517896 180)
			(unlocked yes)
			(layer "F.Fab")
			(hide yes)
			(effects
				(font
					(size 1.016 1.016)
					(thickness 0.1524)
				)
			)
		)
		(duplicate_pad_numbers_are_jumpers no)
		(fp_rect
			(start -0.381 0.8382)
			(end 0.381 -0.8382)
			(stroke
				(width 0)
				(type default)
			)
			(fill no)
			(layer "F.CrtYd")
		)
		(fp_rect
			(start -0.381 0.8382)
			(end 0.381 -0.8382)
			(stroke
				(width 0)
				(type default)
			)
			(fill no)
			(layer "F.Fab")
		)
		(pad "1" smd custom
			(at 0 -0.4318 180)
			(size 0.127 0.127)
			(layers "F.Cu" "F.Mask" "F.Paste")
			(net "P3V3_STBY")
			(options
				(clearance outline)
				(anchor circle)
			)
			(primitives
				(gr_poly
					(pts
						(arc
							(start -0.2032 -0.2794)
							(mid -0.239121 -0.264521)
							(end -0.254 -0.2286)
						)
						(arc
							(start -0.254 0.2286)
							(mid -0.239121 0.264521)
							(end -0.2032 0.2794)
						)
						(arc
							(start 0.2032 0.2794)
							(mid 0.239121 0.264521)
							(end 0.254 0.2286)
						)
						(arc
							(start 0.254 -0.2286)
							(mid 0.239121 -0.264521)
							(end 0.2032 -0.2794)
						)
					)
					(width 0)
					(fill yes)
				)
			)
		)
		(pad "2" smd custom
			(at 0 0.4318 180)
			(size 0.127 0.127)
			(layers "F.Cu" "F.Mask" "F.Paste")
			(net "FPGA_SMB_HOST_DATA")
			(options
				(clearance outline)
				(anchor circle)
			)
			(primitives
				(gr_poly
					(pts
						(arc
							(start -0.2032 -0.2794)
							(mid -0.239121 -0.264521)
							(end -0.254 -0.2286)
						)
						(arc
							(start -0.254 0.2286)
							(mid -0.239121 0.264521)
							(end -0.2032 0.2794)
						)
						(arc
							(start 0.2032 0.2794)
							(mid 0.239121 0.264521)
							(end 0.254 0.2286)
						)
						(arc
							(start 0.254 -0.2286)
							(mid 0.239121 -0.264521)
							(end 0.2032 -0.2794)
						)
					)
					(width 0)
					(fill yes)
				)
			)
		)
	)
	(footprint ""
		(layer "F.Cu")
		(at 188.341 -22.479 180)
		(property "Reference" "PC114"
			(at 0 0 180)
			(layer "F.SilkS")
			(hide yes)
			(effects
				(font
					(size 1.27 1.27)
				)
			)
		)
		(property "Value" "SCD1U16V2KX-3GP"
			(at 1.1811 -2.7051 180)
			(unlocked yes)
			(layer "F.Fab")
			(hide yes)
			(effects
				(font
					(size 1.016 1.016)
					(thickness 0.1524)
				)
			)
		)
		(property "Device Type" "C402H22"
			(at 1.1811 -4.2291 180)
			(unlocked yes)
			(layer "F.Fab")
			(hide yes)
			(effects
				(font
					(size 1.016 1.016)
					(thickness 0.1524)
				)
			)
		)
		(duplicate_pad_numbers_are_jumpers no)
		(fp_rect
			(start -0.381 0.7366)
			(end 0.381 -0.7366)
			(stroke
				(width 0)
				(type default)
			)
			(fill no)
			(layer "F.CrtYd")
		)
		(fp_rect
			(start -0.381 0.7366)
			(end 0.381 -0.7366)
			(stroke
				(width 0)
				(type default)
			)
			(fill no)
			(layer "F.Fab")
		)
		(pad "1" smd custom
			(at 0 -0.4572 180)
			(size 0.1143 0.1143)
			(layers "F.Cu" "F.Mask" "F.Paste")
			(net "PV_VTT_DDR_B_REFO")
			(options
				(clearance outline)
				(anchor circle)
			)
			(primitives
				(gr_poly
					(pts
						(arc
							(start -0.254 -0.1778)
							(mid -0.239121 -0.213721)
							(end -0.2032 -0.2286)
						)
						(arc
							(start 0.2032 -0.2286)
							(mid 0.239121 -0.213721)
							(end 0.254 -0.1778)
						)
						(arc
							(start 0.254 0.1778)
							(mid 0.239121 0.213721)
							(end 0.2032 0.2286)
						)
						(arc
							(start -0.2032 0.2286)
							(mid -0.239121 0.213721)
							(end -0.254 0.1778)
						)
					)
					(width 0)
					(fill yes)
				)
			)
		)
		(pad "2" smd custom
			(at 0 0.4572 180)
			(size 0.1143 0.1143)
			(layers "F.Cu" "F.Mask" "F.Paste")
			(net "GND")
			(options
				(clearance outline)
				(anchor circle)
			)
			(primitives
				(gr_poly
					(pts
						(arc
							(start -0.254 -0.1778)
							(mid -0.239121 -0.213721)
							(end -0.2032 -0.2286)
						)
						(arc
							(start 0.2032 -0.2286)
							(mid 0.239121 -0.213721)
							(end 0.254 -0.1778)
						)
						(arc
							(start 0.254 0.1778)
							(mid 0.239121 0.213721)
							(end 0.2032 0.2286)
						)
						(arc
							(start -0.2032 0.2286)
							(mid -0.239121 0.213721)
							(end -0.254 0.1778)
						)
					)
					(width 0)
					(fill yes)
				)
			)
		)
	)
	(footprint ""
		(layer "F.Cu")
		(at 27.686 -32.385 180)
		(property "Reference" "PC44"
			(at 0 0 180)
			(layer "F.SilkS")
			(hide yes)
			(effects
				(font
					(size 1.27 1.27)
				)
			)
		)
		(property "Value" "SC22U6D3V3MX-1-GP"
			(at -0.0254 -2.0193 180)
			(unlocked yes)
			(layer "F.Fab")
			(hide yes)
			(effects
				(font
					(size 1.016 1.016)
					(thickness 0.1524)
				)
			)
		)
		(property "Device Type" "C603H40"
			(at -0.0254 -3.5433 180)
			(unlocked yes)
			(layer "F.Fab")
			(hide yes)
			(effects
				(font
					(size 1.016 1.016)
					(thickness 0.1524)
				)
			)
		)
		(duplicate_pad_numbers_are_jumpers no)
		(fp_line
			(start -0.4064 0)
			(end 0.4064 0)
			(stroke
				(width 0.2286)
				(type default)
			)
			(layer "F.SilkS")
		)
		(fp_rect
			(start -0.635 1.1811)
			(end 0.635 -1.1811)
			(stroke
				(width 0)
				(type default)
			)
			(fill no)
			(layer "F.CrtYd")
		)
		(fp_rect
			(start -0.635 1.1811)
			(end 0.635 -1.1811)
			(stroke
				(width 0)
				(type default)
			)
			(fill no)
			(layer "F.Fab")
		)
		(pad "1" smd custom
			(at 0 -0.6604 180)
			(size 0.19685 0.19685)
			(layers "F.Cu" "F.Mask" "F.Paste")
			(net "P1V0")
			(options
				(clearance outline)
				(anchor circle)
			)
			(primitives
				(gr_poly
					(pts
						(arc
							(start 0.508 -0.2921)
							(mid 0.478242 -0.363942)
							(end 0.4064 -0.3937)
						)
						(arc
							(start -0.4064 -0.3937)
							(mid -0.478242 -0.363942)
							(end -0.508 -0.2921)
						)
						(arc
							(start -0.508 0.2921)
							(mid -0.478242 0.363942)
							(end -0.4064 0.3937)
						)
						(arc
							(start 0.4064 0.3937)
							(mid 0.478242 0.363942)
							(end 0.508 0.2921)
						)
					)
					(width 0)
					(fill yes)
				)
			)
		)
		(pad "2" smd custom
			(at 0 0.6604 180)
			(size 0.19685 0.19685)
			(layers "F.Cu" "F.Mask" "F.Paste")
			(net "GND")
			(options
				(clearance outline)
				(anchor circle)
			)
			(primitives
				(gr_poly
					(pts
						(arc
							(start 0.508 -0.2921)
							(mid 0.478242 -0.363942)
							(end 0.4064 -0.3937)
						)
						(arc
							(start -0.4064 -0.3937)
							(mid -0.478242 -0.363942)
							(end -0.508 -0.2921)
						)
						(arc
							(start -0.508 0.2921)
							(mid -0.478242 0.363942)
							(end -0.4064 0.3937)
						)
						(arc
							(start 0.4064 0.3937)
							(mid 0.478242 0.363942)
							(end 0.508 0.2921)
						)
					)
					(width 0)
					(fill yes)
				)
			)
		)
	)
	(footprint ""
		(layer "F.Cu")
		(at 91.948 -13.208)
		(property "Reference" "R458"
			(at 0 0 0)
			(layer "F.SilkS")
			(hide yes)
			(effects
				(font
					(size 1.27 1.27)
				)
			)
		)
		(property "Value" "4K7R2F-GP"
			(at 1.7907 -1.1176 0)
			(unlocked yes)
			(layer "F.Fab")
			(hide yes)
			(effects
				(font
					(size 1.016 1.016)
					(thickness 0.1524)
				)
			)
		)
		(property "Device Type" "R402H16"
			(at 1.7907 -2.6416 0)
			(unlocked yes)
			(layer "F.Fab")
			(hide yes)
			(effects
				(font
					(size 1.016 1.016)
					(thickness 0.1524)
				)
			)
		)
		(duplicate_pad_numbers_are_jumpers no)
		(fp_rect
			(start -0.381 0.8382)
			(end 0.381 -0.8382)
			(stroke
				(width 0)
				(type default)
			)
			(fill no)
			(layer "F.CrtYd")
		)
		(fp_rect
			(start -0.381 0.8382)
			(end 0.381 -0.8382)
			(stroke
				(width 0)
				(type default)
			)
			(fill no)
			(layer "F.Fab")
		)
		(pad "1" smd custom
			(at 0 -0.4318)
			(size 0.127 0.127)
			(layers "F.Cu" "F.Mask" "F.Paste")
			(net "P3V3_STBY")
			(options
				(clearance outline)
				(anchor circle)
			)
			(primitives
				(gr_poly
					(pts
						(arc
							(start -0.2032 -0.2794)
							(mid -0.239121 -0.264521)
							(end -0.254 -0.2286)
						)
						(arc
							(start -0.254 0.2286)
							(mid -0.239121 0.264521)
							(end -0.2032 0.2794)
						)
						(arc
							(start 0.2032 0.2794)
							(mid 0.239121 0.264521)
							(end 0.254 0.2286)
						)
						(arc
							(start 0.254 -0.2286)
							(mid 0.239121 -0.264521)
							(end 0.2032 -0.2794)
						)
					)
					(width 0)
					(fill yes)
				)
			)
		)
		(pad "2" smd custom
			(at 0 0.4318)
			(size 0.127 0.127)
			(layers "F.Cu" "F.Mask" "F.Paste")
			(net "SLOT_ID2")
			(options
				(clearance outline)
				(anchor circle)
			)
			(primitives
				(gr_poly
					(pts
						(arc
							(start -0.2032 -0.2794)
							(mid -0.239121 -0.264521)
							(end -0.254 -0.2286)
						)
						(arc
							(start -0.254 0.2286)
							(mid -0.239121 0.264521)
							(end -0.2032 0.2794)
						)
						(arc
							(start 0.2032 0.2794)
							(mid 0.239121 0.264521)
							(end 0.254 0.2286)
						)
						(arc
							(start 0.254 -0.2286)
							(mid 0.239121 -0.264521)
							(end 0.2032 -0.2794)
						)
					)
					(width 0)
					(fill yes)
				)
			)
		)
	)
	(footprint ""
		(layer "F.Cu")
		(at 64.389 -13.589)
		(property "Reference" "C307"
			(at 0 0 0)
			(layer "F.SilkS")
			(hide yes)
			(effects
				(font
					(size 1.27 1.27)
				)
			)
		)
		(property "Value" "SCD01U16V2KX-3GP"
			(at 1.8923 -1.2065 0)
			(unlocked yes)
			(layer "F.Fab")
			(hide yes)
			(effects
				(font
					(size 1.016 1.016)
					(thickness 0.1524)
				)
			)
		)
		(property "Device Type" "C402H22"
			(at 1.8923 -2.7305 0)
			(unlocked yes)
			(layer "F.Fab")
			(hide yes)
			(effects
				(font
					(size 1.016 1.016)
					(thickness 0.1524)
				)
			)
		)
		(duplicate_pad_numbers_are_jumpers no)
		(fp_rect
			(start -0.381 0.7366)
			(end 0.381 -0.7366)
			(stroke
				(width 0)
				(type default)
			)
			(fill no)
			(layer "F.CrtYd")
		)
		(fp_rect
			(start -0.381 0.7366)
			(end 0.381 -0.7366)
			(stroke
				(width 0)
				(type default)
			)
			(fill no)
			(layer "F.Fab")
		)
		(pad "1" smd custom
			(at 0 -0.4572)
			(size 0.1143 0.1143)
			(layers "F.Cu" "F.Mask" "F.Paste")
			(net "SATA2_RX_DP0")
			(options
				(clearance outline)
				(anchor circle)
			)
			(primitives
				(gr_poly
					(pts
						(arc
							(start -0.254 -0.1778)
							(mid -0.239121 -0.213721)
							(end -0.2032 -0.2286)
						)
						(arc
							(start 0.2032 -0.2286)
							(mid 0.239121 -0.213721)
							(end 0.254 -0.1778)
						)
						(arc
							(start 0.254 0.1778)
							(mid 0.239121 0.213721)
							(end 0.2032 0.2286)
						)
						(arc
							(start -0.2032 0.2286)
							(mid -0.239121 0.213721)
							(end -0.254 0.1778)
						)
					)
					(width 0)
					(fill yes)
				)
			)
		)
		(pad "2" smd custom
			(at 0 0.4572)
			(size 0.1143 0.1143)
			(layers "F.Cu" "F.Mask" "F.Paste")
			(net "SATA2_RX_C_DP0")
			(options
				(clearance outline)
				(anchor circle)
			)
			(primitives
				(gr_poly
					(pts
						(arc
							(start -0.254 -0.1778)
							(mid -0.239121 -0.213721)
							(end -0.2032 -0.2286)
						)
						(arc
							(start 0.2032 -0.2286)
							(mid 0.239121 -0.213721)
							(end 0.254 -0.1778)
						)
						(arc
							(start 0.254 0.1778)
							(mid 0.239121 0.213721)
							(end 0.2032 0.2286)
						)
						(arc
							(start -0.2032 0.2286)
							(mid -0.239121 0.213721)
							(end -0.254 0.1778)
						)
					)
					(width 0)
					(fill yes)
				)
			)
		)
	)
	(footprint ""
		(layer "F.Cu")
		(at 44.9072 -37.719 90)
		(property "Reference" "U46"
			(at 0 0 90)
			(layer "F.SilkS")
			(hide yes)
			(effects
				(font
					(size 1.27 1.27)
				)
			)
		)
		(property "Value" "SNLVC1G17DCKR-GP"
			(at 0 -8.0772 90)
			(unlocked yes)
			(layer "F.Fab")
			(hide yes)
			(effects
				(font
					(size 1.016 1.016)
					(thickness 0.1524)
				)
			)
		)
		(property "Device Type" "SC70-5H44"
			(at 0 -9.6012 90)
			(unlocked yes)
			(layer "F.Fab")
			(hide yes)
			(effects
				(font
					(size 1.016 1.016)
					(thickness 0.1524)
				)
			)
		)
		(duplicate_pad_numbers_are_jumpers no)
		(fp_line
			(start 1.0033 -0.3302)
			(end 1.0033 0.3302)
			(stroke
				(width 0.1524)
				(type default)
			)
			(layer "F.SilkS")
		)
		(fp_line
			(start -1.0033 -0.3302)
			(end 1.0033 -0.3302)
			(stroke
				(width 0.1524)
				(type default)
			)
			(layer "F.SilkS")
		)
		(fp_line
			(start 1.0033 0.3302)
			(end -1.0033 0.3302)
			(stroke
				(width 0.1524)
				(type default)
			)
			(layer "F.SilkS")
		)
		(fp_line
			(start -1.0033 0.3302)
			(end -1.0033 -0.3302)
			(stroke
				(width 0.1524)
				(type default)
			)
			(layer "F.SilkS")
		)
		(fp_poly
			(pts
				(xy -1.0033 1.4859) (xy -1.0033 0.8001) (xy -1.1811 0.8001) (xy -1.1811 -0.8001) (xy -1.0033 -0.8001)
				(xy -1.0033 -1.4859) (xy 1.0033 -1.4859) (xy 1.0033 -0.8001) (xy 1.1811 -0.8001) (xy 1.1811 0.8001)
				(xy 1.0033 0.8001) (xy 1.0033 1.4859) (xy 0.2921 1.4859) (xy 0.2921 0.8001) (xy -0.2921 0.8001)
				(xy -0.2921 1.4859)
			)
			(stroke
				(width 0)
				(type default)
			)
			(fill no)
			(layer "F.CrtYd")
		)
		(fp_poly
			(pts
				(xy -1.0033 1.4859) (xy -1.0033 0.8001) (xy -1.1811 0.8001) (xy -1.1811 -0.8001) (xy -1.0033 -0.8001)
				(xy -1.0033 -1.4859) (xy 1.0033 -1.4859) (xy 1.0033 -0.8001) (xy 1.1811 -0.8001) (xy 1.1811 0.8001)
				(xy 1.0033 0.8001) (xy 1.0033 1.4859) (xy 0.2921 1.4859) (xy 0.2921 0.8001) (xy -0.2921 0.8001)
				(xy -0.2921 1.4859)
			)
			(stroke
				(width 0)
				(type default)
			)
			(fill no)
			(layer "F.Fab")
		)
		(pad "1" smd rect
			(at 0.65024 -0.93472 90)
			(size 0.3556 0.762)
			(layers "F.Cu" "F.Mask" "F.Paste")
			(net "Net_59")
		)
		(pad "2" smd rect
			(at 0 -0.93472 90)
			(size 0.3556 0.762)
			(layers "F.Cu" "F.Mask" "F.Paste")
			(net "XDP_RTEST#")
		)
		(pad "3" smd rect
			(at -0.65024 -0.93472 90)
			(size 0.3556 0.762)
			(layers "F.Cu" "F.Mask" "F.Paste")
			(net "GND")
		)
		(pad "4" smd rect
			(at -0.65024 0.93472 90)
			(size 0.3556 0.762)
			(layers "F.Cu" "F.Mask" "F.Paste")
			(net "XDP_BUF_RTEST#")
		)
		(pad "5" smd rect
			(at 0.65024 0.93472 90)
			(size 0.3556 0.762)
			(layers "F.Cu" "F.Mask" "F.Paste")
			(net "P3V3_STBY")
		)
	)
	(footprint ""
		(layer "F.Cu")
		(at 63.6016 -43.815)
		(property "Reference" "U33"
			(at 0 0 0)
			(layer "F.SilkS")
			(hide yes)
			(effects
				(font
					(size 1.27 1.27)
				)
			)
		)
		(property "Value" "TS5A23157DGSR-GP"
			(at -4.916678 -5.611622 0)
			(unlocked yes)
			(layer "F.Fab")
			(hide yes)
			(effects
				(font
					(size 1.016 1.016)
					(thickness 0.1524)
				)
			)
		)
		(property "Device Type" "MSOP10H44"
			(at -4.916678 -7.135622 0)
			(unlocked yes)
			(layer "F.Fab")
			(hide yes)
			(effects
				(font
					(size 1.016 1.016)
					(thickness 0.1524)
				)
			)
		)
		(duplicate_pad_numbers_are_jumpers no)
		(fp_line
			(start -1.6764 -1.0541)
			(end -1.6764 1.0541)
			(stroke
				(width 0.1524)
				(type default)
			)
			(layer "F.SilkS")
		)
		(fp_line
			(start -1.6764 -1.016)
			(end -1.6764 1.016)
			(stroke
				(width 0.1524)
				(type default)
			)
			(layer "F.SilkS")
		)
		(fp_line
			(start -1.6764 1.0541)
			(end 1.0795 1.0541)
			(stroke
				(width 0.1524)
				(type default)
			)
			(layer "F.SilkS")
		)
		(fp_line
			(start -1.5494 1.143)
			(end -1.5494 2.6289)
			(stroke
				(width 0.4064)
				(type default)
			)
			(layer "F.SilkS")
		)
		(fp_line
			(start -1.397 0)
			(end -1.6764 -0.2794)
			(stroke
				(width 0.1524)
				(type default)
			)
			(layer "F.SilkS")
		)
		(fp_line
			(start -1.397 0)
			(end -1.6764 0.2794)
			(stroke
				(width 0.1524)
				(type default)
			)
			(layer "F.SilkS")
		)
		(fp_line
			(start 1.0795 -1.0541)
			(end -1.6764 -1.0541)
			(stroke
				(width 0.1524)
				(type default)
			)
			(layer "F.SilkS")
		)
		(fp_line
			(start 1.0795 1.0541)
			(end 1.0795 -1.0541)
			(stroke
				(width 0.1524)
				(type default)
			)
			(layer "F.SilkS")
		)
		(fp_rect
			(start -1.7526 2.8321)
			(end 1.7526 -2.8321)
			(stroke
				(width 0)
				(type default)
			)
			(fill no)
			(layer "F.CrtYd")
		)
		(fp_rect
			(start -1.7526 2.8321)
			(end 1.7526 -2.8321)
			(stroke
				(width 0)
				(type default)
			)
			(fill no)
			(layer "F.Fab")
		)
		(pad "1" smd rect
			(at -0.99949 2.0066)
			(size 0.3048 1.397)
			(layers "F.Cu" "F.Mask" "F.Paste")
			(net "SMBUS_SW_EN")
		)
		(pad "2" smd rect
			(at -0.50038 2.0066)
			(size 0.3048 1.397)
			(layers "F.Cu" "F.Mask" "F.Paste")
			(net "SMBUS_HOST_R_CLK")
		)
		(pad "3" smd rect
			(at 0 2.0066)
			(size 0.3048 1.397)
			(layers "F.Cu" "F.Mask" "F.Paste")
			(net "GND")
		)
		(pad "4" smd rect
			(at 0.50038 2.0066)
			(size 0.3048 1.397)
			(layers "F.Cu" "F.Mask" "F.Paste")
			(net "SMBUS_HOST_R_DATA")
		)
		(pad "5" smd rect
			(at 0.99949 2.0066)
			(size 0.3048 1.397)
			(layers "F.Cu" "F.Mask" "F.Paste")
			(net "SMBUS_SW_EN")
		)
		(pad "6" smd rect
			(at 0.99949 -2.0066)
			(size 0.3048 1.397)
			(layers "F.Cu" "F.Mask" "F.Paste")
			(net "SMB_HOST_LV_R_DATA")
		)
		(pad "7" smd rect
			(at 0.50038 -2.0066)
			(size 0.3048 1.397)
			(layers "F.Cu" "F.Mask" "F.Paste")
			(net "FPGA_SMB_HOST_R_DATA")
		)
		(pad "8" smd rect
			(at 0 -2.0066)
			(size 0.3048 1.397)
			(layers "F.Cu" "F.Mask" "F.Paste")
			(net "P3V3_STBY")
		)
		(pad "9" smd rect
			(at -0.50038 -2.0066)
			(size 0.3048 1.397)
			(layers "F.Cu" "F.Mask" "F.Paste")
			(net "FPGA_SMB_HOST_R_CLK")
		)
		(pad "10" smd rect
			(at -0.99949 -2.0066)
			(size 0.3048 1.397)
			(layers "F.Cu" "F.Mask" "F.Paste")
			(net "SMB_HOST_LV_R_CLK")
		)
	)
	(footprint ""
		(layer "F.Cu")
		(at 19.5834 -68.7578)
		(property "Reference" "PR16"
			(at 0 0 0)
			(layer "F.SilkS")
			(hide yes)
			(effects
				(font
					(size 1.27 1.27)
				)
			)
		)
		(property "Value" "3K65R2F-1-GP"
			(at 1.7907 -1.1176 0)
			(unlocked yes)
			(layer "F.Fab")
			(hide yes)
			(effects
				(font
					(size 1.016 1.016)
					(thickness 0.1524)
				)
			)
		)
		(property "Device Type" "R402H16"
			(at 1.7907 -2.6416 0)
			(unlocked yes)
			(layer "F.Fab")
			(hide yes)
			(effects
				(font
					(size 1.016 1.016)
					(thickness 0.1524)
				)
			)
		)
		(duplicate_pad_numbers_are_jumpers no)
		(fp_rect
			(start -0.381 0.8382)
			(end 0.381 -0.8382)
			(stroke
				(width 0)
				(type default)
			)
			(fill no)
			(layer "F.CrtYd")
		)
		(fp_rect
			(start -0.381 0.8382)
			(end 0.381 -0.8382)
			(stroke
				(width 0)
				(type default)
			)
			(fill no)
			(layer "F.Fab")
		)
		(pad "1" smd custom
			(at 0 -0.4318)
			(size 0.127 0.127)
			(layers "F.Cu" "F.Mask" "F.Paste")
			(net "VR_PVNN_ISUMP_R2")
			(options
				(clearance outline)
				(anchor circle)
			)
			(primitives
				(gr_poly
					(pts
						(arc
							(start -0.2032 -0.2794)
							(mid -0.239121 -0.264521)
							(end -0.254 -0.2286)
						)
						(arc
							(start -0.254 0.2286)
							(mid -0.239121 0.264521)
							(end -0.2032 0.2794)
						)
						(arc
							(start 0.2032 0.2794)
							(mid 0.239121 0.264521)
							(end 0.254 0.2286)
						)
						(arc
							(start 0.254 -0.2286)
							(mid 0.239121 -0.264521)
							(end 0.2032 -0.2794)
						)
					)
					(width 0)
					(fill yes)
				)
			)
		)
		(pad "2" smd custom
			(at 0 0.4318)
			(size 0.127 0.127)
			(layers "F.Cu" "F.Mask" "F.Paste")
			(net "VR_PVNN_ISUMP")
			(options
				(clearance outline)
				(anchor circle)
			)
			(primitives
				(gr_poly
					(pts
						(arc
							(start -0.2032 -0.2794)
							(mid -0.239121 -0.264521)
							(end -0.254 -0.2286)
						)
						(arc
							(start -0.254 0.2286)
							(mid -0.239121 0.264521)
							(end -0.2032 0.2794)
						)
						(arc
							(start 0.2032 0.2794)
							(mid 0.239121 0.264521)
							(end 0.254 0.2286)
						)
						(arc
							(start 0.254 -0.2286)
							(mid 0.239121 -0.264521)
							(end 0.2032 -0.2794)
						)
					)
					(width 0)
					(fill yes)
				)
			)
		)
	)
	(footprint ""
		(layer "F.Cu")
		(at 173.355 -46.482 90)
		(property "Reference" "R191"
			(at 0 0 90)
			(layer "F.SilkS")
			(hide yes)
			(effects
				(font
					(size 1.27 1.27)
				)
			)
		)
		(property "Value" "0R2J-2-GP"
			(at 0.064008 -3.993896 90)
			(unlocked yes)
			(layer "F.Fab")
			(hide yes)
			(effects
				(font
					(size 1.016 1.016)
					(thickness 0.1524)
				)
			)
		)
		(property "Device Type" "R402H16"
			(at 0.064008 -5.517896 90)
			(unlocked yes)
			(layer "F.Fab")
			(hide yes)
			(effects
				(font
					(size 1.016 1.016)
					(thickness 0.1524)
				)
			)
		)
		(duplicate_pad_numbers_are_jumpers no)
		(fp_rect
			(start -0.381 0.8382)
			(end 0.381 -0.8382)
			(stroke
				(width 0)
				(type default)
			)
			(fill no)
			(layer "F.CrtYd")
		)
		(fp_rect
			(start -0.381 0.8382)
			(end 0.381 -0.8382)
			(stroke
				(width 0)
				(type default)
			)
			(fill no)
			(layer "F.Fab")
		)
		(pad "1" smd custom
			(at 0 -0.4318 90)
			(size 0.127 0.127)
			(layers "F.Cu" "F.Mask" "F.Paste")
			(net "EEPROM_DATA")
			(options
				(clearance outline)
				(anchor circle)
			)
			(primitives
				(gr_poly
					(pts
						(arc
							(start -0.2032 -0.2794)
							(mid -0.239121 -0.264521)
							(end -0.254 -0.2286)
						)
						(arc
							(start -0.254 0.2286)
							(mid -0.239121 0.264521)
							(end -0.2032 0.2794)
						)
						(arc
							(start 0.2032 0.2794)
							(mid 0.239121 0.264521)
							(end 0.254 0.2286)
						)
						(arc
							(start 0.254 -0.2286)
							(mid 0.239121 -0.264521)
							(end 0.2032 -0.2794)
						)
					)
					(width 0)
					(fill yes)
				)
			)
		)
		(pad "2" smd custom
			(at 0 0.4318 90)
			(size 0.127 0.127)
			(layers "F.Cu" "F.Mask" "F.Paste")
			(net "BMC_I2C_DATA")
			(options
				(clearance outline)
				(anchor circle)
			)
			(primitives
				(gr_poly
					(pts
						(arc
							(start -0.2032 -0.2794)
							(mid -0.239121 -0.264521)
							(end -0.254 -0.2286)
						)
						(arc
							(start -0.254 0.2286)
							(mid -0.239121 0.264521)
							(end -0.2032 0.2794)
						)
						(arc
							(start 0.2032 0.2794)
							(mid 0.239121 0.264521)
							(end 0.254 0.2286)
						)
						(arc
							(start 0.254 -0.2286)
							(mid 0.239121 -0.264521)
							(end 0.2032 -0.2794)
						)
					)
					(width 0)
					(fill yes)
				)
			)
		)
	)
	(footprint ""
		(layer "F.Cu")
		(at 69.596 -30.734 -90)
		(property "Reference" "R403"
			(at 0 0 270)
			(layer "F.SilkS")
			(hide yes)
			(effects
				(font
					(size 1.27 1.27)
				)
			)
		)
		(property "Value" "1KR2F-3-GP"
			(at 1.7907 -1.1176 270)
			(unlocked yes)
			(layer "F.Fab")
			(hide yes)
			(effects
				(font
					(size 1.016 1.016)
					(thickness 0.1524)
				)
			)
		)
		(property "Device Type" "R402H16"
			(at 1.7907 -2.6416 270)
			(unlocked yes)
			(layer "F.Fab")
			(hide yes)
			(effects
				(font
					(size 1.016 1.016)
					(thickness 0.1524)
				)
			)
		)
		(duplicate_pad_numbers_are_jumpers no)
		(fp_rect
			(start -0.381 0.8382)
			(end 0.381 -0.8382)
			(stroke
				(width 0)
				(type default)
			)
			(fill no)
			(layer "F.CrtYd")
		)
		(fp_rect
			(start -0.381 0.8382)
			(end 0.381 -0.8382)
			(stroke
				(width 0)
				(type default)
			)
			(fill no)
			(layer "F.Fab")
		)
		(pad "1" smd custom
			(at 0 -0.4318 270)
			(size 0.127 0.127)
			(layers "F.Cu" "F.Mask" "F.Paste")
			(net "BD_ID_2")
			(options
				(clearance outline)
				(anchor circle)
			)
			(primitives
				(gr_poly
					(pts
						(arc
							(start -0.2032 -0.2794)
							(mid -0.239121 -0.264521)
							(end -0.254 -0.2286)
						)
						(arc
							(start -0.254 0.2286)
							(mid -0.239121 0.264521)
							(end -0.2032 0.2794)
						)
						(arc
							(start 0.2032 0.2794)
							(mid 0.239121 0.264521)
							(end 0.254 0.2286)
						)
						(arc
							(start 0.254 -0.2286)
							(mid 0.239121 -0.264521)
							(end 0.2032 -0.2794)
						)
					)
					(width 0)
					(fill yes)
				)
			)
		)
		(pad "2" smd custom
			(at 0 0.4318 270)
			(size 0.127 0.127)
			(layers "F.Cu" "F.Mask" "F.Paste")
			(net "GND")
			(options
				(clearance outline)
				(anchor circle)
			)
			(primitives
				(gr_poly
					(pts
						(arc
							(start -0.2032 -0.2794)
							(mid -0.239121 -0.264521)
							(end -0.254 -0.2286)
						)
						(arc
							(start -0.254 0.2286)
							(mid -0.239121 0.264521)
							(end -0.2032 0.2794)
						)
						(arc
							(start 0.2032 0.2794)
							(mid 0.239121 0.264521)
							(end 0.254 0.2286)
						)
						(arc
							(start 0.254 -0.2286)
							(mid 0.239121 -0.264521)
							(end 0.2032 -0.2794)
						)
					)
					(width 0)
					(fill yes)
				)
			)
		)
	)
	(footprint ""
		(layer "F.Cu")
		(at 49.149 -16.0782 180)
		(property "Reference" "R325"
			(at 0 0 180)
			(layer "F.SilkS")
			(hide yes)
			(effects
				(font
					(size 1.27 1.27)
				)
			)
		)
		(property "Value" "4K7R2F-GP"
			(at 0.064008 -3.993896 180)
			(unlocked yes)
			(layer "F.Fab")
			(hide yes)
			(effects
				(font
					(size 1.016 1.016)
					(thickness 0.1524)
				)
			)
		)
		(property "Device Type" "R402H16"
			(at 0.064008 -5.517896 180)
			(unlocked yes)
			(layer "F.Fab")
			(hide yes)
			(effects
				(font
					(size 1.016 1.016)
					(thickness 0.1524)
				)
			)
		)
		(duplicate_pad_numbers_are_jumpers no)
		(fp_rect
			(start -0.381 0.8382)
			(end 0.381 -0.8382)
			(stroke
				(width 0)
				(type default)
			)
			(fill no)
			(layer "F.CrtYd")
		)
		(fp_rect
			(start -0.381 0.8382)
			(end 0.381 -0.8382)
			(stroke
				(width 0)
				(type default)
			)
			(fill no)
			(layer "F.Fab")
		)
		(pad "1" smd custom
			(at 0 -0.4318 180)
			(size 0.127 0.127)
			(layers "F.Cu" "F.Mask" "F.Paste")
			(net "P3V3")
			(options
				(clearance outline)
				(anchor circle)
			)
			(primitives
				(gr_poly
					(pts
						(arc
							(start -0.2032 -0.2794)
							(mid -0.239121 -0.264521)
							(end -0.254 -0.2286)
						)
						(arc
							(start -0.254 0.2286)
							(mid -0.239121 0.264521)
							(end -0.2032 0.2794)
						)
						(arc
							(start 0.2032 0.2794)
							(mid 0.239121 0.264521)
							(end 0.254 0.2286)
						)
						(arc
							(start 0.254 -0.2286)
							(mid 0.239121 -0.264521)
							(end 0.2032 -0.2794)
						)
					)
					(width 0)
					(fill yes)
				)
			)
		)
		(pad "2" smd custom
			(at 0 0.4318 180)
			(size 0.127 0.127)
			(layers "F.Cu" "F.Mask" "F.Paste")
			(net "CLKBUFF_OE0#")
			(options
				(clearance outline)
				(anchor circle)
			)
			(primitives
				(gr_poly
					(pts
						(arc
							(start -0.2032 -0.2794)
							(mid -0.239121 -0.264521)
							(end -0.254 -0.2286)
						)
						(arc
							(start -0.254 0.2286)
							(mid -0.239121 0.264521)
							(end -0.2032 0.2794)
						)
						(arc
							(start 0.2032 0.2794)
							(mid 0.239121 0.264521)
							(end 0.254 0.2286)
						)
						(arc
							(start 0.254 -0.2286)
							(mid 0.239121 -0.264521)
							(end 0.2032 -0.2794)
						)
					)
					(width 0)
					(fill yes)
				)
			)
		)
	)
	(footprint ""
		(layer "F.Cu")
		(at 158.115 -20.32)
		(property "Reference" "R414"
			(at 0 0 0)
			(layer "F.SilkS")
			(hide yes)
			(effects
				(font
					(size 1.27 1.27)
				)
			)
		)
		(property "Value" "0R2J-2-GP"
			(at 1.7907 -1.1176 0)
			(unlocked yes)
			(layer "F.Fab")
			(hide yes)
			(effects
				(font
					(size 1.016 1.016)
					(thickness 0.1524)
				)
			)
		)
		(property "Device Type" "R402H16"
			(at 1.7907 -2.6416 0)
			(unlocked yes)
			(layer "F.Fab")
			(hide yes)
			(effects
				(font
					(size 1.016 1.016)
					(thickness 0.1524)
				)
			)
		)
		(duplicate_pad_numbers_are_jumpers no)
		(fp_rect
			(start -0.381 0.8382)
			(end 0.381 -0.8382)
			(stroke
				(width 0)
				(type default)
			)
			(fill no)
			(layer "F.CrtYd")
		)
		(fp_rect
			(start -0.381 0.8382)
			(end 0.381 -0.8382)
			(stroke
				(width 0)
				(type default)
			)
			(fill no)
			(layer "F.Fab")
		)
		(pad "1" smd custom
			(at 0 -0.4318)
			(size 0.127 0.127)
			(layers "F.Cu" "F.Mask" "F.Paste")
			(net "DISABLE")
			(options
				(clearance outline)
				(anchor circle)
			)
			(primitives
				(gr_poly
					(pts
						(arc
							(start -0.2032 -0.2794)
							(mid -0.239121 -0.264521)
							(end -0.254 -0.2286)
						)
						(arc
							(start -0.254 0.2286)
							(mid -0.239121 0.264521)
							(end -0.2032 0.2794)
						)
						(arc
							(start 0.2032 0.2794)
							(mid 0.239121 0.264521)
							(end 0.254 0.2286)
						)
						(arc
							(start 0.254 -0.2286)
							(mid 0.239121 -0.264521)
							(end 0.2032 -0.2794)
						)
					)
					(width 0)
					(fill yes)
				)
			)
		)
		(pad "2" smd custom
			(at 0 0.4318)
			(size 0.127 0.127)
			(layers "F.Cu" "F.Mask" "F.Paste")
			(net "CPU_FPGA_DISABLE")
			(options
				(clearance outline)
				(anchor circle)
			)
			(primitives
				(gr_poly
					(pts
						(arc
							(start -0.2032 -0.2794)
							(mid -0.239121 -0.264521)
							(end -0.254 -0.2286)
						)
						(arc
							(start -0.254 0.2286)
							(mid -0.239121 0.264521)
							(end -0.2032 0.2794)
						)
						(arc
							(start 0.2032 0.2794)
							(mid 0.239121 0.264521)
							(end 0.254 0.2286)
						)
						(arc
							(start 0.254 -0.2286)
							(mid 0.239121 -0.264521)
							(end 0.2032 -0.2794)
						)
					)
					(width 0)
					(fill yes)
				)
			)
		)
	)
	(footprint ""
		(layer "F.Cu")
		(at 145.3134 -49.9364 180)
		(property "Reference" "TP38"
			(at 0 0 180)
			(layer "F.SilkS")
			(hide yes)
			(effects
				(font
					(size 1.27 1.27)
				)
			)
		)
		(property "Value" "TPAD32-GP"
			(at 0 -3.166364 180)
			(unlocked yes)
			(layer "F.Fab")
			(hide yes)
			(effects
				(font
					(size 1.016 1.016)
					(thickness 0.1524)
				)
			)
		)
		(property "Device Type" "TPAD32"
			(at 0 -4.690618 180)
			(unlocked yes)
			(layer "F.Fab")
			(hide yes)
			(effects
				(font
					(size 1.016 1.016)
					(thickness 0.1524)
				)
			)
		)
		(duplicate_pad_numbers_are_jumpers no)
		(fp_poly
			(pts
				(arc
					(start -0.7112 0)
					(mid 0.7112 0)
					(end -0.7112 0)
				)
			)
			(stroke
				(width 0)
				(type default)
			)
			(fill no)
			(layer "F.CrtYd")
		)
		(fp_poly
			(pts
				(arc
					(start -0.7112 0)
					(mid 0.7112 0)
					(end -0.7112 0)
				)
			)
			(stroke
				(width 0)
				(type default)
			)
			(fill no)
			(layer "F.Fab")
		)
		(pad "1" smd circle
			(at 0 0 180)
			(size 0.8128 0.8128)
			(layers "F.Cu" "F.Mask" "F.Paste")
			(net "C_CSO#")
		)
	)
	(footprint ""
		(layer "F.Cu")
		(at 54.356 -44.0944 180)
		(property "Reference" "C16"
			(at 0 0 180)
			(layer "F.SilkS")
			(hide yes)
			(effects
				(font
					(size 1.27 1.27)
				)
			)
		)
		(property "Value" "SC1U25V3KX-GP"
			(at -0.0254 -2.0193 180)
			(unlocked yes)
			(layer "F.Fab")
			(hide yes)
			(effects
				(font
					(size 1.016 1.016)
					(thickness 0.1524)
				)
			)
		)
		(property "Device Type" "C603H36"
			(at -0.0254 -3.5433 180)
			(unlocked yes)
			(layer "F.Fab")
			(hide yes)
			(effects
				(font
					(size 1.016 1.016)
					(thickness 0.1524)
				)
			)
		)
		(duplicate_pad_numbers_are_jumpers no)
		(fp_line
			(start -0.4064 0)
			(end 0.4064 0)
			(stroke
				(width 0.2286)
				(type default)
			)
			(layer "F.SilkS")
		)
		(fp_rect
			(start -0.635 1.1811)
			(end 0.635 -1.1811)
			(stroke
				(width 0)
				(type default)
			)
			(fill no)
			(layer "F.CrtYd")
		)
		(fp_rect
			(start -0.635 1.1811)
			(end 0.635 -1.1811)
			(stroke
				(width 0)
				(type default)
			)
			(fill no)
			(layer "F.Fab")
		)
		(pad "1" smd custom
			(at 0 -0.6604 180)
			(size 0.19685 0.19685)
			(layers "F.Cu" "F.Mask" "F.Paste")
			(net "SW_P3V3_CPU_EN_LV_D")
			(options
				(clearance outline)
				(anchor circle)
			)
			(primitives
				(gr_poly
					(pts
						(arc
							(start 0.508 -0.2921)
							(mid 0.478242 -0.363942)
							(end 0.4064 -0.3937)
						)
						(arc
							(start -0.4064 -0.3937)
							(mid -0.478242 -0.363942)
							(end -0.508 -0.2921)
						)
						(arc
							(start -0.508 0.2921)
							(mid -0.478242 0.363942)
							(end -0.4064 0.3937)
						)
						(arc
							(start 0.4064 0.3937)
							(mid 0.478242 0.363942)
							(end 0.508 0.2921)
						)
					)
					(width 0)
					(fill yes)
				)
			)
		)
		(pad "2" smd custom
			(at 0 0.6604 180)
			(size 0.19685 0.19685)
			(layers "F.Cu" "F.Mask" "F.Paste")
			(net "GND")
			(options
				(clearance outline)
				(anchor circle)
			)
			(primitives
				(gr_poly
					(pts
						(arc
							(start 0.508 -0.2921)
							(mid 0.478242 -0.363942)
							(end 0.4064 -0.3937)
						)
						(arc
							(start -0.4064 -0.3937)
							(mid -0.478242 -0.363942)
							(end -0.508 -0.2921)
						)
						(arc
							(start -0.508 0.2921)
							(mid -0.478242 0.363942)
							(end -0.4064 0.3937)
						)
						(arc
							(start 0.4064 0.3937)
							(mid 0.478242 0.363942)
							(end 0.508 0.2921)
						)
					)
					(width 0)
					(fill yes)
				)
			)
		)
	)
	(footprint ""
		(layer "F.Cu")
		(at 19.7358 -64.7192 180)
		(property "Reference" "PR20"
			(at 0 0 180)
			(layer "F.SilkS")
			(hide yes)
			(effects
				(font
					(size 1.27 1.27)
				)
			)
		)
		(property "Value" "0R2J-2-GP"
			(at 1.7907 -1.1176 180)
			(unlocked yes)
			(layer "F.Fab")
			(hide yes)
			(effects
				(font
					(size 1.016 1.016)
					(thickness 0.1524)
				)
			)
		)
		(property "Device Type" "R402H16"
			(at 1.7907 -2.6416 180)
			(unlocked yes)
			(layer "F.Fab")
			(hide yes)
			(effects
				(font
					(size 1.016 1.016)
					(thickness 0.1524)
				)
			)
		)
		(duplicate_pad_numbers_are_jumpers no)
		(fp_rect
			(start -0.381 0.8382)
			(end 0.381 -0.8382)
			(stroke
				(width 0)
				(type default)
			)
			(fill no)
			(layer "F.CrtYd")
		)
		(fp_rect
			(start -0.381 0.8382)
			(end 0.381 -0.8382)
			(stroke
				(width 0)
				(type default)
			)
			(fill no)
			(layer "F.Fab")
		)
		(pad "1" smd custom
			(at 0 -0.4318 180)
			(size 0.127 0.127)
			(layers "F.Cu" "F.Mask" "F.Paste")
			(net "VR_PVNN_VSEN")
			(options
				(clearance outline)
				(anchor circle)
			)
			(primitives
				(gr_poly
					(pts
						(arc
							(start -0.2032 -0.2794)
							(mid -0.239121 -0.264521)
							(end -0.254 -0.2286)
						)
						(arc
							(start -0.254 0.2286)
							(mid -0.239121 0.264521)
							(end -0.2032 0.2794)
						)
						(arc
							(start 0.2032 0.2794)
							(mid 0.239121 0.264521)
							(end 0.254 0.2286)
						)
						(arc
							(start 0.254 -0.2286)
							(mid 0.239121 -0.264521)
							(end 0.2032 -0.2794)
						)
					)
					(width 0)
					(fill yes)
				)
			)
		)
		(pad "2" smd custom
			(at 0 0.4318 180)
			(size 0.127 0.127)
			(layers "F.Cu" "F.Mask" "F.Paste")
			(net "VR_PVNN_VSEN_R")
			(options
				(clearance outline)
				(anchor circle)
			)
			(primitives
				(gr_poly
					(pts
						(arc
							(start -0.2032 -0.2794)
							(mid -0.239121 -0.264521)
							(end -0.254 -0.2286)
						)
						(arc
							(start -0.254 0.2286)
							(mid -0.239121 0.264521)
							(end -0.2032 0.2794)
						)
						(arc
							(start 0.2032 0.2794)
							(mid 0.239121 0.264521)
							(end 0.254 0.2286)
						)
						(arc
							(start 0.254 -0.2286)
							(mid 0.239121 -0.264521)
							(end 0.2032 -0.2794)
						)
					)
					(width 0)
					(fill yes)
				)
			)
		)
	)
	(footprint ""
		(layer "F.Cu")
		(at 185.039 -42.926 -90)
		(property "Reference" "R223"
			(at 0 0 270)
			(layer "F.SilkS")
			(hide yes)
			(effects
				(font
					(size 1.27 1.27)
				)
			)
		)
		(property "Value" "0R2J-2-GP"
			(at 0.064008 -3.993896 270)
			(unlocked yes)
			(layer "F.Fab")
			(hide yes)
			(effects
				(font
					(size 1.016 1.016)
					(thickness 0.1524)
				)
			)
		)
		(property "Device Type" "R402H16"
			(at 0.064008 -5.517896 270)
			(unlocked yes)
			(layer "F.Fab")
			(hide yes)
			(effects
				(font
					(size 1.016 1.016)
					(thickness 0.1524)
				)
			)
		)
		(duplicate_pad_numbers_are_jumpers no)
		(fp_rect
			(start -0.381 0.8382)
			(end 0.381 -0.8382)
			(stroke
				(width 0)
				(type default)
			)
			(fill no)
			(layer "F.CrtYd")
		)
		(fp_rect
			(start -0.381 0.8382)
			(end 0.381 -0.8382)
			(stroke
				(width 0)
				(type default)
			)
			(fill no)
			(layer "F.Fab")
		)
		(pad "1" smd custom
			(at 0 -0.4318 270)
			(size 0.127 0.127)
			(layers "F.Cu" "F.Mask" "F.Paste")
			(net "PV_VDDR_VREF_B")
			(options
				(clearance outline)
				(anchor circle)
			)
			(primitives
				(gr_poly
					(pts
						(arc
							(start -0.2032 -0.2794)
							(mid -0.239121 -0.264521)
							(end -0.254 -0.2286)
						)
						(arc
							(start -0.254 0.2286)
							(mid -0.239121 0.264521)
							(end -0.2032 0.2794)
						)
						(arc
							(start 0.2032 0.2794)
							(mid 0.239121 0.264521)
							(end 0.254 0.2286)
						)
						(arc
							(start 0.254 -0.2286)
							(mid 0.239121 -0.264521)
							(end 0.2032 -0.2794)
						)
					)
					(width 0)
					(fill yes)
				)
			)
		)
		(pad "2" smd custom
			(at 0 0.4318 270)
			(size 0.127 0.127)
			(layers "F.Cu" "F.Mask" "F.Paste")
			(net "DDR3_M_B_VREF_DQ1")
			(options
				(clearance outline)
				(anchor circle)
			)
			(primitives
				(gr_poly
					(pts
						(arc
							(start -0.2032 -0.2794)
							(mid -0.239121 -0.264521)
							(end -0.254 -0.2286)
						)
						(arc
							(start -0.254 0.2286)
							(mid -0.239121 0.264521)
							(end -0.2032 0.2794)
						)
						(arc
							(start 0.2032 0.2794)
							(mid 0.239121 0.264521)
							(end 0.254 0.2286)
						)
						(arc
							(start 0.254 -0.2286)
							(mid 0.239121 -0.264521)
							(end 0.2032 -0.2794)
						)
					)
					(width 0)
					(fill yes)
				)
			)
		)
	)
	(footprint ""
		(layer "F.Cu")
		(at 162.052 -54.737 -90)
		(property "Reference" "U17"
			(at 0 0 270)
			(layer "F.SilkS")
			(hide yes)
			(effects
				(font
					(size 1.27 1.27)
				)
			)
		)
		(property "Value" "W25Q64FVZPIG-GP"
			(at -4.3561 -4.9022 270)
			(unlocked yes)
			(layer "F.Fab")
			(hide yes)
			(effects
				(font
					(size 1.016 1.016)
					(thickness 0.1524)
				)
			)
		)
		(property "Device Type" "DFN8A5060-G435345H32"
			(at -4.3561 -6.4262 270)
			(unlocked yes)
			(layer "F.Fab")
			(hide yes)
			(effects
				(font
					(size 1.016 1.016)
					(thickness 0.1524)
				)
			)
		)
		(duplicate_pad_numbers_are_jumpers no)
		(fp_line
			(start -3.0099 4.0132)
			(end -2.2479 4.0132)
			(stroke
				(width 0.1524)
				(type default)
			)
			(layer "F.SilkS")
		)
		(fp_line
			(start 2.2479 4.0132)
			(end 3.0099 4.0132)
			(stroke
				(width 0.1524)
				(type default)
			)
			(layer "F.SilkS")
		)
		(fp_line
			(start 3.0099 4.0132)
			(end 3.0099 3.2512)
			(stroke
				(width 0.1524)
				(type default)
			)
			(layer "F.SilkS")
		)
		(fp_line
			(start -1.905 3.736594)
			(end -1.905 4.244594)
			(stroke
				(width 0.1524)
				(type default)
			)
			(layer "F.SilkS")
		)
		(fp_line
			(start -3.0099 3.2512)
			(end -3.0099 4.0132)
			(stroke
				(width 0.1524)
				(type default)
			)
			(layer "F.SilkS")
		)
		(fp_line
			(start -3.0099 -4.0132)
			(end -3.0099 -3.2512)
			(stroke
				(width 0.1524)
				(type default)
			)
			(layer "F.SilkS")
		)
		(fp_line
			(start -2.2479 -4.0132)
			(end -3.0099 -4.0132)
			(stroke
				(width 0.1524)
				(type default)
			)
			(layer "F.SilkS")
		)
		(fp_poly
			(pts
				(xy 3.0099 -4.0132) (xy 1.9939 -4.0132) (xy 3.0099 -2.9972)
			)
			(stroke
				(width 0)
				(type default)
			)
			(fill yes)
			(layer "F.SilkS")
		)
		(fp_rect
			(start -2.5019 2.9972)
			(end 2.5019 -2.9972)
			(stroke
				(width 0)
				(type default)
			)
			(fill no)
			(layer "F.CrtYd")
		)
		(fp_poly
			(pts
				(xy 3.0099 -2.9972) (xy -2.5019 -2.9972) (xy -2.5019 2.9972) (xy 2.5019 2.9972) (xy 2.5019 -2.9845)
				(xy 3.0099 -2.9845) (xy 3.0099 4.0132) (xy -3.0099 4.0132) (xy -3.0099 -4.0132) (xy 3.0099 -4.0132)
			)
			(stroke
				(width 0)
				(type default)
			)
			(fill no)
			(layer "F.CrtYd")
		)
		(fp_rect
			(start -3.0099 4.0132)
			(end 3.0099 -4.0132)
			(stroke
				(width 0)
				(type default)
			)
			(fill no)
			(layer "F.Fab")
		)
		(pad "1" smd rect
			(at 1.905 -2.822194 270)
			(size 0.635 1.3716)
			(layers "F.Cu" "F.Mask" "F.Paste")
			(net "C_R_CSO#")
		)
		(pad "2" smd rect
			(at 0.635 -2.822194 270)
			(size 0.635 1.3716)
			(layers "F.Cu" "F.Mask" "F.Paste")
			(net "C_R_DATA0")
		)
		(pad "3" smd rect
			(at -0.635 -2.822194 270)
			(size 0.635 1.3716)
			(layers "F.Cu" "F.Mask" "F.Paste")
			(net "P3V3_STBY")
		)
		(pad "4" smd rect
			(at -1.905 -2.822194 270)
			(size 0.635 1.3716)
			(layers "F.Cu" "F.Mask" "F.Paste")
			(net "GND")
		)
		(pad "5" smd rect
			(at -1.905 2.822194 270)
			(size 0.635 1.3716)
			(layers "F.Cu" "F.Mask" "F.Paste")
			(net "C_R_ASDO")
		)
		(pad "6" smd rect
			(at -0.635 2.822194 270)
			(size 0.635 1.3716)
			(layers "F.Cu" "F.Mask" "F.Paste")
			(net "C_R_DCLK")
		)
		(pad "7" smd rect
			(at 0.635 2.822194 270)
			(size 0.635 1.3716)
			(layers "F.Cu" "F.Mask" "F.Paste")
			(net "P3V3_STBY")
		)
		(pad "8" smd rect
			(at 1.905 2.822194 270)
			(size 0.635 1.3716)
			(layers "F.Cu" "F.Mask" "F.Paste")
			(net "P3V3_STBY")
		)
		(pad "9" smd rect
			(at 0 0 270)
			(size 4.3434 3.4544)
			(layers "F.Cu" "F.Mask" "F.Paste")
			(net "GND")
		)
	)
	(footprint ""
		(layer "F.Cu")
		(at 143.891 -19.304)
		(property "Reference" "R97"
			(at 0 0 0)
			(layer "F.SilkS")
			(hide yes)
			(effects
				(font
					(size 1.27 1.27)
				)
			)
		)
		(property "Value" "0R2J-2-GP"
			(at 0.064008 -3.993896 0)
			(unlocked yes)
			(layer "F.Fab")
			(hide yes)
			(effects
				(font
					(size 1.016 1.016)
					(thickness 0.1524)
				)
			)
		)
		(property "Device Type" "R402H16"
			(at 0.064008 -5.517896 0)
			(unlocked yes)
			(layer "F.Fab")
			(hide yes)
			(effects
				(font
					(size 1.016 1.016)
					(thickness 0.1524)
				)
			)
		)
		(duplicate_pad_numbers_are_jumpers no)
		(fp_rect
			(start -0.381 0.8382)
			(end 0.381 -0.8382)
			(stroke
				(width 0)
				(type default)
			)
			(fill no)
			(layer "F.CrtYd")
		)
		(fp_rect
			(start -0.381 0.8382)
			(end 0.381 -0.8382)
			(stroke
				(width 0)
				(type default)
			)
			(fill no)
			(layer "F.Fab")
		)
		(pad "1" smd custom
			(at 0 -0.4318)
			(size 0.127 0.127)
			(layers "F.Cu" "F.Mask" "F.Paste")
			(net "MSEL0")
			(options
				(clearance outline)
				(anchor circle)
			)
			(primitives
				(gr_poly
					(pts
						(arc
							(start -0.2032 -0.2794)
							(mid -0.239121 -0.264521)
							(end -0.254 -0.2286)
						)
						(arc
							(start -0.254 0.2286)
							(mid -0.239121 0.264521)
							(end -0.2032 0.2794)
						)
						(arc
							(start 0.2032 0.2794)
							(mid 0.239121 0.264521)
							(end 0.254 0.2286)
						)
						(arc
							(start 0.254 -0.2286)
							(mid 0.239121 -0.264521)
							(end 0.2032 -0.2794)
						)
					)
					(width 0)
					(fill yes)
				)
			)
		)
		(pad "2" smd custom
			(at 0 0.4318)
			(size 0.127 0.127)
			(layers "F.Cu" "F.Mask" "F.Paste")
			(net "GND")
			(options
				(clearance outline)
				(anchor circle)
			)
			(primitives
				(gr_poly
					(pts
						(arc
							(start -0.2032 -0.2794)
							(mid -0.239121 -0.264521)
							(end -0.254 -0.2286)
						)
						(arc
							(start -0.254 0.2286)
							(mid -0.239121 0.264521)
							(end -0.2032 0.2794)
						)
						(arc
							(start 0.2032 0.2794)
							(mid 0.239121 0.264521)
							(end 0.254 0.2286)
						)
						(arc
							(start 0.254 -0.2286)
							(mid 0.239121 -0.264521)
							(end 0.2032 -0.2794)
						)
					)
					(width 0)
					(fill yes)
				)
			)
		)
	)
	(footprint ""
		(layer "F.Cu")
		(at 167.005 -56.007 180)
		(property "Reference" "C232"
			(at 0 0 180)
			(layer "F.SilkS")
			(hide yes)
			(effects
				(font
					(size 1.27 1.27)
				)
			)
		)
		(property "Value" "SCD1U10V2KX-5GP"
			(at 1.1811 -2.7051 180)
			(unlocked yes)
			(layer "F.Fab")
			(hide yes)
			(effects
				(font
					(size 1.016 1.016)
					(thickness 0.1524)
				)
			)
		)
		(property "Device Type" "C402H22"
			(at 1.1811 -4.2291 180)
			(unlocked yes)
			(layer "F.Fab")
			(hide yes)
			(effects
				(font
					(size 1.016 1.016)
					(thickness 0.1524)
				)
			)
		)
		(duplicate_pad_numbers_are_jumpers no)
		(fp_rect
			(start -0.381 0.7366)
			(end 0.381 -0.7366)
			(stroke
				(width 0)
				(type default)
			)
			(fill no)
			(layer "F.CrtYd")
		)
		(fp_rect
			(start -0.381 0.7366)
			(end 0.381 -0.7366)
			(stroke
				(width 0)
				(type default)
			)
			(fill no)
			(layer "F.Fab")
		)
		(pad "1" smd custom
			(at 0 -0.4572 180)
			(size 0.1143 0.1143)
			(layers "F.Cu" "F.Mask" "F.Paste")
			(net "P3V3_STBY")
			(options
				(clearance outline)
				(anchor circle)
			)
			(primitives
				(gr_poly
					(pts
						(arc
							(start -0.254 -0.1778)
							(mid -0.239121 -0.213721)
							(end -0.2032 -0.2286)
						)
						(arc
							(start 0.2032 -0.2286)
							(mid 0.239121 -0.213721)
							(end 0.254 -0.1778)
						)
						(arc
							(start 0.254 0.1778)
							(mid 0.239121 0.213721)
							(end 0.2032 0.2286)
						)
						(arc
							(start -0.2032 0.2286)
							(mid -0.239121 0.213721)
							(end -0.254 0.1778)
						)
					)
					(width 0)
					(fill yes)
				)
			)
		)
		(pad "2" smd custom
			(at 0 0.4572 180)
			(size 0.1143 0.1143)
			(layers "F.Cu" "F.Mask" "F.Paste")
			(net "GND")
			(options
				(clearance outline)
				(anchor circle)
			)
			(primitives
				(gr_poly
					(pts
						(arc
							(start -0.254 -0.1778)
							(mid -0.239121 -0.213721)
							(end -0.2032 -0.2286)
						)
						(arc
							(start 0.2032 -0.2286)
							(mid 0.239121 -0.213721)
							(end 0.254 -0.1778)
						)
						(arc
							(start 0.254 0.1778)
							(mid 0.239121 0.213721)
							(end 0.2032 0.2286)
						)
						(arc
							(start -0.2032 0.2286)
							(mid -0.239121 0.213721)
							(end -0.254 0.1778)
						)
					)
					(width 0)
					(fill yes)
				)
			)
		)
	)
	(footprint ""
		(layer "F.Cu")
		(at 120.0658 -62.357 -90)
		(property "Reference" "C98"
			(at 0 0 270)
			(layer "F.SilkS")
			(hide yes)
			(effects
				(font
					(size 1.27 1.27)
				)
			)
		)
		(property "Value" "SC1U6D3V2KX-GP"
			(at 1.1811 -2.7051 270)
			(unlocked yes)
			(layer "F.Fab")
			(hide yes)
			(effects
				(font
					(size 1.016 1.016)
					(thickness 0.1524)
				)
			)
		)
		(property "Device Type" "C402H22"
			(at 1.1811 -4.2291 270)
			(unlocked yes)
			(layer "F.Fab")
			(hide yes)
			(effects
				(font
					(size 1.016 1.016)
					(thickness 0.1524)
				)
			)
		)
		(duplicate_pad_numbers_are_jumpers no)
		(fp_rect
			(start -0.381 0.7366)
			(end 0.381 -0.7366)
			(stroke
				(width 0)
				(type default)
			)
			(fill no)
			(layer "F.CrtYd")
		)
		(fp_rect
			(start -0.381 0.7366)
			(end 0.381 -0.7366)
			(stroke
				(width 0)
				(type default)
			)
			(fill no)
			(layer "F.Fab")
		)
		(pad "1" smd custom
			(at 0 -0.4572 270)
			(size 0.1143 0.1143)
			(layers "F.Cu" "F.Mask" "F.Paste")
			(net "PV_VTT_DDR_A")
			(options
				(clearance outline)
				(anchor circle)
			)
			(primitives
				(gr_poly
					(pts
						(arc
							(start -0.254 -0.1778)
							(mid -0.239121 -0.213721)
							(end -0.2032 -0.2286)
						)
						(arc
							(start 0.2032 -0.2286)
							(mid 0.239121 -0.213721)
							(end 0.254 -0.1778)
						)
						(arc
							(start 0.254 0.1778)
							(mid 0.239121 0.213721)
							(end 0.2032 0.2286)
						)
						(arc
							(start -0.2032 0.2286)
							(mid -0.239121 0.213721)
							(end -0.254 0.1778)
						)
					)
					(width 0)
					(fill yes)
				)
			)
		)
		(pad "2" smd custom
			(at 0 0.4572 270)
			(size 0.1143 0.1143)
			(layers "F.Cu" "F.Mask" "F.Paste")
			(net "GND")
			(options
				(clearance outline)
				(anchor circle)
			)
			(primitives
				(gr_poly
					(pts
						(arc
							(start -0.254 -0.1778)
							(mid -0.239121 -0.213721)
							(end -0.2032 -0.2286)
						)
						(arc
							(start 0.2032 -0.2286)
							(mid 0.239121 -0.213721)
							(end 0.254 -0.1778)
						)
						(arc
							(start 0.254 0.1778)
							(mid 0.239121 0.213721)
							(end 0.2032 0.2286)
						)
						(arc
							(start -0.2032 0.2286)
							(mid -0.239121 0.213721)
							(end -0.254 0.1778)
						)
					)
					(width 0)
					(fill yes)
				)
			)
		)
	)
	(footprint ""
		(layer "F.Cu")
		(at 201.803 -21.717 180)
		(property "Reference" "PL7"
			(at 0 0 180)
			(layer "F.SilkS")
			(hide yes)
			(effects
				(font
					(size 1.27 1.27)
				)
			)
		)
		(property "Value" "BLM41PG600-GP"
			(at 0 -5.5372 180)
			(unlocked yes)
			(layer "F.Fab")
			(hide yes)
			(effects
				(font
					(size 1.016 1.016)
					(thickness 0.1524)
				)
			)
		)
		(property "Device Type" "L451616H71"
			(at 0 -7.0612 180)
			(unlocked yes)
			(layer "F.Fab")
			(hide yes)
			(effects
				(font
					(size 1.016 1.016)
					(thickness 0.1524)
				)
			)
		)
		(duplicate_pad_numbers_are_jumpers no)
		(fp_rect
			(start -1.0668 2.7559)
			(end 1.0668 -2.7559)
			(stroke
				(width 0)
				(type default)
			)
			(fill no)
			(layer "F.CrtYd")
		)
		(fp_rect
			(start -1.0668 2.7559)
			(end 1.0668 -2.7559)
			(stroke
				(width 0)
				(type default)
			)
			(fill no)
			(layer "F.Fab")
		)
		(pad "1" smd rect
			(at 0 -1.9558 180)
			(size 1.8796 1.3462)
			(layers "F.Cu" "F.Mask" "F.Paste")
			(net "P12V")
		)
		(pad "2" smd rect
			(at 0 1.9558 180)
			(size 1.8796 1.3462)
			(layers "F.Cu" "F.Mask" "F.Paste")
			(net "PVDDR_VIN")
		)
	)
	(footprint ""
		(layer "F.Cu")
		(at 33.147 -54.9656)
		(property "Reference" "PC23"
			(at 0 0 0)
			(layer "F.SilkS")
			(hide yes)
			(effects
				(font
					(size 1.27 1.27)
				)
			)
		)
		(property "Value" "SC10U25V5KX-GP"
			(at 0 -4.9022 0)
			(unlocked yes)
			(layer "F.Fab")
			(hide yes)
			(effects
				(font
					(size 1.016 1.016)
					(thickness 0.1524)
				)
			)
		)
		(property "Device Type" "C805H56"
			(at 0 -6.8072 0)
			(unlocked yes)
			(layer "F.Fab")
			(hide yes)
			(effects
				(font
					(size 1.016 1.016)
					(thickness 0.1524)
				)
			)
		)
		(duplicate_pad_numbers_are_jumpers no)
		(fp_line
			(start 0.6096 0)
			(end -0.6096 0)
			(stroke
				(width 0.3048)
				(type default)
			)
			(layer "F.SilkS")
		)
		(fp_poly
			(pts
				(xy -0.9017 1.4351) (xy 0.9017 1.4351) (xy 0.9017 -1.4351) (xy -0.9017 -1.4351)
			)
			(stroke
				(width 0)
				(type default)
			)
			(fill no)
			(layer "F.CrtYd")
		)
		(fp_poly
			(pts
				(xy 0.9017 1.4351) (xy 0.9017 -1.4351) (xy -0.9017 -1.4351) (xy -0.9017 1.4351)
			)
			(stroke
				(width 0)
				(type default)
			)
			(fill no)
			(layer "F.Fab")
		)
		(pad "1" smd rect
			(at 0 -0.8382)
			(size 1.5494 0.9398)
			(layers "F.Cu" "F.Mask" "F.Paste")
			(net "VR_FET_SW_P12V_PVCCP_PVNN")
		)
		(pad "2" smd rect
			(at 0 0.8382)
			(size 1.5494 0.9398)
			(layers "F.Cu" "F.Mask" "F.Paste")
			(net "GND")
		)
	)
	(footprint ""
		(layer "F.Cu")
		(at 153.035 -11.684 -90)
		(property "Reference" "C295"
			(at 0 0 270)
			(layer "F.SilkS")
			(hide yes)
			(effects
				(font
					(size 1.27 1.27)
				)
			)
		)
		(property "Value" "SCD1U16V2KX-3GP"
			(at 1.1811 -2.7051 270)
			(unlocked yes)
			(layer "F.Fab")
			(hide yes)
			(effects
				(font
					(size 1.016 1.016)
					(thickness 0.1524)
				)
			)
		)
		(property "Device Type" "C402H22"
			(at 1.1811 -4.2291 270)
			(unlocked yes)
			(layer "F.Fab")
			(hide yes)
			(effects
				(font
					(size 1.016 1.016)
					(thickness 0.1524)
				)
			)
		)
		(duplicate_pad_numbers_are_jumpers no)
		(fp_rect
			(start -0.381 0.7366)
			(end 0.381 -0.7366)
			(stroke
				(width 0)
				(type default)
			)
			(fill no)
			(layer "F.CrtYd")
		)
		(fp_rect
			(start -0.381 0.7366)
			(end 0.381 -0.7366)
			(stroke
				(width 0)
				(type default)
			)
			(fill no)
			(layer "F.Fab")
		)
		(pad "1" smd custom
			(at 0 -0.4572 270)
			(size 0.1143 0.1143)
			(layers "F.Cu" "F.Mask" "F.Paste")
			(net "DDR3_M_B_VREF_CA")
			(options
				(clearance outline)
				(anchor circle)
			)
			(primitives
				(gr_poly
					(pts
						(arc
							(start -0.254 -0.1778)
							(mid -0.239121 -0.213721)
							(end -0.2032 -0.2286)
						)
						(arc
							(start 0.2032 -0.2286)
							(mid 0.239121 -0.213721)
							(end 0.254 -0.1778)
						)
						(arc
							(start 0.254 0.1778)
							(mid 0.239121 0.213721)
							(end 0.2032 0.2286)
						)
						(arc
							(start -0.2032 0.2286)
							(mid -0.239121 0.213721)
							(end -0.254 0.1778)
						)
					)
					(width 0)
					(fill yes)
				)
			)
		)
		(pad "2" smd custom
			(at 0 0.4572 270)
			(size 0.1143 0.1143)
			(layers "F.Cu" "F.Mask" "F.Paste")
			(net "GND")
			(options
				(clearance outline)
				(anchor circle)
			)
			(primitives
				(gr_poly
					(pts
						(arc
							(start -0.254 -0.1778)
							(mid -0.239121 -0.213721)
							(end -0.2032 -0.2286)
						)
						(arc
							(start 0.2032 -0.2286)
							(mid 0.239121 -0.213721)
							(end 0.254 -0.1778)
						)
						(arc
							(start 0.254 0.1778)
							(mid 0.239121 0.213721)
							(end 0.2032 0.2286)
						)
						(arc
							(start -0.2032 0.2286)
							(mid -0.239121 0.213721)
							(end -0.254 0.1778)
						)
					)
					(width 0)
					(fill yes)
				)
			)
		)
	)
	(footprint ""
		(layer "F.Cu")
		(at 5.7658 -53.3654 90)
		(property "Reference" "R144"
			(at 0 0 90)
			(layer "F.SilkS")
			(hide yes)
			(effects
				(font
					(size 1.27 1.27)
				)
			)
		)
		(property "Value" "10KR2F-2-GP"
			(at 0.064008 -3.993896 90)
			(unlocked yes)
			(layer "F.Fab")
			(hide yes)
			(effects
				(font
					(size 1.016 1.016)
					(thickness 0.1524)
				)
			)
		)
		(property "Device Type" "R402H16"
			(at 0.064008 -5.517896 90)
			(unlocked yes)
			(layer "F.Fab")
			(hide yes)
			(effects
				(font
					(size 1.016 1.016)
					(thickness 0.1524)
				)
			)
		)
		(duplicate_pad_numbers_are_jumpers no)
		(fp_rect
			(start -0.381 0.8382)
			(end 0.381 -0.8382)
			(stroke
				(width 0)
				(type default)
			)
			(fill no)
			(layer "F.CrtYd")
		)
		(fp_rect
			(start -0.381 0.8382)
			(end 0.381 -0.8382)
			(stroke
				(width 0)
				(type default)
			)
			(fill no)
			(layer "F.Fab")
		)
		(pad "1" smd custom
			(at 0 -0.4318 90)
			(size 0.127 0.127)
			(layers "F.Cu" "F.Mask" "F.Paste")
			(net "PEDET_SEL")
			(options
				(clearance outline)
				(anchor circle)
			)
			(primitives
				(gr_poly
					(pts
						(arc
							(start -0.2032 -0.2794)
							(mid -0.239121 -0.264521)
							(end -0.254 -0.2286)
						)
						(arc
							(start -0.254 0.2286)
							(mid -0.239121 0.264521)
							(end -0.2032 0.2794)
						)
						(arc
							(start 0.2032 0.2794)
							(mid 0.239121 0.264521)
							(end 0.254 0.2286)
						)
						(arc
							(start 0.254 -0.2286)
							(mid 0.239121 -0.264521)
							(end 0.2032 -0.2794)
						)
					)
					(width 0)
					(fill yes)
				)
			)
		)
		(pad "2" smd custom
			(at 0 0.4318 90)
			(size 0.127 0.127)
			(layers "F.Cu" "F.Mask" "F.Paste")
			(net "GND")
			(options
				(clearance outline)
				(anchor circle)
			)
			(primitives
				(gr_poly
					(pts
						(arc
							(start -0.2032 -0.2794)
							(mid -0.239121 -0.264521)
							(end -0.254 -0.2286)
						)
						(arc
							(start -0.254 0.2286)
							(mid -0.239121 0.264521)
							(end -0.2032 0.2794)
						)
						(arc
							(start 0.2032 0.2794)
							(mid 0.239121 0.264521)
							(end 0.254 0.2286)
						)
						(arc
							(start 0.254 -0.2286)
							(mid 0.239121 -0.264521)
							(end 0.2032 -0.2794)
						)
					)
					(width 0)
					(fill yes)
				)
			)
		)
	)
	(footprint ""
		(layer "F.Cu")
		(at 12.1412 -52.7812 90)
		(property "Reference" "C57"
			(at 0 0 90)
			(layer "F.SilkS")
			(hide yes)
			(effects
				(font
					(size 1.27 1.27)
				)
			)
		)
		(property "Value" "SCD1U16V2KX-3GP"
			(at 1.1811 -2.7051 90)
			(unlocked yes)
			(layer "F.Fab")
			(hide yes)
			(effects
				(font
					(size 1.016 1.016)
					(thickness 0.1524)
				)
			)
		)
		(property "Device Type" "C402H22"
			(at 1.1811 -4.2291 90)
			(unlocked yes)
			(layer "F.Fab")
			(hide yes)
			(effects
				(font
					(size 1.016 1.016)
					(thickness 0.1524)
				)
			)
		)
		(duplicate_pad_numbers_are_jumpers no)
		(fp_rect
			(start -0.381 0.7366)
			(end 0.381 -0.7366)
			(stroke
				(width 0)
				(type default)
			)
			(fill no)
			(layer "F.CrtYd")
		)
		(fp_rect
			(start -0.381 0.7366)
			(end 0.381 -0.7366)
			(stroke
				(width 0)
				(type default)
			)
			(fill no)
			(layer "F.Fab")
		)
		(pad "1" smd custom
			(at 0 -0.4572 90)
			(size 0.1143 0.1143)
			(layers "F.Cu" "F.Mask" "F.Paste")
			(net "P2E_CPU_NGFF_C_RX_DP12")
			(options
				(clearance outline)
				(anchor circle)
			)
			(primitives
				(gr_poly
					(pts
						(arc
							(start -0.254 -0.1778)
							(mid -0.239121 -0.213721)
							(end -0.2032 -0.2286)
						)
						(arc
							(start 0.2032 -0.2286)
							(mid 0.239121 -0.213721)
							(end 0.254 -0.1778)
						)
						(arc
							(start 0.254 0.1778)
							(mid 0.239121 0.213721)
							(end 0.2032 0.2286)
						)
						(arc
							(start -0.2032 0.2286)
							(mid -0.239121 0.213721)
							(end -0.254 0.1778)
						)
					)
					(width 0)
					(fill yes)
				)
			)
		)
		(pad "2" smd custom
			(at 0 0.4572 90)
			(size 0.1143 0.1143)
			(layers "F.Cu" "F.Mask" "F.Paste")
			(net "P2E_CPU_NGFF_RX_DP12")
			(options
				(clearance outline)
				(anchor circle)
			)
			(primitives
				(gr_poly
					(pts
						(arc
							(start -0.254 -0.1778)
							(mid -0.239121 -0.213721)
							(end -0.2032 -0.2286)
						)
						(arc
							(start 0.2032 -0.2286)
							(mid 0.239121 -0.213721)
							(end 0.254 -0.1778)
						)
						(arc
							(start 0.254 0.1778)
							(mid 0.239121 0.213721)
							(end 0.2032 0.2286)
						)
						(arc
							(start -0.2032 0.2286)
							(mid -0.239121 0.213721)
							(end -0.254 0.1778)
						)
					)
					(width 0)
					(fill yes)
				)
			)
		)
	)
	(footprint ""
		(layer "F.Cu")
		(at 32.893 -18.415)
		(property "Reference" "R265"
			(at 0 0 0)
			(layer "F.SilkS")
			(hide yes)
			(effects
				(font
					(size 1.27 1.27)
				)
			)
		)
		(property "Value" "0R2J-2-GP"
			(at 0.064008 -3.993896 0)
			(unlocked yes)
			(layer "F.Fab")
			(hide yes)
			(effects
				(font
					(size 1.016 1.016)
					(thickness 0.1524)
				)
			)
		)
		(property "Device Type" "R402H16"
			(at 0.064008 -5.517896 0)
			(unlocked yes)
			(layer "F.Fab")
			(hide yes)
			(effects
				(font
					(size 1.016 1.016)
					(thickness 0.1524)
				)
			)
		)
		(duplicate_pad_numbers_are_jumpers no)
		(fp_rect
			(start -0.381 0.8382)
			(end 0.381 -0.8382)
			(stroke
				(width 0)
				(type default)
			)
			(fill no)
			(layer "F.CrtYd")
		)
		(fp_rect
			(start -0.381 0.8382)
			(end 0.381 -0.8382)
			(stroke
				(width 0)
				(type default)
			)
			(fill no)
			(layer "F.Fab")
		)
		(pad "1" smd custom
			(at 0 -0.4318)
			(size 0.127 0.127)
			(layers "F.Cu" "F.Mask" "F.Paste")
			(net "XDP_DFX_PORT_R_CLK0")
			(options
				(clearance outline)
				(anchor circle)
			)
			(primitives
				(gr_poly
					(pts
						(arc
							(start -0.2032 -0.2794)
							(mid -0.239121 -0.264521)
							(end -0.254 -0.2286)
						)
						(arc
							(start -0.254 0.2286)
							(mid -0.239121 0.264521)
							(end -0.2032 0.2794)
						)
						(arc
							(start 0.2032 0.2794)
							(mid 0.239121 0.264521)
							(end 0.254 0.2286)
						)
						(arc
							(start 0.254 -0.2286)
							(mid 0.239121 -0.264521)
							(end 0.2032 -0.2794)
						)
					)
					(width 0)
					(fill yes)
				)
			)
		)
		(pad "2" smd custom
			(at 0 0.4318)
			(size 0.127 0.127)
			(layers "F.Cu" "F.Mask" "F.Paste")
			(net "XDP_DFX_PORT_CLK0")
			(options
				(clearance outline)
				(anchor circle)
			)
			(primitives
				(gr_poly
					(pts
						(arc
							(start -0.2032 -0.2794)
							(mid -0.239121 -0.264521)
							(end -0.254 -0.2286)
						)
						(arc
							(start -0.254 0.2286)
							(mid -0.239121 0.264521)
							(end -0.2032 0.2794)
						)
						(arc
							(start 0.2032 0.2794)
							(mid 0.239121 0.264521)
							(end 0.254 0.2286)
						)
						(arc
							(start 0.254 -0.2286)
							(mid 0.239121 -0.264521)
							(end 0.2032 -0.2794)
						)
					)
					(width 0)
					(fill yes)
				)
			)
		)
	)
	(footprint ""
		(layer "F.Cu")
		(at 44.323 -18.415 -90)
		(property "Reference" "R363"
			(at 0 0 270)
			(layer "F.SilkS")
			(hide yes)
			(effects
				(font
					(size 1.27 1.27)
				)
			)
		)
		(property "Value" "4K7R2F-GP"
			(at 0.064008 -3.993896 270)
			(unlocked yes)
			(layer "F.Fab")
			(hide yes)
			(effects
				(font
					(size 1.016 1.016)
					(thickness 0.1524)
				)
			)
		)
		(property "Device Type" "R402H16"
			(at 0.064008 -5.517896 270)
			(unlocked yes)
			(layer "F.Fab")
			(hide yes)
			(effects
				(font
					(size 1.016 1.016)
					(thickness 0.1524)
				)
			)
		)
		(duplicate_pad_numbers_are_jumpers no)
		(fp_rect
			(start -0.381 0.8382)
			(end 0.381 -0.8382)
			(stroke
				(width 0)
				(type default)
			)
			(fill no)
			(layer "F.CrtYd")
		)
		(fp_rect
			(start -0.381 0.8382)
			(end 0.381 -0.8382)
			(stroke
				(width 0)
				(type default)
			)
			(fill no)
			(layer "F.Fab")
		)
		(pad "1" smd custom
			(at 0 -0.4318 270)
			(size 0.127 0.127)
			(layers "F.Cu" "F.Mask" "F.Paste")
			(net "CLKBUFF_OE2#")
			(options
				(clearance outline)
				(anchor circle)
			)
			(primitives
				(gr_poly
					(pts
						(arc
							(start -0.2032 -0.2794)
							(mid -0.239121 -0.264521)
							(end -0.254 -0.2286)
						)
						(arc
							(start -0.254 0.2286)
							(mid -0.239121 0.264521)
							(end -0.2032 0.2794)
						)
						(arc
							(start 0.2032 0.2794)
							(mid 0.239121 0.264521)
							(end 0.254 0.2286)
						)
						(arc
							(start 0.254 -0.2286)
							(mid 0.239121 -0.264521)
							(end 0.2032 -0.2794)
						)
					)
					(width 0)
					(fill yes)
				)
			)
		)
		(pad "2" smd custom
			(at 0 0.4318 270)
			(size 0.127 0.127)
			(layers "F.Cu" "F.Mask" "F.Paste")
			(net "GND")
			(options
				(clearance outline)
				(anchor circle)
			)
			(primitives
				(gr_poly
					(pts
						(arc
							(start -0.2032 -0.2794)
							(mid -0.239121 -0.264521)
							(end -0.254 -0.2286)
						)
						(arc
							(start -0.254 0.2286)
							(mid -0.239121 0.264521)
							(end -0.2032 0.2794)
						)
						(arc
							(start 0.2032 0.2794)
							(mid 0.239121 0.264521)
							(end 0.254 0.2286)
						)
						(arc
							(start 0.254 -0.2286)
							(mid 0.239121 -0.264521)
							(end 0.2032 -0.2794)
						)
					)
					(width 0)
					(fill yes)
				)
			)
		)
	)
	(footprint ""
		(layer "F.Cu")
		(at 46.355 -22.733)
		(property "Reference" "C207"
			(at 0 0 0)
			(layer "F.SilkS")
			(hide yes)
			(effects
				(font
					(size 1.27 1.27)
				)
			)
		)
		(property "Value" "SCD1U10V2KX-5GP"
			(at 1.1811 -2.7051 0)
			(unlocked yes)
			(layer "F.Fab")
			(hide yes)
			(effects
				(font
					(size 1.016 1.016)
					(thickness 0.1524)
				)
			)
		)
		(property "Device Type" "C402H22"
			(at 1.1811 -4.2291 0)
			(unlocked yes)
			(layer "F.Fab")
			(hide yes)
			(effects
				(font
					(size 1.016 1.016)
					(thickness 0.1524)
				)
			)
		)
		(duplicate_pad_numbers_are_jumpers no)
		(fp_rect
			(start -0.381 0.7366)
			(end 0.381 -0.7366)
			(stroke
				(width 0)
				(type default)
			)
			(fill no)
			(layer "F.CrtYd")
		)
		(fp_rect
			(start -0.381 0.7366)
			(end 0.381 -0.7366)
			(stroke
				(width 0)
				(type default)
			)
			(fill no)
			(layer "F.Fab")
		)
		(pad "1" smd custom
			(at 0 -0.4572)
			(size 0.1143 0.1143)
			(layers "F.Cu" "F.Mask" "F.Paste")
			(net "P3V3_VDD_CLKBUFF")
			(options
				(clearance outline)
				(anchor circle)
			)
			(primitives
				(gr_poly
					(pts
						(arc
							(start -0.254 -0.1778)
							(mid -0.239121 -0.213721)
							(end -0.2032 -0.2286)
						)
						(arc
							(start 0.2032 -0.2286)
							(mid 0.239121 -0.213721)
							(end 0.254 -0.1778)
						)
						(arc
							(start 0.254 0.1778)
							(mid 0.239121 0.213721)
							(end 0.2032 0.2286)
						)
						(arc
							(start -0.2032 0.2286)
							(mid -0.239121 0.213721)
							(end -0.254 0.1778)
						)
					)
					(width 0)
					(fill yes)
				)
			)
		)
		(pad "2" smd custom
			(at 0 0.4572)
			(size 0.1143 0.1143)
			(layers "F.Cu" "F.Mask" "F.Paste")
			(net "GND")
			(options
				(clearance outline)
				(anchor circle)
			)
			(primitives
				(gr_poly
					(pts
						(arc
							(start -0.254 -0.1778)
							(mid -0.239121 -0.213721)
							(end -0.2032 -0.2286)
						)
						(arc
							(start 0.2032 -0.2286)
							(mid 0.239121 -0.213721)
							(end 0.254 -0.1778)
						)
						(arc
							(start 0.254 0.1778)
							(mid 0.239121 0.213721)
							(end 0.2032 0.2286)
						)
						(arc
							(start -0.2032 0.2286)
							(mid -0.239121 0.213721)
							(end -0.254 0.1778)
						)
					)
					(width 0)
					(fill yes)
				)
			)
		)
	)
	(footprint ""
		(layer "F.Cu")
		(at 9.4488 -47.498 -90)
		(property "Reference" "R12"
			(at 0 0 270)
			(layer "F.SilkS")
			(hide yes)
			(effects
				(font
					(size 1.27 1.27)
				)
			)
		)
		(property "Value" "4K7R2F-GP"
			(at 0.064008 -3.993896 270)
			(unlocked yes)
			(layer "F.Fab")
			(hide yes)
			(effects
				(font
					(size 1.016 1.016)
					(thickness 0.1524)
				)
			)
		)
		(property "Device Type" "R402H16"
			(at 0.064008 -5.517896 270)
			(unlocked yes)
			(layer "F.Fab")
			(hide yes)
			(effects
				(font
					(size 1.016 1.016)
					(thickness 0.1524)
				)
			)
		)
		(duplicate_pad_numbers_are_jumpers no)
		(fp_rect
			(start -0.381 0.8382)
			(end 0.381 -0.8382)
			(stroke
				(width 0)
				(type default)
			)
			(fill no)
			(layer "F.CrtYd")
		)
		(fp_rect
			(start -0.381 0.8382)
			(end 0.381 -0.8382)
			(stroke
				(width 0)
				(type default)
			)
			(fill no)
			(layer "F.Fab")
		)
		(pad "1" smd custom
			(at 0 -0.4318 270)
			(size 0.127 0.127)
			(layers "F.Cu" "F.Mask" "F.Paste")
			(net "P3V3_STBY")
			(options
				(clearance outline)
				(anchor circle)
			)
			(primitives
				(gr_poly
					(pts
						(arc
							(start -0.2032 -0.2794)
							(mid -0.239121 -0.264521)
							(end -0.254 -0.2286)
						)
						(arc
							(start -0.254 0.2286)
							(mid -0.239121 0.264521)
							(end -0.2032 0.2794)
						)
						(arc
							(start 0.2032 0.2794)
							(mid 0.239121 0.264521)
							(end 0.254 0.2286)
						)
						(arc
							(start 0.254 -0.2286)
							(mid 0.239121 -0.264521)
							(end 0.2032 -0.2794)
						)
					)
					(width 0)
					(fill yes)
				)
			)
		)
		(pad "2" smd custom
			(at 0 0.4318 270)
			(size 0.127 0.127)
			(layers "F.Cu" "F.Mask" "F.Paste")
			(net "TEMP_1_A2")
			(options
				(clearance outline)
				(anchor circle)
			)
			(primitives
				(gr_poly
					(pts
						(arc
							(start -0.2032 -0.2794)
							(mid -0.239121 -0.264521)
							(end -0.254 -0.2286)
						)
						(arc
							(start -0.254 0.2286)
							(mid -0.239121 0.264521)
							(end -0.2032 0.2794)
						)
						(arc
							(start 0.2032 0.2794)
							(mid 0.239121 0.264521)
							(end 0.254 0.2286)
						)
						(arc
							(start 0.254 -0.2286)
							(mid 0.239121 -0.264521)
							(end 0.2032 -0.2794)
						)
					)
					(width 0)
					(fill yes)
				)
			)
		)
	)
	(footprint ""
		(layer "F.Cu")
		(at 31.75 -15.748)
		(property "Reference" "R417"
			(at 0 0 0)
			(layer "F.SilkS")
			(hide yes)
			(effects
				(font
					(size 1.27 1.27)
				)
			)
		)
		(property "Value" "0R2J-2-GP"
			(at 1.7907 -1.1176 0)
			(unlocked yes)
			(layer "F.Fab")
			(hide yes)
			(effects
				(font
					(size 1.016 1.016)
					(thickness 0.1524)
				)
			)
		)
		(property "Device Type" "R402H16"
			(at 1.7907 -2.6416 0)
			(unlocked yes)
			(layer "F.Fab")
			(hide yes)
			(effects
				(font
					(size 1.016 1.016)
					(thickness 0.1524)
				)
			)
		)
		(duplicate_pad_numbers_are_jumpers no)
		(fp_rect
			(start -0.381 0.8382)
			(end 0.381 -0.8382)
			(stroke
				(width 0)
				(type default)
			)
			(fill no)
			(layer "F.CrtYd")
		)
		(fp_rect
			(start -0.381 0.8382)
			(end 0.381 -0.8382)
			(stroke
				(width 0)
				(type default)
			)
			(fill no)
			(layer "F.Fab")
		)
		(pad "1" smd custom
			(at 0 -0.4318)
			(size 0.127 0.127)
			(layers "F.Cu" "F.Mask" "F.Paste")
			(net "CPU_RSMRST#")
			(options
				(clearance outline)
				(anchor circle)
			)
			(primitives
				(gr_poly
					(pts
						(arc
							(start -0.2032 -0.2794)
							(mid -0.239121 -0.264521)
							(end -0.254 -0.2286)
						)
						(arc
							(start -0.254 0.2286)
							(mid -0.239121 0.264521)
							(end -0.2032 0.2794)
						)
						(arc
							(start 0.2032 0.2794)
							(mid 0.239121 0.264521)
							(end 0.254 0.2286)
						)
						(arc
							(start 0.254 -0.2286)
							(mid 0.239121 -0.264521)
							(end 0.2032 -0.2794)
						)
					)
					(width 0)
					(fill yes)
				)
			)
		)
		(pad "2" smd custom
			(at 0 0.4318)
			(size 0.127 0.127)
			(layers "F.Cu" "F.Mask" "F.Paste")
			(net "PICE_GF_I2C_SW_EN")
			(options
				(clearance outline)
				(anchor circle)
			)
			(primitives
				(gr_poly
					(pts
						(arc
							(start -0.2032 -0.2794)
							(mid -0.239121 -0.264521)
							(end -0.254 -0.2286)
						)
						(arc
							(start -0.254 0.2286)
							(mid -0.239121 0.264521)
							(end -0.2032 0.2794)
						)
						(arc
							(start 0.2032 0.2794)
							(mid 0.239121 0.264521)
							(end 0.254 0.2286)
						)
						(arc
							(start 0.254 -0.2286)
							(mid 0.239121 -0.264521)
							(end 0.2032 -0.2794)
						)
					)
					(width 0)
					(fill yes)
				)
			)
		)
	)
	(footprint ""
		(layer "F.Cu")
		(at 101.0666 -68.8594)
		(property "Reference" "PR8"
			(at 0 0 0)
			(layer "F.SilkS")
			(hide yes)
			(effects
				(font
					(size 1.27 1.27)
				)
			)
		)
		(property "Value" "0R2J-2-GP"
			(at 0.064008 -3.993896 0)
			(unlocked yes)
			(layer "F.Fab")
			(hide yes)
			(effects
				(font
					(size 1.016 1.016)
					(thickness 0.1524)
				)
			)
		)
		(property "Device Type" "R402H16"
			(at 0.064008 -5.517896 0)
			(unlocked yes)
			(layer "F.Fab")
			(hide yes)
			(effects
				(font
					(size 1.016 1.016)
					(thickness 0.1524)
				)
			)
		)
		(duplicate_pad_numbers_are_jumpers no)
		(fp_rect
			(start -0.381 0.8382)
			(end 0.381 -0.8382)
			(stroke
				(width 0)
				(type default)
			)
			(fill no)
			(layer "F.CrtYd")
		)
		(fp_rect
			(start -0.381 0.8382)
			(end 0.381 -0.8382)
			(stroke
				(width 0)
				(type default)
			)
			(fill no)
			(layer "F.Fab")
		)
		(pad "1" smd custom
			(at 0 -0.4318)
			(size 0.127 0.127)
			(layers "F.Cu" "F.Mask" "F.Paste")
			(net "PWRGD_PVCCP_VNN_PG")
			(options
				(clearance outline)
				(anchor circle)
			)
			(primitives
				(gr_poly
					(pts
						(arc
							(start -0.2032 -0.2794)
							(mid -0.239121 -0.264521)
							(end -0.254 -0.2286)
						)
						(arc
							(start -0.254 0.2286)
							(mid -0.239121 0.264521)
							(end -0.2032 0.2794)
						)
						(arc
							(start 0.2032 0.2794)
							(mid 0.239121 0.264521)
							(end 0.254 0.2286)
						)
						(arc
							(start 0.254 -0.2286)
							(mid 0.239121 -0.264521)
							(end 0.2032 -0.2794)
						)
					)
					(width 0)
					(fill yes)
				)
			)
		)
		(pad "2" smd custom
			(at 0 0.4318)
			(size 0.127 0.127)
			(layers "F.Cu" "F.Mask" "F.Paste")
			(net "VR_P1V1_EN")
			(options
				(clearance outline)
				(anchor circle)
			)
			(primitives
				(gr_poly
					(pts
						(arc
							(start -0.2032 -0.2794)
							(mid -0.239121 -0.264521)
							(end -0.254 -0.2286)
						)
						(arc
							(start -0.254 0.2286)
							(mid -0.239121 0.264521)
							(end -0.2032 0.2794)
						)
						(arc
							(start 0.2032 0.2794)
							(mid 0.239121 0.264521)
							(end 0.254 0.2286)
						)
						(arc
							(start 0.254 -0.2286)
							(mid 0.239121 -0.264521)
							(end 0.2032 -0.2794)
						)
					)
					(width 0)
					(fill yes)
				)
			)
		)
	)
	(footprint ""
		(layer "F.Cu")
		(at 22.733 -65.1764 180)
		(property "Reference" "PR29"
			(at 0 0 180)
			(layer "F.SilkS")
			(hide yes)
			(effects
				(font
					(size 1.27 1.27)
				)
			)
		)
		(property "Value" "100R2F-L1-GP-U"
			(at 1.7907 -1.1176 180)
			(unlocked yes)
			(layer "F.Fab")
			(hide yes)
			(effects
				(font
					(size 1.016 1.016)
					(thickness 0.1524)
				)
			)
		)
		(property "Device Type" "R402H14"
			(at 1.7907 -2.6416 180)
			(unlocked yes)
			(layer "F.Fab")
			(hide yes)
			(effects
				(font
					(size 1.016 1.016)
					(thickness 0.1524)
				)
			)
		)
		(duplicate_pad_numbers_are_jumpers no)
		(fp_rect
			(start -0.381 0.8382)
			(end 0.381 -0.8382)
			(stroke
				(width 0)
				(type default)
			)
			(fill no)
			(layer "F.CrtYd")
		)
		(fp_rect
			(start -0.381 0.8382)
			(end 0.381 -0.8382)
			(stroke
				(width 0)
				(type default)
			)
			(fill no)
			(layer "F.Fab")
		)
		(pad "1" smd custom
			(at 0 -0.4318 180)
			(size 0.127 0.127)
			(layers "F.Cu" "F.Mask" "F.Paste")
			(net "VR_PVNN_ISUMN_R")
			(options
				(clearance outline)
				(anchor circle)
			)
			(primitives
				(gr_poly
					(pts
						(arc
							(start -0.2032 -0.2794)
							(mid -0.239121 -0.264521)
							(end -0.254 -0.2286)
						)
						(arc
							(start -0.254 0.2286)
							(mid -0.239121 0.264521)
							(end -0.2032 0.2794)
						)
						(arc
							(start 0.2032 0.2794)
							(mid 0.239121 0.264521)
							(end 0.254 0.2286)
						)
						(arc
							(start 0.254 -0.2286)
							(mid 0.239121 -0.264521)
							(end 0.2032 -0.2794)
						)
					)
					(width 0)
					(fill yes)
				)
			)
		)
		(pad "2" smd custom
			(at 0 0.4318 180)
			(size 0.127 0.127)
			(layers "F.Cu" "F.Mask" "F.Paste")
			(net "VR_PVNN_ISUMN_RC")
			(options
				(clearance outline)
				(anchor circle)
			)
			(primitives
				(gr_poly
					(pts
						(arc
							(start -0.2032 -0.2794)
							(mid -0.239121 -0.264521)
							(end -0.254 -0.2286)
						)
						(arc
							(start -0.254 0.2286)
							(mid -0.239121 0.264521)
							(end -0.2032 0.2794)
						)
						(arc
							(start 0.2032 0.2794)
							(mid 0.239121 0.264521)
							(end 0.254 0.2286)
						)
						(arc
							(start 0.254 -0.2286)
							(mid 0.239121 -0.264521)
							(end 0.2032 -0.2794)
						)
					)
					(width 0)
					(fill yes)
				)
			)
		)
	)
	(footprint ""
		(layer "F.Cu")
		(at 167.894 -24.765 -90)
		(property "Reference" "PC98"
			(at 0 0 270)
			(layer "F.SilkS")
			(hide yes)
			(effects
				(font
					(size 1.27 1.27)
				)
			)
		)
		(property "Value" "SC10U6D3V5KX-4GP"
			(at -0.0762 -6.1214 270)
			(unlocked yes)
			(layer "F.Fab")
			(hide yes)
			(effects
				(font
					(size 1.016 1.016)
					(thickness 0.1524)
				)
			)
		)
		(property "Device Type" "C805H58"
			(at -0.0762 -8.1534 270)
			(unlocked yes)
			(layer "F.Fab")
			(hide yes)
			(effects
				(font
					(size 1.016 1.016)
					(thickness 0.1524)
				)
			)
		)
		(duplicate_pad_numbers_are_jumpers no)
		(fp_line
			(start 0.6096 0)
			(end -0.6096 0)
			(stroke
				(width 0.3048)
				(type default)
			)
			(layer "F.SilkS")
		)
		(fp_poly
			(pts
				(xy -0.9017 1.4351) (xy 0.9017 1.4351) (xy 0.9017 -1.4351) (xy -0.9017 -1.4351)
			)
			(stroke
				(width 0)
				(type default)
			)
			(fill no)
			(layer "F.CrtYd")
		)
		(fp_poly
			(pts
				(xy 0.9017 1.4351) (xy 0.9017 -1.4351) (xy -0.9017 -1.4351) (xy -0.9017 1.4351)
			)
			(stroke
				(width 0)
				(type default)
			)
			(fill no)
			(layer "F.Fab")
		)
		(pad "1" smd rect
			(at 0 -0.8382 270)
			(size 1.5494 0.9398)
			(layers "F.Cu" "F.Mask" "F.Paste")
			(net "P1V8_STBY_LDO_IN2")
		)
		(pad "2" smd rect
			(at 0 0.8382 270)
			(size 1.5494 0.9398)
			(layers "F.Cu" "F.Mask" "F.Paste")
			(net "GND")
		)
	)
	(footprint ""
		(layer "F.Cu")
		(at 134.62 -18.796)
		(property "Reference" "R51"
			(at 0 0 0)
			(layer "F.SilkS")
			(hide yes)
			(effects
				(font
					(size 1.27 1.27)
				)
			)
		)
		(property "Value" "4K7R2F-GP"
			(at 0.064008 -3.993896 0)
			(unlocked yes)
			(layer "F.Fab")
			(hide yes)
			(effects
				(font
					(size 1.016 1.016)
					(thickness 0.1524)
				)
			)
		)
		(property "Device Type" "R402H16"
			(at 0.064008 -5.517896 0)
			(unlocked yes)
			(layer "F.Fab")
			(hide yes)
			(effects
				(font
					(size 1.016 1.016)
					(thickness 0.1524)
				)
			)
		)
		(duplicate_pad_numbers_are_jumpers no)
		(fp_rect
			(start -0.381 0.8382)
			(end 0.381 -0.8382)
			(stroke
				(width 0)
				(type default)
			)
			(fill no)
			(layer "F.CrtYd")
		)
		(fp_rect
			(start -0.381 0.8382)
			(end 0.381 -0.8382)
			(stroke
				(width 0)
				(type default)
			)
			(fill no)
			(layer "F.Fab")
		)
		(pad "1" smd custom
			(at 0 -0.4318)
			(size 0.127 0.127)
			(layers "F.Cu" "F.Mask" "F.Paste")
			(net "P3V3_STBY")
			(options
				(clearance outline)
				(anchor circle)
			)
			(primitives
				(gr_poly
					(pts
						(arc
							(start -0.2032 -0.2794)
							(mid -0.239121 -0.264521)
							(end -0.254 -0.2286)
						)
						(arc
							(start -0.254 0.2286)
							(mid -0.239121 0.264521)
							(end -0.2032 0.2794)
						)
						(arc
							(start 0.2032 0.2794)
							(mid 0.239121 0.264521)
							(end 0.254 0.2286)
						)
						(arc
							(start 0.254 -0.2286)
							(mid 0.239121 -0.264521)
							(end 0.2032 -0.2794)
						)
					)
					(width 0)
					(fill yes)
				)
			)
		)
		(pad "2" smd custom
			(at 0 0.4318)
			(size 0.127 0.127)
			(layers "F.Cu" "F.Mask" "F.Paste")
			(net "FPGA_PWRBTN#")
			(options
				(clearance outline)
				(anchor circle)
			)
			(primitives
				(gr_poly
					(pts
						(arc
							(start -0.2032 -0.2794)
							(mid -0.239121 -0.264521)
							(end -0.254 -0.2286)
						)
						(arc
							(start -0.254 0.2286)
							(mid -0.239121 0.264521)
							(end -0.2032 0.2794)
						)
						(arc
							(start 0.2032 0.2794)
							(mid 0.239121 0.264521)
							(end 0.254 0.2286)
						)
						(arc
							(start 0.254 -0.2286)
							(mid 0.239121 -0.264521)
							(end 0.2032 -0.2794)
						)
					)
					(width 0)
					(fill yes)
				)
			)
		)
	)
	(footprint ""
		(layer "F.Cu")
		(at 158.500064 -66.699892 180)
		(property "Reference" "DIMM2"
			(at 0 0 180)
			(layer "F.SilkS")
			(hide yes)
			(effects
				(font
					(size 1.27 1.27)
				)
			)
		)
		(property "Value" "DDR3-204P-174-COLAY-1-GP"
			(at -40.682164 -17.468088 180)
			(unlocked yes)
			(layer "F.Fab")
			(hide yes)
			(effects
				(font
					(size 1.016 1.016)
					(thickness 0.1524)
				)
			)
		)
		(property "Device Type" "AS0A626-H8SN-7H-COLAY-1"
			(at -40.682164 -18.992088 180)
			(unlocked yes)
			(layer "F.Fab")
			(hide yes)
			(effects
				(font
					(size 1.016 1.016)
					(thickness 0.1524)
				)
			)
		)
		(duplicate_pad_numbers_are_jumpers no)
		(fp_line
			(start 39.9542 -7.6327)
			(end 37.2491 -7.6327)
			(stroke
				(width 0.1524)
				(type default)
			)
			(layer "F.SilkS")
		)
		(fp_line
			(start 39.9542 -14.9606)
			(end 39.9542 -7.6327)
			(stroke
				(width 0.1524)
				(type default)
			)
			(layer "F.SilkS")
		)
		(fp_line
			(start 38.2524 -14.9606)
			(end 39.9542 -14.9606)
			(stroke
				(width 0.1524)
				(type default)
			)
			(layer "F.SilkS")
		)
		(fp_line
			(start 38.2524 -23.749)
			(end 38.2524 -14.9606)
			(stroke
				(width 0.1524)
				(type default)
			)
			(layer "F.SilkS")
		)
		(fp_line
			(start 37.2491 0.254)
			(end 36.2585 0.254)
			(stroke
				(width 0.1524)
				(type default)
			)
			(layer "F.SilkS")
		)
		(fp_line
			(start 37.2491 -7.6327)
			(end 37.2491 0.254)
			(stroke
				(width 0.1524)
				(type default)
			)
			(layer "F.SilkS")
		)
		(fp_line
			(start 36.2585 5.2578)
			(end -36.2585 5.2578)
			(stroke
				(width 0.1524)
				(type default)
			)
			(layer "F.SilkS")
		)
		(fp_line
			(start 36.2585 0.254)
			(end 36.2585 5.2578)
			(stroke
				(width 0.1524)
				(type default)
			)
			(layer "F.SilkS")
		)
		(fp_line
			(start 32.131 -5.7785)
			(end 31.1658 -5.7785)
			(stroke
				(width 0.1524)
				(type default)
			)
			(layer "F.SilkS")
		)
		(fp_line
			(start 31.8008 -21.3106)
			(end 31.8008 -23.749)
			(stroke
				(width 0.1524)
				(type default)
			)
			(layer "F.SilkS")
		)
		(fp_line
			(start 31.8008 -23.749)
			(end 38.2524 -23.749)
			(stroke
				(width 0.1524)
				(type default)
			)
			(layer "F.SilkS")
		)
		(fp_line
			(start 31.6484 -5.2959)
			(end 32.131 -5.7785)
			(stroke
				(width 0.1524)
				(type default)
			)
			(layer "F.SilkS")
		)
		(fp_line
			(start 31.6357 -5.2832)
			(end 31.6357 -6.4008)
			(stroke
				(width 0.1524)
				(type default)
			)
			(layer "F.SilkS")
		)
		(fp_line
			(start 31.3436 -5.2578)
			(end 31.3436 -9.4488)
			(stroke
				(width 0.1524)
				(type default)
			)
			(layer "F.SilkS")
		)
		(fp_line
			(start 31.3436 -9.4488)
			(end 30.7975 -9.4488)
			(stroke
				(width 0.1524)
				(type default)
			)
			(layer "F.SilkS")
		)
		(fp_line
			(start 31.3436 -14.5542)
			(end 31.3436 -21.3106)
			(stroke
				(width 0.1524)
				(type default)
			)
			(layer "F.SilkS")
		)
		(fp_line
			(start 31.3436 -21.3106)
			(end 31.8008 -21.3106)
			(stroke
				(width 0.1524)
				(type default)
			)
			(layer "F.SilkS")
		)
		(fp_line
			(start 31.1658 -5.7531)
			(end 31.6357 -5.2832)
			(stroke
				(width 0.1524)
				(type default)
			)
			(layer "F.SilkS")
		)
		(fp_line
			(start 31.1658 -5.7785)
			(end 31.1658 -5.7531)
			(stroke
				(width 0.1524)
				(type default)
			)
			(layer "F.SilkS")
		)
		(fp_line
			(start 30.7975 -9.4488)
			(end 30.7975 -14.5542)
			(stroke
				(width 0.1524)
				(type default)
			)
			(layer "F.SilkS")
		)
		(fp_line
			(start 30.7975 -14.5542)
			(end 31.3436 -14.5542)
			(stroke
				(width 0.1524)
				(type default)
			)
			(layer "F.SilkS")
		)
		(fp_line
			(start -30.7975 -9.4488)
			(end -31.3436 -9.4488)
			(stroke
				(width 0.1524)
				(type default)
			)
			(layer "F.SilkS")
		)
		(fp_line
			(start -30.7975 -14.5542)
			(end -30.7975 -9.4488)
			(stroke
				(width 0.1524)
				(type default)
			)
			(layer "F.SilkS")
		)
		(fp_line
			(start -31.1531 5.8166)
			(end -31.1531 5.7658)
			(stroke
				(width 0.1524)
				(type default)
			)
			(layer "F.SilkS")
		)
		(fp_line
			(start -31.1531 5.7658)
			(end -31.6484 5.2705)
			(stroke
				(width 0.1524)
				(type default)
			)
			(layer "F.SilkS")
		)
		(fp_line
			(start -31.3436 -5.2578)
			(end 31.3436 -5.2578)
			(stroke
				(width 0.1524)
				(type default)
			)
			(layer "F.SilkS")
		)
		(fp_line
			(start -31.3436 -9.4488)
			(end -31.3436 -5.2578)
			(stroke
				(width 0.1524)
				(type default)
			)
			(layer "F.SilkS")
		)
		(fp_line
			(start -31.3436 -14.5542)
			(end -30.7975 -14.5542)
			(stroke
				(width 0.1524)
				(type default)
			)
			(layer "F.SilkS")
		)
		(fp_line
			(start -31.3436 -21.3106)
			(end -31.3436 -14.5542)
			(stroke
				(width 0.1524)
				(type default)
			)
			(layer "F.SilkS")
		)
		(fp_line
			(start -31.4579 5.3594)
			(end -31.8389 5.3594)
			(stroke
				(width 0.3302)
				(type default)
			)
			(layer "F.SilkS")
		)
		(fp_line
			(start -31.6484 5.2959)
			(end -32.1437 5.7912)
			(stroke
				(width 0.1524)
				(type default)
			)
			(layer "F.SilkS")
		)
		(fp_line
			(start -31.6484 5.2832)
			(end -31.6484 5.2959)
			(stroke
				(width 0.1524)
				(type default)
			)
			(layer "F.SilkS")
		)
		(fp_line
			(start -31.6484 5.2705)
			(end -31.6484 6.35)
			(stroke
				(width 0.1524)
				(type default)
			)
			(layer "F.SilkS")
		)
		(fp_line
			(start -31.8008 -21.3106)
			(end -31.3436 -21.3106)
			(stroke
				(width 0.1524)
				(type default)
			)
			(layer "F.SilkS")
		)
		(fp_line
			(start -31.8008 -23.749)
			(end -31.8008 -21.3106)
			(stroke
				(width 0.1524)
				(type default)
			)
			(layer "F.SilkS")
		)
		(fp_line
			(start -32.1183 5.8166)
			(end -31.1531 5.8166)
			(stroke
				(width 0.1524)
				(type default)
			)
			(layer "F.SilkS")
		)
		(fp_line
			(start -32.1437 5.7912)
			(end -32.1183 5.8166)
			(stroke
				(width 0.1524)
				(type default)
			)
			(layer "F.SilkS")
		)
		(fp_line
			(start -36.2585 5.2578)
			(end -36.2585 0.254)
			(stroke
				(width 0.1524)
				(type default)
			)
			(layer "F.SilkS")
		)
		(fp_line
			(start -36.2585 0.254)
			(end -37.2491 0.254)
			(stroke
				(width 0.1524)
				(type default)
			)
			(layer "F.SilkS")
		)
		(fp_line
			(start -37.2491 0.254)
			(end -37.2491 -7.6327)
			(stroke
				(width 0.1524)
				(type default)
			)
			(layer "F.SilkS")
		)
		(fp_line
			(start -37.2491 -7.6327)
			(end -39.9542 -7.6327)
			(stroke
				(width 0.1524)
				(type default)
			)
			(layer "F.SilkS")
		)
		(fp_line
			(start -38.2524 -14.9606)
			(end -38.2524 -23.749)
			(stroke
				(width 0.1524)
				(type default)
			)
			(layer "F.SilkS")
		)
		(fp_line
			(start -38.2524 -23.749)
			(end -31.8008 -23.749)
			(stroke
				(width 0.1524)
				(type default)
			)
			(layer "F.SilkS")
		)
		(fp_line
			(start -39.9542 -7.6327)
			(end -39.9542 -14.9606)
			(stroke
				(width 0.1524)
				(type default)
			)
			(layer "F.SilkS")
		)
		(fp_line
			(start -39.9542 -14.9606)
			(end -38.2524 -14.9606)
			(stroke
				(width 0.1524)
				(type default)
			)
			(layer "F.SilkS")
		)
		(fp_poly
			(pts
				(xy 32.512 -3.001772) (xy 32.512 3.001772) (xy -32.2834 3.001772) (xy -32.2834 -3.001772)
			)
			(stroke
				(width 0)
				(type default)
			)
			(fill yes)
			(layer "F.SilkS")
		)
		(fp_poly
			(pts
				(xy -35.8013 4.8514) (xy -35.8013 0) (xy -36.9951 0) (xy -36.9951 -10.4902) (xy -38.8493 -10.4902)
				(xy -38.8493 -13.4874) (xy -36.9951 -13.4874) (xy -36.9951 -17.145) (xy -37.5031 -21.0566) (xy -32.0548 -21.0566)
				(xy -32.0548 -4.3942) (xy 32.0548 -4.3942) (xy 32.0548 -21.0566) (xy 37.5031 -21.0566) (xy 36.9951 -17.145)
				(xy 36.9951 -13.4874) (xy 38.8493 -13.4874) (xy 38.8493 -10.4902) (xy 36.9951 -10.4902) (xy 36.9951 0)
				(xy 35.8013 0) (xy 35.8013 4.8514)
			)
			(stroke
				(width 0)
				(type default)
			)
			(fill no)
			(layer "F.CrtYd")
		)
		(fp_poly
			(pts
				(xy -36.2585 5.2578) (xy -36.2585 0.254) (xy -37.2491 0.254) (xy -37.2491 -7.6327) (xy -39.9542 -7.6327)
				(xy -39.9542 -14.9606) (xy -38.2524 -14.9606) (xy -38.2524 -23.749) (xy -31.8008 -23.749) (xy -31.8008 -21.3106)
				(xy -31.3436 -21.3106) (xy -31.3436 -14.5542) (xy -30.7975 -14.5542) (xy -30.7975 -9.4488) (xy -31.3436 -9.4488)
				(xy -31.3436 -5.2578) (xy 31.3436 -5.2578) (xy 31.3436 -9.4488) (xy 30.7975 -9.4488) (xy 30.7975 -14.5542)
				(xy 31.3436 -14.5542) (xy 31.3436 -21.3106) (xy 31.8008 -21.3106) (xy 31.8008 -23.749) (xy 38.2524 -23.749)
				(xy 38.2524 -14.9606) (xy 39.9542 -14.9606) (xy 39.9542 -7.6327) (xy 37.2491 -7.6327) (xy 37.2491 -4.1656)
				(xy 36.9951 -4.1656) (xy 36.9951 -10.4902) (xy 38.8493 -10.4902) (xy 38.8493 -13.4874) (xy 36.9951 -13.4874)
				(xy 36.9951 -17.142968) (xy 37.503354 -21.0566) (xy 32.0548 -21.0566) (xy 32.0548 -4.3942) (xy -32.0548 -4.3942)
				(xy -32.0548 -21.0566) (xy -37.503354 -21.0566) (xy -36.9951 -17.142968) (xy -36.9951 -13.4874)
				(xy -38.8493 -13.4874) (xy -38.8493 -10.4902) (xy -36.9951 -10.4902) (xy -36.9951 0) (xy -35.8013 0.000254)
				(xy -35.8013 4.8514) (xy 35.8013 4.8514) (xy 35.8013 0) (xy 36.9951 0) (xy 36.9951 -4.1529) (xy 37.2491 -4.1529)
				(xy 37.2491 0.254) (xy 36.2585 0.254) (xy 36.2585 5.2578)
			)
			(stroke
				(width 0)
				(type default)
			)
			(fill no)
			(layer "F.CrtYd")
		)
		(fp_poly
			(pts
				(xy -36.2585 5.2578) (xy -36.2585 0.254) (xy -37.2491 0.254) (xy -37.2491 -7.6327) (xy -39.9542 -7.6327)
				(xy -39.9542 -14.9606) (xy -38.2524 -14.9606) (xy -38.2524 -23.749) (xy -31.8008 -23.749) (xy -31.8008 -21.3106)
				(xy -31.3436 -21.3106) (xy -31.3436 -14.5542) (xy -30.7975 -14.5542) (xy -30.7975 -9.4488) (xy -31.3436 -9.4488)
				(xy -31.3436 -5.2578) (xy 31.3436 -5.2578) (xy 31.3436 -9.4488) (xy 30.7975 -9.4488) (xy 30.7975 -14.5542)
				(xy 31.3436 -14.5542) (xy 31.3436 -21.3106) (xy 31.8008 -21.3106) (xy 31.8008 -23.749) (xy 38.2524 -23.749)
				(xy 38.2524 -14.9606) (xy 39.9542 -14.9606) (xy 39.9542 -7.6327) (xy 37.2491 -7.6327) (xy 37.2491 0.254)
				(xy 36.2585 0.254) (xy 36.2585 5.2578)
			)
			(stroke
				(width 0)
				(type default)
			)
			(fill no)
			(layer "F.Fab")
		)
		(fp_text user "204"
			(at 28.706064 -6.279642 180)
			(unlocked yes)
			(layer "F.SilkS")
			(effects
				(font
					(size 0.635 0.635)
					(thickness 0.1524)
				)
				(justify left)
			)
		)
		(fp_text user "1"
			(at -32.888936 6.293358 180)
			(unlocked yes)
			(layer "F.SilkS")
			(effects
				(font
					(size 0.635 0.635)
					(thickness 0.1524)
				)
				(justify left)
			)
		)
		(pad "" np_thru_hole circle
			(at -33.399984 0 180)
			(size 0.254 0.254)
			(drill 1.6002)
			(layers "*.Cu" "*.Mask")
			(clearance 1.0287)
			(thermal_gap 1.0287)
		)
		(pad "" np_thru_hole circle
			(at 33.399984 0 180)
			(size 0.254 0.254)
			(drill 1.1176)
			(layers "*.Cu" "*.Mask")
			(clearance 0.7874)
			(thermal_gap 0.7874)
		)
		(pad "1" smd custom
			(at -31.649924 4.106672 180)
			(size 0.1143 0.1143)
			(layers "F.Cu" "F.Mask" "F.Paste")
			(net "DDR3_M_A_VREF_DQ1")
			(options
				(clearance outline)
				(anchor circle)
			)
			(primitives
				(gr_poly
					(pts
						(xy 0 0.9017) (xy -0.03175 0.89916) (xy -0.0635 0.889) (xy -0.09144 0.87376) (xy -0.11684 0.85344)
						(xy -0.13716 0.82804) (xy -0.1524 0.8001) (xy -0.16256 0.76835) (xy -0.1651 0.7366) (xy -0.1651 -0.13462)
						(xy -0.17272 -0.14224) (xy -0.19812 -0.1778) (xy -0.2032 -0.18796) (xy -0.20701 -0.19685) (xy -0.21209 -0.20701)
						(xy -0.2159 -0.21717) (xy -0.21844 -0.22733) (xy -0.22225 -0.23876) (xy -0.22352 -0.24892) (xy -0.22606 -0.25908)
						(xy -0.22733 -0.27051) (xy -0.22733 -0.28067) (xy -0.2286 -0.2921) (xy -0.22733 -0.30353) (xy -0.22733 -0.31369)
						(xy -0.22606 -0.32512) (xy -0.22352 -0.33528) (xy -0.22225 -0.34544) (xy -0.21844 -0.35687) (xy -0.2159 -0.36703)
						(xy -0.21209 -0.37719) (xy -0.20701 -0.38735) (xy -0.2032 -0.39624) (xy -0.19812 -0.4064) (xy -0.17272 -0.44196)
						(xy -0.1651 -0.44958) (xy -0.1651 -0.7366) (xy -0.16256 -0.76835) (xy -0.1524 -0.8001) (xy -0.13716 -0.82804)
						(xy -0.11684 -0.85344) (xy -0.09144 -0.87376) (xy -0.0635 -0.889) (xy -0.03175 -0.89916) (xy 0 -0.9017)
						(xy 0.03175 -0.89916) (xy 0.0635 -0.889) (xy 0.09144 -0.87376) (xy 0.11684 -0.85344) (xy 0.13716 -0.82804)
						(xy 0.1524 -0.8001) (xy 0.16256 -0.76835) (xy 0.1651 -0.7366) (xy 0.1651 -0.44958) (xy 0.17272 -0.44196)
						(xy 0.19812 -0.4064) (xy 0.2032 -0.39624) (xy 0.20701 -0.38735) (xy 0.21209 -0.37719) (xy 0.2159 -0.36703)
						(xy 0.21844 -0.35687) (xy 0.22225 -0.34544) (xy 0.22352 -0.33528) (xy 0.22606 -0.32512) (xy 0.22733 -0.31369)
						(xy 0.22733 -0.30353) (xy 0.2286 -0.2921) (xy 0.22733 -0.28067) (xy 0.22733 -0.27051) (xy 0.22606 -0.25908)
						(xy 0.22352 -0.24892) (xy 0.22225 -0.23876) (xy 0.21844 -0.22733) (xy 0.2159 -0.21717) (xy 0.21209 -0.20701)
						(xy 0.20701 -0.19685) (xy 0.2032 -0.18796) (xy 0.19812 -0.1778) (xy 0.17272 -0.14224) (xy 0.1651 -0.13462)
						(xy 0.1651 0.7366) (xy 0.16256 0.76835) (xy 0.1524 0.8001) (xy 0.13716 0.82804) (xy 0.11684 0.85344)
						(xy 0.09144 0.87376) (xy 0.0635 0.889) (xy 0.03175 0.89916)
					)
					(width 0)
					(fill yes)
				)
			)
		)
		(pad "2" smd custom
			(at -31.34995 -4.106672 180)
			(size 0.1143 0.1143)
			(layers "F.Cu" "F.Mask" "F.Paste")
			(net "GND")
			(options
				(clearance outline)
				(anchor circle)
			)
			(primitives
				(gr_poly
					(pts
						(xy 0 0.9017) (xy -0.03175 0.89916) (xy -0.0635 0.889) (xy -0.09144 0.87376) (xy -0.11684 0.85344)
						(xy -0.13716 0.82804) (xy -0.1524 0.8001) (xy -0.16256 0.76835) (xy -0.1651 0.7366) (xy -0.1651 0.44958)
						(xy -0.17272 0.44196) (xy -0.19812 0.4064) (xy -0.2032 0.39624) (xy -0.20701 0.38735) (xy -0.21209 0.37719)
						(xy -0.2159 0.36703) (xy -0.21844 0.35687) (xy -0.22225 0.34544) (xy -0.22352 0.33528) (xy -0.22606 0.32512)
						(xy -0.22733 0.31369) (xy -0.22733 0.30353) (xy -0.2286 0.2921) (xy -0.22733 0.28067) (xy -0.22733 0.27051)
						(xy -0.22606 0.25908) (xy -0.22352 0.24892) (xy -0.22225 0.23876) (xy -0.21844 0.22733) (xy -0.2159 0.21717)
						(xy -0.21209 0.20701) (xy -0.20701 0.19685) (xy -0.2032 0.18796) (xy -0.19812 0.1778) (xy -0.17272 0.14224)
						(xy -0.1651 0.13462) (xy -0.1651 -0.7366) (xy -0.16256 -0.76835) (xy -0.1524 -0.8001) (xy -0.13716 -0.82804)
						(xy -0.11684 -0.85344) (xy -0.09144 -0.87376) (xy -0.0635 -0.889) (xy -0.03175 -0.89916) (xy 0 -0.9017)
						(xy 0.03175 -0.89916) (xy 0.0635 -0.889) (xy 0.09144 -0.87376) (xy 0.11684 -0.85344) (xy 0.13716 -0.82804)
						(xy 0.1524 -0.8001) (xy 0.16256 -0.76835) (xy 0.1651 -0.7366) (xy 0.1651 0.13462) (xy 0.17272 0.14224)
						(xy 0.19812 0.1778) (xy 0.2032 0.18796) (xy 0.20701 0.19685) (xy 0.21209 0.20701) (xy 0.2159 0.21717)
						(xy 0.21844 0.22733) (xy 0.22225 0.23876) (xy 0.22352 0.24892) (xy 0.22606 0.25908) (xy 0.22733 0.27051)
						(xy 0.22733 0.28067) (xy 0.2286 0.2921) (xy 0.22733 0.30353) (xy 0.22733 0.31369) (xy 0.22606 0.32512)
						(xy 0.22352 0.33528) (xy 0.22225 0.34544) (xy 0.21844 0.35687) (xy 0.2159 0.36703) (xy 0.21209 0.37719)
						(xy 0.20701 0.38735) (xy 0.2032 0.39624) (xy 0.19812 0.4064) (xy 0.17272 0.44196) (xy 0.1651 0.44958)
						(xy 0.1651 0.7366) (xy 0.16256 0.76835) (xy 0.1524 0.8001) (xy 0.13716 0.82804) (xy 0.11684 0.85344)
						(xy 0.09144 0.87376) (xy 0.0635 0.889) (xy 0.03175 0.89916)
					)
					(width 0)
					(fill yes)
				)
			)
		)
		(pad "3" smd custom
			(at -31.049976 4.106672 180)
			(size 0.1143 0.1143)
			(layers "F.Cu" "F.Mask" "F.Paste")
			(net "GND")
			(options
				(clearance outline)
				(anchor circle)
			)
			(primitives
				(gr_poly
					(pts
						(xy 0 0.9017) (xy -0.03175 0.89916) (xy -0.0635 0.889) (xy -0.09144 0.87376) (xy -0.11684 0.85344)
						(xy -0.13716 0.82804) (xy -0.1524 0.8001) (xy -0.16256 0.76835) (xy -0.1651 0.7366) (xy -0.1651 0.11938)
						(xy -0.17272 0.11176) (xy -0.19812 0.0762) (xy -0.2032 0.06604) (xy -0.20701 0.05715) (xy -0.21209 0.04699)
						(xy -0.2159 0.03683) (xy -0.21844 0.02667) (xy -0.22225 0.01524) (xy -0.22352 0.00508) (xy -0.22606 -0.00508)
						(xy -0.22733 -0.01651) (xy -0.22733 -0.02667) (xy -0.2286 -0.0381) (xy -0.22733 -0.04953) (xy -0.22733 -0.05969)
						(xy -0.22606 -0.07112) (xy -0.22352 -0.08128) (xy -0.22225 -0.09144) (xy -0.21844 -0.10287) (xy -0.2159 -0.11303)
						(xy -0.21209 -0.12319) (xy -0.20701 -0.13335) (xy -0.2032 -0.14224) (xy -0.19812 -0.1524) (xy -0.17272 -0.18796)
						(xy -0.1651 -0.19558) (xy -0.1651 -0.7366) (xy -0.16256 -0.76835) (xy -0.1524 -0.8001) (xy -0.13716 -0.82804)
						(xy -0.11684 -0.85344) (xy -0.09144 -0.87376) (xy -0.0635 -0.889) (xy -0.03175 -0.89916) (xy 0 -0.9017)
						(xy 0.03175 -0.89916) (xy 0.0635 -0.889) (xy 0.09144 -0.87376) (xy 0.11684 -0.85344) (xy 0.13716 -0.82804)
						(xy 0.1524 -0.8001) (xy 0.16256 -0.76835) (xy 0.1651 -0.7366) (xy 0.1651 -0.19685) (xy 0.17272 -0.18923)
						(xy 0.17907 -0.18034) (xy 0.18669 -0.17145) (xy 0.19177 -0.16256) (xy 0.19812 -0.15367) (xy 0.20828 -0.13335)
						(xy 0.21971 -0.10287) (xy 0.22225 -0.09271) (xy 0.22479 -0.08128) (xy 0.22606 -0.07112) (xy 0.2286 -0.05969)
						(xy 0.2286 -0.01651) (xy 0.22606 -0.00508) (xy 0.22479 0.00508) (xy 0.22225 0.01651) (xy 0.21971 0.02667)
						(xy 0.20828 0.05715) (xy 0.19812 0.07747) (xy 0.19177 0.08636) (xy 0.18669 0.09525) (xy 0.17907 0.10414)
						(xy 0.17272 0.11303) (xy 0.1651 0.12065) (xy 0.1651 0.7366) (xy 0.16256 0.76835) (xy 0.1524 0.8001)
						(xy 0.13716 0.82804) (xy 0.11684 0.85344) (xy 0.09144 0.87376) (xy 0.0635 0.889) (xy 0.03175 0.89916)
					)
					(width 0)
					(fill yes)
				)
			)
		)
		(pad "4" smd custom
			(at -30.750002 -4.106672 180)
			(size 0.1143 0.1143)
			(layers "F.Cu" "F.Mask" "F.Paste")
			(net "M_A_DQ0")
			(options
				(clearance outline)
				(anchor circle)
			)
			(primitives
				(gr_poly
					(pts
						(xy 0 0.9017) (xy -0.03175 0.89916) (xy -0.0635 0.889) (xy -0.09144 0.87376) (xy -0.11684 0.85344)
						(xy -0.13716 0.82804) (xy -0.1524 0.8001) (xy -0.16256 0.76835) (xy -0.1651 0.7366) (xy -0.1651 0.19685)
						(xy -0.17272 0.18923) (xy -0.17907 0.18034) (xy -0.18669 0.17145) (xy -0.19177 0.16256) (xy -0.19812 0.15367)
						(xy -0.20828 0.13335) (xy -0.21971 0.10287) (xy -0.22225 0.09271) (xy -0.22479 0.08128) (xy -0.22606 0.07112)
						(xy -0.2286 0.05969) (xy -0.2286 0.01651) (xy -0.22606 0.00508) (xy -0.22479 -0.00508) (xy -0.22225 -0.01651)
						(xy -0.21971 -0.02667) (xy -0.20828 -0.05715) (xy -0.19812 -0.07747) (xy -0.19177 -0.08636) (xy -0.18669 -0.09525)
						(xy -0.17907 -0.10414) (xy -0.17272 -0.11303) (xy -0.1651 -0.12065) (xy -0.1651 -0.7366) (xy -0.16256 -0.76835)
						(xy -0.1524 -0.8001) (xy -0.13716 -0.82804) (xy -0.11684 -0.85344) (xy -0.09144 -0.87376) (xy -0.0635 -0.889)
						(xy -0.03175 -0.89916) (xy 0 -0.9017) (xy 0.03175 -0.89916) (xy 0.0635 -0.889) (xy 0.09144 -0.87376)
						(xy 0.11684 -0.85344) (xy 0.13716 -0.82804) (xy 0.1524 -0.8001) (xy 0.16256 -0.76835) (xy 0.1651 -0.7366)
						(xy 0.1651 -0.11938) (xy 0.17272 -0.11176) (xy 0.19812 -0.0762) (xy 0.2032 -0.06604) (xy 0.20701 -0.05715)
						(xy 0.21209 -0.04699) (xy 0.2159 -0.03683) (xy 0.21844 -0.02667) (xy 0.22225 -0.01524) (xy 0.22352 -0.00508)
						(xy 0.22606 0.00508) (xy 0.22733 0.01651) (xy 0.22733 0.02667) (xy 0.2286 0.0381) (xy 0.22733 0.04953)
						(xy 0.22733 0.05969) (xy 0.22606 0.07112) (xy 0.22352 0.08128) (xy 0.22225 0.09144) (xy 0.21844 0.10287)
						(xy 0.2159 0.11303) (xy 0.21209 0.12319) (xy 0.20701 0.13335) (xy 0.2032 0.14224) (xy 0.19812 0.1524)
						(xy 0.17272 0.18796) (xy 0.1651 0.19558) (xy 0.1651 0.7366) (xy 0.16256 0.76835) (xy 0.1524 0.8001)
						(xy 0.13716 0.82804) (xy 0.11684 0.85344) (xy 0.09144 0.87376) (xy 0.0635 0.889) (xy 0.03175 0.89916)
					)
					(width 0)
					(fill yes)
				)
			)
		)
		(pad "5" smd custom
			(at -30.450028 4.106672 180)
			(size 0.1143 0.1143)
			(layers "F.Cu" "F.Mask" "F.Paste")
			(net "M_A_DQ4")
			(options
				(clearance outline)
				(anchor circle)
			)
			(primitives
				(gr_poly
					(pts
						(xy 0 0.9017) (xy -0.03175 0.89916) (xy -0.0635 0.889) (xy -0.09144 0.87376) (xy -0.11684 0.85344)
						(xy -0.13716 0.82804) (xy -0.1524 0.8001) (xy -0.16256 0.76835) (xy -0.1651 0.7366) (xy -0.1651 -0.13462)
						(xy -0.17272 -0.14224) (xy -0.19812 -0.1778) (xy -0.2032 -0.18796) (xy -0.20701 -0.19685) (xy -0.21209 -0.20701)
						(xy -0.2159 -0.21717) (xy -0.21844 -0.22733) (xy -0.22225 -0.23876) (xy -0.22352 -0.24892) (xy -0.22606 -0.25908)
						(xy -0.22733 -0.27051) (xy -0.22733 -0.28067) (xy -0.2286 -0.2921) (xy -0.22733 -0.30353) (xy -0.22733 -0.31369)
						(xy -0.22606 -0.32512) (xy -0.22352 -0.33528) (xy -0.22225 -0.34544) (xy -0.21844 -0.35687) (xy -0.2159 -0.36703)
						(xy -0.21209 -0.37719) (xy -0.20701 -0.38735) (xy -0.2032 -0.39624) (xy -0.19812 -0.4064) (xy -0.17272 -0.44196)
						(xy -0.1651 -0.44958) (xy -0.1651 -0.7366) (xy -0.16256 -0.76835) (xy -0.1524 -0.8001) (xy -0.13716 -0.82804)
						(xy -0.11684 -0.85344) (xy -0.09144 -0.87376) (xy -0.0635 -0.889) (xy -0.03175 -0.89916) (xy 0 -0.9017)
						(xy 0.03175 -0.89916) (xy 0.0635 -0.889) (xy 0.09144 -0.87376) (xy 0.11684 -0.85344) (xy 0.13716 -0.82804)
						(xy 0.1524 -0.8001) (xy 0.16256 -0.76835) (xy 0.1651 -0.7366) (xy 0.1651 -0.44958) (xy 0.17272 -0.44196)
						(xy 0.19812 -0.4064) (xy 0.2032 -0.39624) (xy 0.20701 -0.38735) (xy 0.21209 -0.37719) (xy 0.2159 -0.36703)
						(xy 0.21844 -0.35687) (xy 0.22225 -0.34544) (xy 0.22352 -0.33528) (xy 0.22606 -0.32512) (xy 0.22733 -0.31369)
						(xy 0.22733 -0.30353) (xy 0.2286 -0.2921) (xy 0.22733 -0.28067) (xy 0.22733 -0.27051) (xy 0.22606 -0.25908)
						(xy 0.22352 -0.24892) (xy 0.22225 -0.23876) (xy 0.21844 -0.22733) (xy 0.2159 -0.21717) (xy 0.21209 -0.20701)
						(xy 0.20701 -0.19685) (xy 0.2032 -0.18796) (xy 0.19812 -0.1778) (xy 0.17272 -0.14224) (xy 0.1651 -0.13462)
						(xy 0.1651 0.7366) (xy 0.16256 0.76835) (xy 0.1524 0.8001) (xy 0.13716 0.82804) (xy 0.11684 0.85344)
						(xy 0.09144 0.87376) (xy 0.0635 0.889) (xy 0.03175 0.89916)
					)
					(width 0)
					(fill yes)
				)
			)
		)
		(pad "6" smd custom
			(at -30.150054 -4.106672 180)
			(size 0.1143 0.1143)
			(layers "F.Cu" "F.Mask" "F.Paste")
			(net "M_A_DQ1")
			(options
				(clearance outline)
				(anchor circle)
			)
			(primitives
				(gr_poly
					(pts
						(xy 0 0.9017) (xy -0.03175 0.89916) (xy -0.0635 0.889) (xy -0.09144 0.87376) (xy -0.11684 0.85344)
						(xy -0.13716 0.82804) (xy -0.1524 0.8001) (xy -0.16256 0.76835) (xy -0.1651 0.7366) (xy -0.1651 0.44958)
						(xy -0.17272 0.44196) (xy -0.19812 0.4064) (xy -0.2032 0.39624) (xy -0.20701 0.38735) (xy -0.21209 0.37719)
						(xy -0.2159 0.36703) (xy -0.21844 0.35687) (xy -0.22225 0.34544) (xy -0.22352 0.33528) (xy -0.22606 0.32512)
						(xy -0.22733 0.31369) (xy -0.22733 0.30353) (xy -0.2286 0.2921) (xy -0.22733 0.28067) (xy -0.22733 0.27051)
						(xy -0.22606 0.25908) (xy -0.22352 0.24892) (xy -0.22225 0.23876) (xy -0.21844 0.22733) (xy -0.2159 0.21717)
						(xy -0.21209 0.20701) (xy -0.20701 0.19685) (xy -0.2032 0.18796) (xy -0.19812 0.1778) (xy -0.17272 0.14224)
						(xy -0.1651 0.13462) (xy -0.1651 -0.7366) (xy -0.16256 -0.76835) (xy -0.1524 -0.8001) (xy -0.13716 -0.82804)
						(xy -0.11684 -0.85344) (xy -0.09144 -0.87376) (xy -0.0635 -0.889) (xy -0.03175 -0.89916) (xy 0 -0.9017)
						(xy 0.03175 -0.89916) (xy 0.0635 -0.889) (xy 0.09144 -0.87376) (xy 0.11684 -0.85344) (xy 0.13716 -0.82804)
						(xy 0.1524 -0.8001) (xy 0.16256 -0.76835) (xy 0.1651 -0.7366) (xy 0.1651 0.13462) (xy 0.17272 0.14224)
						(xy 0.19812 0.1778) (xy 0.2032 0.18796) (xy 0.20701 0.19685) (xy 0.21209 0.20701) (xy 0.2159 0.21717)
						(xy 0.21844 0.22733) (xy 0.22225 0.23876) (xy 0.22352 0.24892) (xy 0.22606 0.25908) (xy 0.22733 0.27051)
						(xy 0.22733 0.28067) (xy 0.2286 0.2921) (xy 0.22733 0.30353) (xy 0.22733 0.31369) (xy 0.22606 0.32512)
						(xy 0.22352 0.33528) (xy 0.22225 0.34544) (xy 0.21844 0.35687) (xy 0.2159 0.36703) (xy 0.21209 0.37719)
						(xy 0.20701 0.38735) (xy 0.2032 0.39624) (xy 0.19812 0.4064) (xy 0.17272 0.44196) (xy 0.1651 0.44958)
						(xy 0.1651 0.7366) (xy 0.16256 0.76835) (xy 0.1524 0.8001) (xy 0.13716 0.82804) (xy 0.11684 0.85344)
						(xy 0.09144 0.87376) (xy 0.0635 0.889) (xy 0.03175 0.89916)
					)
					(width 0)
					(fill yes)
				)
			)
		)
		(pad "7" smd custom
			(at -29.85008 4.106672 180)
			(size 0.1143 0.1143)
			(layers "F.Cu" "F.Mask" "F.Paste")
			(net "M_A_DQ5")
			(options
				(clearance outline)
				(anchor circle)
			)
			(primitives
				(gr_poly
					(pts
						(xy 0 0.9017) (xy -0.03175 0.89916) (xy -0.0635 0.889) (xy -0.09144 0.87376) (xy -0.11684 0.85344)
						(xy -0.13716 0.82804) (xy -0.1524 0.8001) (xy -0.16256 0.76835) (xy -0.1651 0.7366) (xy -0.1651 0.11938)
						(xy -0.17272 0.11176) (xy -0.19812 0.0762) (xy -0.2032 0.06604) (xy -0.20701 0.05715) (xy -0.21209 0.04699)
						(xy -0.2159 0.03683) (xy -0.21844 0.02667) (xy -0.22225 0.01524) (xy -0.22352 0.00508) (xy -0.22606 -0.00508)
						(xy -0.22733 -0.01651) (xy -0.22733 -0.02667) (xy -0.2286 -0.0381) (xy -0.22733 -0.04953) (xy -0.22733 -0.05969)
						(xy -0.22606 -0.07112) (xy -0.22352 -0.08128) (xy -0.22225 -0.09144) (xy -0.21844 -0.10287) (xy -0.2159 -0.11303)
						(xy -0.21209 -0.12319) (xy -0.20701 -0.13335) (xy -0.2032 -0.14224) (xy -0.19812 -0.1524) (xy -0.17272 -0.18796)
						(xy -0.1651 -0.19558) (xy -0.1651 -0.7366) (xy -0.16256 -0.76835) (xy -0.1524 -0.8001) (xy -0.13716 -0.82804)
						(xy -0.11684 -0.85344) (xy -0.09144 -0.87376) (xy -0.0635 -0.889) (xy -0.03175 -0.89916) (xy 0 -0.9017)
						(xy 0.03175 -0.89916) (xy 0.0635 -0.889) (xy 0.09144 -0.87376) (xy 0.11684 -0.85344) (xy 0.13716 -0.82804)
						(xy 0.1524 -0.8001) (xy 0.16256 -0.76835) (xy 0.1651 -0.7366) (xy 0.1651 -0.19685) (xy 0.17272 -0.18923)
						(xy 0.17907 -0.18034) (xy 0.18669 -0.17145) (xy 0.19177 -0.16256) (xy 0.19812 -0.15367) (xy 0.20828 -0.13335)
						(xy 0.21971 -0.10287) (xy 0.22225 -0.09271) (xy 0.22479 -0.08128) (xy 0.22606 -0.07112) (xy 0.2286 -0.05969)
						(xy 0.2286 -0.01651) (xy 0.22606 -0.00508) (xy 0.22479 0.00508) (xy 0.22225 0.01651) (xy 0.21971 0.02667)
						(xy 0.20828 0.05715) (xy 0.19812 0.07747) (xy 0.19177 0.08636) (xy 0.18669 0.09525) (xy 0.17907 0.10414)
						(xy 0.17272 0.11303) (xy 0.1651 0.12065) (xy 0.1651 0.7366) (xy 0.16256 0.76835) (xy 0.1524 0.8001)
						(xy 0.13716 0.82804) (xy 0.11684 0.85344) (xy 0.09144 0.87376) (xy 0.0635 0.889) (xy 0.03175 0.89916)
					)
					(width 0)
					(fill yes)
				)
			)
		)
		(pad "8" smd custom
			(at -29.550106 -4.106672 180)
			(size 0.1143 0.1143)
			(layers "F.Cu" "F.Mask" "F.Paste")
			(net "GND")
			(options
				(clearance outline)
				(anchor circle)
			)
			(primitives
				(gr_poly
					(pts
						(xy 0 0.9017) (xy -0.03175 0.89916) (xy -0.0635 0.889) (xy -0.09144 0.87376) (xy -0.11684 0.85344)
						(xy -0.13716 0.82804) (xy -0.1524 0.8001) (xy -0.16256 0.76835) (xy -0.1651 0.7366) (xy -0.1651 0.19685)
						(xy -0.17272 0.18923) (xy -0.17907 0.18034) (xy -0.18669 0.17145) (xy -0.19177 0.16256) (xy -0.19812 0.15367)
						(xy -0.20828 0.13335) (xy -0.21971 0.10287) (xy -0.22225 0.09271) (xy -0.22479 0.08128) (xy -0.22606 0.07112)
						(xy -0.2286 0.05969) (xy -0.2286 0.01651) (xy -0.22606 0.00508) (xy -0.22479 -0.00508) (xy -0.22225 -0.01651)
						(xy -0.21971 -0.02667) (xy -0.20828 -0.05715) (xy -0.19812 -0.07747) (xy -0.19177 -0.08636) (xy -0.18669 -0.09525)
						(xy -0.17907 -0.10414) (xy -0.17272 -0.11303) (xy -0.1651 -0.12065) (xy -0.1651 -0.7366) (xy -0.16256 -0.76835)
						(xy -0.1524 -0.8001) (xy -0.13716 -0.82804) (xy -0.11684 -0.85344) (xy -0.09144 -0.87376) (xy -0.0635 -0.889)
						(xy -0.03175 -0.89916) (xy 0 -0.9017) (xy 0.03175 -0.89916) (xy 0.0635 -0.889) (xy 0.09144 -0.87376)
						(xy 0.11684 -0.85344) (xy 0.13716 -0.82804) (xy 0.1524 -0.8001) (xy 0.16256 -0.76835) (xy 0.1651 -0.7366)
						(xy 0.1651 -0.11938) (xy 0.17272 -0.11176) (xy 0.19812 -0.0762) (xy 0.2032 -0.06604) (xy 0.20701 -0.05715)
						(xy 0.21209 -0.04699) (xy 0.2159 -0.03683) (xy 0.21844 -0.02667) (xy 0.22225 -0.01524) (xy 0.22352 -0.00508)
						(xy 0.22606 0.00508) (xy 0.22733 0.01651) (xy 0.22733 0.02667) (xy 0.2286 0.0381) (xy 0.22733 0.04953)
						(xy 0.22733 0.05969) (xy 0.22606 0.07112) (xy 0.22352 0.08128) (xy 0.22225 0.09144) (xy 0.21844 0.10287)
						(xy 0.2159 0.11303) (xy 0.21209 0.12319) (xy 0.20701 0.13335) (xy 0.2032 0.14224) (xy 0.19812 0.1524)
						(xy 0.17272 0.18796) (xy 0.1651 0.19558) (xy 0.1651 0.7366) (xy 0.16256 0.76835) (xy 0.1524 0.8001)
						(xy 0.13716 0.82804) (xy 0.11684 0.85344) (xy 0.09144 0.87376) (xy 0.0635 0.889) (xy 0.03175 0.89916)
					)
					(width 0)
					(fill yes)
				)
			)
		)
		(pad "9" smd custom
			(at -29.249878 4.106672 180)
			(size 0.1143 0.1143)
			(layers "F.Cu" "F.Mask" "F.Paste")
			(net "GND")
			(options
				(clearance outline)
				(anchor circle)
			)
			(primitives
				(gr_poly
					(pts
						(xy 0 0.9017) (xy -0.03175 0.89916) (xy -0.0635 0.889) (xy -0.09144 0.87376) (xy -0.11684 0.85344)
						(xy -0.13716 0.82804) (xy -0.1524 0.8001) (xy -0.16256 0.76835) (xy -0.1651 0.7366) (xy -0.1651 -0.13462)
						(xy -0.17272 -0.14224) (xy -0.19812 -0.1778) (xy -0.2032 -0.18796) (xy -0.20701 -0.19685) (xy -0.21209 -0.20701)
						(xy -0.2159 -0.21717) (xy -0.21844 -0.22733) (xy -0.22225 -0.23876) (xy -0.22352 -0.24892) (xy -0.22606 -0.25908)
						(xy -0.22733 -0.27051) (xy -0.22733 -0.28067) (xy -0.2286 -0.2921) (xy -0.22733 -0.30353) (xy -0.22733 -0.31369)
						(xy -0.22606 -0.32512) (xy -0.22352 -0.33528) (xy -0.22225 -0.34544) (xy -0.21844 -0.35687) (xy -0.2159 -0.36703)
						(xy -0.21209 -0.37719) (xy -0.20701 -0.38735) (xy -0.2032 -0.39624) (xy -0.19812 -0.4064) (xy -0.17272 -0.44196)
						(xy -0.1651 -0.44958) (xy -0.1651 -0.7366) (xy -0.16256 -0.76835) (xy -0.1524 -0.8001) (xy -0.13716 -0.82804)
						(xy -0.11684 -0.85344) (xy -0.09144 -0.87376) (xy -0.0635 -0.889) (xy -0.03175 -0.89916) (xy 0 -0.9017)
						(xy 0.03175 -0.89916) (xy 0.0635 -0.889) (xy 0.09144 -0.87376) (xy 0.11684 -0.85344) (xy 0.13716 -0.82804)
						(xy 0.1524 -0.8001) (xy 0.16256 -0.76835) (xy 0.1651 -0.7366) (xy 0.1651 -0.44958) (xy 0.17272 -0.44196)
						(xy 0.19812 -0.4064) (xy 0.2032 -0.39624) (xy 0.20701 -0.38735) (xy 0.21209 -0.37719) (xy 0.2159 -0.36703)
						(xy 0.21844 -0.35687) (xy 0.22225 -0.34544) (xy 0.22352 -0.33528) (xy 0.22606 -0.32512) (xy 0.22733 -0.31369)
						(xy 0.22733 -0.30353) (xy 0.2286 -0.2921) (xy 0.22733 -0.28067) (xy 0.22733 -0.27051) (xy 0.22606 -0.25908)
						(xy 0.22352 -0.24892) (xy 0.22225 -0.23876) (xy 0.21844 -0.22733) (xy 0.2159 -0.21717) (xy 0.21209 -0.20701)
						(xy 0.20701 -0.19685) (xy 0.2032 -0.18796) (xy 0.19812 -0.1778) (xy 0.17272 -0.14224) (xy 0.1651 -0.13462)
						(xy 0.1651 0.7366) (xy 0.16256 0.76835) (xy 0.1524 0.8001) (xy 0.13716 0.82804) (xy 0.11684 0.85344)
						(xy 0.09144 0.87376) (xy 0.0635 0.889) (xy 0.03175 0.89916)
					)
					(width 0)
					(fill yes)
				)
			)
		)
		(pad "10" smd custom
			(at -28.949904 -4.106672 180)
			(size 0.1143 0.1143)
			(layers "F.Cu" "F.Mask" "F.Paste")
			(net "M_A_DQS_DN0")
			(options
				(clearance outline)
				(anchor circle)
			)
			(primitives
				(gr_poly
					(pts
						(xy 0 0.9017) (xy -0.03175 0.89916) (xy -0.0635 0.889) (xy -0.09144 0.87376) (xy -0.11684 0.85344)
						(xy -0.13716 0.82804) (xy -0.1524 0.8001) (xy -0.16256 0.76835) (xy -0.1651 0.7366) (xy -0.1651 0.44958)
						(xy -0.17272 0.44196) (xy -0.19812 0.4064) (xy -0.2032 0.39624) (xy -0.20701 0.38735) (xy -0.21209 0.37719)
						(xy -0.2159 0.36703) (xy -0.21844 0.35687) (xy -0.22225 0.34544) (xy -0.22352 0.33528) (xy -0.22606 0.32512)
						(xy -0.22733 0.31369) (xy -0.22733 0.30353) (xy -0.2286 0.2921) (xy -0.22733 0.28067) (xy -0.22733 0.27051)
						(xy -0.22606 0.25908) (xy -0.22352 0.24892) (xy -0.22225 0.23876) (xy -0.21844 0.22733) (xy -0.2159 0.21717)
						(xy -0.21209 0.20701) (xy -0.20701 0.19685) (xy -0.2032 0.18796) (xy -0.19812 0.1778) (xy -0.17272 0.14224)
						(xy -0.1651 0.13462) (xy -0.1651 -0.7366) (xy -0.16256 -0.76835) (xy -0.1524 -0.8001) (xy -0.13716 -0.82804)
						(xy -0.11684 -0.85344) (xy -0.09144 -0.87376) (xy -0.0635 -0.889) (xy -0.03175 -0.89916) (xy 0 -0.9017)
						(xy 0.03175 -0.89916) (xy 0.0635 -0.889) (xy 0.09144 -0.87376) (xy 0.11684 -0.85344) (xy 0.13716 -0.82804)
						(xy 0.1524 -0.8001) (xy 0.16256 -0.76835) (xy 0.1651 -0.7366) (xy 0.1651 0.13462) (xy 0.17272 0.14224)
						(xy 0.19812 0.1778) (xy 0.2032 0.18796) (xy 0.20701 0.19685) (xy 0.21209 0.20701) (xy 0.2159 0.21717)
						(xy 0.21844 0.22733) (xy 0.22225 0.23876) (xy 0.22352 0.24892) (xy 0.22606 0.25908) (xy 0.22733 0.27051)
						(xy 0.22733 0.28067) (xy 0.2286 0.2921) (xy 0.22733 0.30353) (xy 0.22733 0.31369) (xy 0.22606 0.32512)
						(xy 0.22352 0.33528) (xy 0.22225 0.34544) (xy 0.21844 0.35687) (xy 0.2159 0.36703) (xy 0.21209 0.37719)
						(xy 0.20701 0.38735) (xy 0.2032 0.39624) (xy 0.19812 0.4064) (xy 0.17272 0.44196) (xy 0.1651 0.44958)
						(xy 0.1651 0.7366) (xy 0.16256 0.76835) (xy 0.1524 0.8001) (xy 0.13716 0.82804) (xy 0.11684 0.85344)
						(xy 0.09144 0.87376) (xy 0.0635 0.889) (xy 0.03175 0.89916)
					)
					(width 0)
					(fill yes)
				)
			)
		)
		(pad "11" smd custom
			(at -28.64993 4.106672 180)
			(size 0.1143 0.1143)
			(layers "F.Cu" "F.Mask" "F.Paste")
			(net "GND")
			(options
				(clearance outline)
				(anchor circle)
			)
			(primitives
				(gr_poly
					(pts
						(xy 0 0.9017) (xy -0.03175 0.89916) (xy -0.0635 0.889) (xy -0.09144 0.87376) (xy -0.11684 0.85344)
						(xy -0.13716 0.82804) (xy -0.1524 0.8001) (xy -0.16256 0.76835) (xy -0.1651 0.7366) (xy -0.1651 0.11938)
						(xy -0.17272 0.11176) (xy -0.19812 0.0762) (xy -0.2032 0.06604) (xy -0.20701 0.05715) (xy -0.21209 0.04699)
						(xy -0.2159 0.03683) (xy -0.21844 0.02667) (xy -0.22225 0.01524) (xy -0.22352 0.00508) (xy -0.22606 -0.00508)
						(xy -0.22733 -0.01651) (xy -0.22733 -0.02667) (xy -0.2286 -0.0381) (xy -0.22733 -0.04953) (xy -0.22733 -0.05969)
						(xy -0.22606 -0.07112) (xy -0.22352 -0.08128) (xy -0.22225 -0.09144) (xy -0.21844 -0.10287) (xy -0.2159 -0.11303)
						(xy -0.21209 -0.12319) (xy -0.20701 -0.13335) (xy -0.2032 -0.14224) (xy -0.19812 -0.1524) (xy -0.17272 -0.18796)
						(xy -0.1651 -0.19558) (xy -0.1651 -0.7366) (xy -0.16256 -0.76835) (xy -0.1524 -0.8001) (xy -0.13716 -0.82804)
						(xy -0.11684 -0.85344) (xy -0.09144 -0.87376) (xy -0.0635 -0.889) (xy -0.03175 -0.89916) (xy 0 -0.9017)
						(xy 0.03175 -0.89916) (xy 0.0635 -0.889) (xy 0.09144 -0.87376) (xy 0.11684 -0.85344) (xy 0.13716 -0.82804)
						(xy 0.1524 -0.8001) (xy 0.16256 -0.76835) (xy 0.1651 -0.7366) (xy 0.1651 -0.19685) (xy 0.17272 -0.18923)
						(xy 0.17907 -0.18034) (xy 0.18669 -0.17145) (xy 0.19177 -0.16256) (xy 0.19812 -0.15367) (xy 0.20828 -0.13335)
						(xy 0.21971 -0.10287) (xy 0.22225 -0.09271) (xy 0.22479 -0.08128) (xy 0.22606 -0.07112) (xy 0.2286 -0.05969)
						(xy 0.2286 -0.01651) (xy 0.22606 -0.00508) (xy 0.22479 0.00508) (xy 0.22225 0.01651) (xy 0.21971 0.02667)
						(xy 0.20828 0.05715) (xy 0.19812 0.07747) (xy 0.19177 0.08636) (xy 0.18669 0.09525) (xy 0.17907 0.10414)
						(xy 0.17272 0.11303) (xy 0.1651 0.12065) (xy 0.1651 0.7366) (xy 0.16256 0.76835) (xy 0.1524 0.8001)
						(xy 0.13716 0.82804) (xy 0.11684 0.85344) (xy 0.09144 0.87376) (xy 0.0635 0.889) (xy 0.03175 0.89916)
					)
					(width 0)
					(fill yes)
				)
			)
		)
		(pad "12" smd custom
			(at -28.349956 -4.106672 180)
			(size 0.1143 0.1143)
			(layers "F.Cu" "F.Mask" "F.Paste")
			(net "M_A_DQS_DP0")
			(options
				(clearance outline)
				(anchor circle)
			)
			(primitives
				(gr_poly
					(pts
						(xy 0 0.9017) (xy -0.03175 0.89916) (xy -0.0635 0.889) (xy -0.09144 0.87376) (xy -0.11684 0.85344)
						(xy -0.13716 0.82804) (xy -0.1524 0.8001) (xy -0.16256 0.76835) (xy -0.1651 0.7366) (xy -0.1651 0.19685)
						(xy -0.17272 0.18923) (xy -0.17907 0.18034) (xy -0.18669 0.17145) (xy -0.19177 0.16256) (xy -0.19812 0.15367)
						(xy -0.20828 0.13335) (xy -0.21971 0.10287) (xy -0.22225 0.09271) (xy -0.22479 0.08128) (xy -0.22606 0.07112)
						(xy -0.2286 0.05969) (xy -0.2286 0.01651) (xy -0.22606 0.00508) (xy -0.22479 -0.00508) (xy -0.22225 -0.01651)
						(xy -0.21971 -0.02667) (xy -0.20828 -0.05715) (xy -0.19812 -0.07747) (xy -0.19177 -0.08636) (xy -0.18669 -0.09525)
						(xy -0.17907 -0.10414) (xy -0.17272 -0.11303) (xy -0.1651 -0.12065) (xy -0.1651 -0.7366) (xy -0.16256 -0.76835)
						(xy -0.1524 -0.8001) (xy -0.13716 -0.82804) (xy -0.11684 -0.85344) (xy -0.09144 -0.87376) (xy -0.0635 -0.889)
						(xy -0.03175 -0.89916) (xy 0 -0.9017) (xy 0.03175 -0.89916) (xy 0.0635 -0.889) (xy 0.09144 -0.87376)
						(xy 0.11684 -0.85344) (xy 0.13716 -0.82804) (xy 0.1524 -0.8001) (xy 0.16256 -0.76835) (xy 0.1651 -0.7366)
						(xy 0.1651 -0.11938) (xy 0.17272 -0.11176) (xy 0.19812 -0.0762) (xy 0.2032 -0.06604) (xy 0.20701 -0.05715)
						(xy 0.21209 -0.04699) (xy 0.2159 -0.03683) (xy 0.21844 -0.02667) (xy 0.22225 -0.01524) (xy 0.22352 -0.00508)
						(xy 0.22606 0.00508) (xy 0.22733 0.01651) (xy 0.22733 0.02667) (xy 0.2286 0.0381) (xy 0.22733 0.04953)
						(xy 0.22733 0.05969) (xy 0.22606 0.07112) (xy 0.22352 0.08128) (xy 0.22225 0.09144) (xy 0.21844 0.10287)
						(xy 0.2159 0.11303) (xy 0.21209 0.12319) (xy 0.20701 0.13335) (xy 0.2032 0.14224) (xy 0.19812 0.1524)
						(xy 0.17272 0.18796) (xy 0.1651 0.19558) (xy 0.1651 0.7366) (xy 0.16256 0.76835) (xy 0.1524 0.8001)
						(xy 0.13716 0.82804) (xy 0.11684 0.85344) (xy 0.09144 0.87376) (xy 0.0635 0.889) (xy 0.03175 0.89916)
					)
					(width 0)
					(fill yes)
				)
			)
		)
		(pad "13" smd custom
			(at -28.049982 4.106672 180)
			(size 0.1143 0.1143)
			(layers "F.Cu" "F.Mask" "F.Paste")
			(net "M_A_DQ6")
			(options
				(clearance outline)
				(anchor circle)
			)
			(primitives
				(gr_poly
					(pts
						(xy 0 0.9017) (xy -0.03175 0.89916) (xy -0.0635 0.889) (xy -0.09144 0.87376) (xy -0.11684 0.85344)
						(xy -0.13716 0.82804) (xy -0.1524 0.8001) (xy -0.16256 0.76835) (xy -0.1651 0.7366) (xy -0.1651 -0.13462)
						(xy -0.17272 -0.14224) (xy -0.19812 -0.1778) (xy -0.2032 -0.18796) (xy -0.20701 -0.19685) (xy -0.21209 -0.20701)
						(xy -0.2159 -0.21717) (xy -0.21844 -0.22733) (xy -0.22225 -0.23876) (xy -0.22352 -0.24892) (xy -0.22606 -0.25908)
						(xy -0.22733 -0.27051) (xy -0.22733 -0.28067) (xy -0.2286 -0.2921) (xy -0.22733 -0.30353) (xy -0.22733 -0.31369)
						(xy -0.22606 -0.32512) (xy -0.22352 -0.33528) (xy -0.22225 -0.34544) (xy -0.21844 -0.35687) (xy -0.2159 -0.36703)
						(xy -0.21209 -0.37719) (xy -0.20701 -0.38735) (xy -0.2032 -0.39624) (xy -0.19812 -0.4064) (xy -0.17272 -0.44196)
						(xy -0.1651 -0.44958) (xy -0.1651 -0.7366) (xy -0.16256 -0.76835) (xy -0.1524 -0.8001) (xy -0.13716 -0.82804)
						(xy -0.11684 -0.85344) (xy -0.09144 -0.87376) (xy -0.0635 -0.889) (xy -0.03175 -0.89916) (xy 0 -0.9017)
						(xy 0.03175 -0.89916) (xy 0.0635 -0.889) (xy 0.09144 -0.87376) (xy 0.11684 -0.85344) (xy 0.13716 -0.82804)
						(xy 0.1524 -0.8001) (xy 0.16256 -0.76835) (xy 0.1651 -0.7366) (xy 0.1651 -0.44958) (xy 0.17272 -0.44196)
						(xy 0.19812 -0.4064) (xy 0.2032 -0.39624) (xy 0.20701 -0.38735) (xy 0.21209 -0.37719) (xy 0.2159 -0.36703)
						(xy 0.21844 -0.35687) (xy 0.22225 -0.34544) (xy 0.22352 -0.33528) (xy 0.22606 -0.32512) (xy 0.22733 -0.31369)
						(xy 0.22733 -0.30353) (xy 0.2286 -0.2921) (xy 0.22733 -0.28067) (xy 0.22733 -0.27051) (xy 0.22606 -0.25908)
						(xy 0.22352 -0.24892) (xy 0.22225 -0.23876) (xy 0.21844 -0.22733) (xy 0.2159 -0.21717) (xy 0.21209 -0.20701)
						(xy 0.20701 -0.19685) (xy 0.2032 -0.18796) (xy 0.19812 -0.1778) (xy 0.17272 -0.14224) (xy 0.1651 -0.13462)
						(xy 0.1651 0.7366) (xy 0.16256 0.76835) (xy 0.1524 0.8001) (xy 0.13716 0.82804) (xy 0.11684 0.85344)
						(xy 0.09144 0.87376) (xy 0.0635 0.889) (xy 0.03175 0.89916)
					)
					(width 0)
					(fill yes)
				)
			)
		)
		(pad "14" smd custom
			(at -27.750008 -4.106672 180)
			(size 0.1143 0.1143)
			(layers "F.Cu" "F.Mask" "F.Paste")
			(net "GND")
			(options
				(clearance outline)
				(anchor circle)
			)
			(primitives
				(gr_poly
					(pts
						(xy 0 0.9017) (xy -0.03175 0.89916) (xy -0.0635 0.889) (xy -0.09144 0.87376) (xy -0.11684 0.85344)
						(xy -0.13716 0.82804) (xy -0.1524 0.8001) (xy -0.16256 0.76835) (xy -0.1651 0.7366) (xy -0.1651 0.44958)
						(xy -0.17272 0.44196) (xy -0.19812 0.4064) (xy -0.2032 0.39624) (xy -0.20701 0.38735) (xy -0.21209 0.37719)
						(xy -0.2159 0.36703) (xy -0.21844 0.35687) (xy -0.22225 0.34544) (xy -0.22352 0.33528) (xy -0.22606 0.32512)
						(xy -0.22733 0.31369) (xy -0.22733 0.30353) (xy -0.2286 0.2921) (xy -0.22733 0.28067) (xy -0.22733 0.27051)
						(xy -0.22606 0.25908) (xy -0.22352 0.24892) (xy -0.22225 0.23876) (xy -0.21844 0.22733) (xy -0.2159 0.21717)
						(xy -0.21209 0.20701) (xy -0.20701 0.19685) (xy -0.2032 0.18796) (xy -0.19812 0.1778) (xy -0.17272 0.14224)
						(xy -0.1651 0.13462) (xy -0.1651 -0.7366) (xy -0.16256 -0.76835) (xy -0.1524 -0.8001) (xy -0.13716 -0.82804)
						(xy -0.11684 -0.85344) (xy -0.09144 -0.87376) (xy -0.0635 -0.889) (xy -0.03175 -0.89916) (xy 0 -0.9017)
						(xy 0.03175 -0.89916) (xy 0.0635 -0.889) (xy 0.09144 -0.87376) (xy 0.11684 -0.85344) (xy 0.13716 -0.82804)
						(xy 0.1524 -0.8001) (xy 0.16256 -0.76835) (xy 0.1651 -0.7366) (xy 0.1651 0.13462) (xy 0.17272 0.14224)
						(xy 0.19812 0.1778) (xy 0.2032 0.18796) (xy 0.20701 0.19685) (xy 0.21209 0.20701) (xy 0.2159 0.21717)
						(xy 0.21844 0.22733) (xy 0.22225 0.23876) (xy 0.22352 0.24892) (xy 0.22606 0.25908) (xy 0.22733 0.27051)
						(xy 0.22733 0.28067) (xy 0.2286 0.2921) (xy 0.22733 0.30353) (xy 0.22733 0.31369) (xy 0.22606 0.32512)
						(xy 0.22352 0.33528) (xy 0.22225 0.34544) (xy 0.21844 0.35687) (xy 0.2159 0.36703) (xy 0.21209 0.37719)
						(xy 0.20701 0.38735) (xy 0.2032 0.39624) (xy 0.19812 0.4064) (xy 0.17272 0.44196) (xy 0.1651 0.44958)
						(xy 0.1651 0.7366) (xy 0.16256 0.76835) (xy 0.1524 0.8001) (xy 0.13716 0.82804) (xy 0.11684 0.85344)
						(xy 0.09144 0.87376) (xy 0.0635 0.889) (xy 0.03175 0.89916)
					)
					(width 0)
					(fill yes)
				)
			)
		)
		(pad "15" smd custom
			(at -27.450034 4.106672 180)
			(size 0.1143 0.1143)
			(layers "F.Cu" "F.Mask" "F.Paste")
			(net "M_A_DQ7")
			(options
				(clearance outline)
				(anchor circle)
			)
			(primitives
				(gr_poly
					(pts
						(xy 0 0.9017) (xy -0.03175 0.89916) (xy -0.0635 0.889) (xy -0.09144 0.87376) (xy -0.11684 0.85344)
						(xy -0.13716 0.82804) (xy -0.1524 0.8001) (xy -0.16256 0.76835) (xy -0.1651 0.7366) (xy -0.1651 0.11938)
						(xy -0.17272 0.11176) (xy -0.19812 0.0762) (xy -0.2032 0.06604) (xy -0.20701 0.05715) (xy -0.21209 0.04699)
						(xy -0.2159 0.03683) (xy -0.21844 0.02667) (xy -0.22225 0.01524) (xy -0.22352 0.00508) (xy -0.22606 -0.00508)
						(xy -0.22733 -0.01651) (xy -0.22733 -0.02667) (xy -0.2286 -0.0381) (xy -0.22733 -0.04953) (xy -0.22733 -0.05969)
						(xy -0.22606 -0.07112) (xy -0.22352 -0.08128) (xy -0.22225 -0.09144) (xy -0.21844 -0.10287) (xy -0.2159 -0.11303)
						(xy -0.21209 -0.12319) (xy -0.20701 -0.13335) (xy -0.2032 -0.14224) (xy -0.19812 -0.1524) (xy -0.17272 -0.18796)
						(xy -0.1651 -0.19558) (xy -0.1651 -0.7366) (xy -0.16256 -0.76835) (xy -0.1524 -0.8001) (xy -0.13716 -0.82804)
						(xy -0.11684 -0.85344) (xy -0.09144 -0.87376) (xy -0.0635 -0.889) (xy -0.03175 -0.89916) (xy 0 -0.9017)
						(xy 0.03175 -0.89916) (xy 0.0635 -0.889) (xy 0.09144 -0.87376) (xy 0.11684 -0.85344) (xy 0.13716 -0.82804)
						(xy 0.1524 -0.8001) (xy 0.16256 -0.76835) (xy 0.1651 -0.7366) (xy 0.1651 -0.19685) (xy 0.17272 -0.18923)
						(xy 0.17907 -0.18034) (xy 0.18669 -0.17145) (xy 0.19177 -0.16256) (xy 0.19812 -0.15367) (xy 0.20828 -0.13335)
						(xy 0.21971 -0.10287) (xy 0.22225 -0.09271) (xy 0.22479 -0.08128) (xy 0.22606 -0.07112) (xy 0.2286 -0.05969)
						(xy 0.2286 -0.01651) (xy 0.22606 -0.00508) (xy 0.22479 0.00508) (xy 0.22225 0.01651) (xy 0.21971 0.02667)
						(xy 0.20828 0.05715) (xy 0.19812 0.07747) (xy 0.19177 0.08636) (xy 0.18669 0.09525) (xy 0.17907 0.10414)
						(xy 0.17272 0.11303) (xy 0.1651 0.12065) (xy 0.1651 0.7366) (xy 0.16256 0.76835) (xy 0.1524 0.8001)
						(xy 0.13716 0.82804) (xy 0.11684 0.85344) (xy 0.09144 0.87376) (xy 0.0635 0.889) (xy 0.03175 0.89916)
					)
					(width 0)
					(fill yes)
				)
			)
		)
		(pad "16" smd custom
			(at -27.15006 -4.106672 180)
			(size 0.1143 0.1143)
			(layers "F.Cu" "F.Mask" "F.Paste")
			(net "M_A_DQ2")
			(options
				(clearance outline)
				(anchor circle)
			)
			(primitives
				(gr_poly
					(pts
						(xy 0 0.9017) (xy -0.03175 0.89916) (xy -0.0635 0.889) (xy -0.09144 0.87376) (xy -0.11684 0.85344)
						(xy -0.13716 0.82804) (xy -0.1524 0.8001) (xy -0.16256 0.76835) (xy -0.1651 0.7366) (xy -0.1651 0.19685)
						(xy -0.17272 0.18923) (xy -0.17907 0.18034) (xy -0.18669 0.17145) (xy -0.19177 0.16256) (xy -0.19812 0.15367)
						(xy -0.20828 0.13335) (xy -0.21971 0.10287) (xy -0.22225 0.09271) (xy -0.22479 0.08128) (xy -0.22606 0.07112)
						(xy -0.2286 0.05969) (xy -0.2286 0.01651) (xy -0.22606 0.00508) (xy -0.22479 -0.00508) (xy -0.22225 -0.01651)
						(xy -0.21971 -0.02667) (xy -0.20828 -0.05715) (xy -0.19812 -0.07747) (xy -0.19177 -0.08636) (xy -0.18669 -0.09525)
						(xy -0.17907 -0.10414) (xy -0.17272 -0.11303) (xy -0.1651 -0.12065) (xy -0.1651 -0.7366) (xy -0.16256 -0.76835)
						(xy -0.1524 -0.8001) (xy -0.13716 -0.82804) (xy -0.11684 -0.85344) (xy -0.09144 -0.87376) (xy -0.0635 -0.889)
						(xy -0.03175 -0.89916) (xy 0 -0.9017) (xy 0.03175 -0.89916) (xy 0.0635 -0.889) (xy 0.09144 -0.87376)
						(xy 0.11684 -0.85344) (xy 0.13716 -0.82804) (xy 0.1524 -0.8001) (xy 0.16256 -0.76835) (xy 0.1651 -0.7366)
						(xy 0.1651 -0.11938) (xy 0.17272 -0.11176) (xy 0.19812 -0.0762) (xy 0.2032 -0.06604) (xy 0.20701 -0.05715)
						(xy 0.21209 -0.04699) (xy 0.2159 -0.03683) (xy 0.21844 -0.02667) (xy 0.22225 -0.01524) (xy 0.22352 -0.00508)
						(xy 0.22606 0.00508) (xy 0.22733 0.01651) (xy 0.22733 0.02667) (xy 0.2286 0.0381) (xy 0.22733 0.04953)
						(xy 0.22733 0.05969) (xy 0.22606 0.07112) (xy 0.22352 0.08128) (xy 0.22225 0.09144) (xy 0.21844 0.10287)
						(xy 0.2159 0.11303) (xy 0.21209 0.12319) (xy 0.20701 0.13335) (xy 0.2032 0.14224) (xy 0.19812 0.1524)
						(xy 0.17272 0.18796) (xy 0.1651 0.19558) (xy 0.1651 0.7366) (xy 0.16256 0.76835) (xy 0.1524 0.8001)
						(xy 0.13716 0.82804) (xy 0.11684 0.85344) (xy 0.09144 0.87376) (xy 0.0635 0.889) (xy 0.03175 0.89916)
					)
					(width 0)
					(fill yes)
				)
			)
		)
		(pad "17" smd custom
			(at -26.850086 4.106672 180)
			(size 0.1143 0.1143)
			(layers "F.Cu" "F.Mask" "F.Paste")
			(net "GND")
			(options
				(clearance outline)
				(anchor circle)
			)
			(primitives
				(gr_poly
					(pts
						(xy 0 0.9017) (xy -0.03175 0.89916) (xy -0.0635 0.889) (xy -0.09144 0.87376) (xy -0.11684 0.85344)
						(xy -0.13716 0.82804) (xy -0.1524 0.8001) (xy -0.16256 0.76835) (xy -0.1651 0.7366) (xy -0.1651 -0.13462)
						(xy -0.17272 -0.14224) (xy -0.19812 -0.1778) (xy -0.2032 -0.18796) (xy -0.20701 -0.19685) (xy -0.21209 -0.20701)
						(xy -0.2159 -0.21717) (xy -0.21844 -0.22733) (xy -0.22225 -0.23876) (xy -0.22352 -0.24892) (xy -0.22606 -0.25908)
						(xy -0.22733 -0.27051) (xy -0.22733 -0.28067) (xy -0.2286 -0.2921) (xy -0.22733 -0.30353) (xy -0.22733 -0.31369)
						(xy -0.22606 -0.32512) (xy -0.22352 -0.33528) (xy -0.22225 -0.34544) (xy -0.21844 -0.35687) (xy -0.2159 -0.36703)
						(xy -0.21209 -0.37719) (xy -0.20701 -0.38735) (xy -0.2032 -0.39624) (xy -0.19812 -0.4064) (xy -0.17272 -0.44196)
						(xy -0.1651 -0.44958) (xy -0.1651 -0.7366) (xy -0.16256 -0.76835) (xy -0.1524 -0.8001) (xy -0.13716 -0.82804)
						(xy -0.11684 -0.85344) (xy -0.09144 -0.87376) (xy -0.0635 -0.889) (xy -0.03175 -0.89916) (xy 0 -0.9017)
						(xy 0.03175 -0.89916) (xy 0.0635 -0.889) (xy 0.09144 -0.87376) (xy 0.11684 -0.85344) (xy 0.13716 -0.82804)
						(xy 0.1524 -0.8001) (xy 0.16256 -0.76835) (xy 0.1651 -0.7366) (xy 0.1651 -0.44958) (xy 0.17272 -0.44196)
						(xy 0.19812 -0.4064) (xy 0.2032 -0.39624) (xy 0.20701 -0.38735) (xy 0.21209 -0.37719) (xy 0.2159 -0.36703)
						(xy 0.21844 -0.35687) (xy 0.22225 -0.34544) (xy 0.22352 -0.33528) (xy 0.22606 -0.32512) (xy 0.22733 -0.31369)
						(xy 0.22733 -0.30353) (xy 0.2286 -0.2921) (xy 0.22733 -0.28067) (xy 0.22733 -0.27051) (xy 0.22606 -0.25908)
						(xy 0.22352 -0.24892) (xy 0.22225 -0.23876) (xy 0.21844 -0.22733) (xy 0.2159 -0.21717) (xy 0.21209 -0.20701)
						(xy 0.20701 -0.19685) (xy 0.2032 -0.18796) (xy 0.19812 -0.1778) (xy 0.17272 -0.14224) (xy 0.1651 -0.13462)
						(xy 0.1651 0.7366) (xy 0.16256 0.76835) (xy 0.1524 0.8001) (xy 0.13716 0.82804) (xy 0.11684 0.85344)
						(xy 0.09144 0.87376) (xy 0.0635 0.889) (xy 0.03175 0.89916)
					)
					(width 0)
					(fill yes)
				)
			)
		)
		(pad "18" smd custom
			(at -26.550112 -4.106672 180)
			(size 0.1143 0.1143)
			(layers "F.Cu" "F.Mask" "F.Paste")
			(net "M_A_DQ3")
			(options
				(clearance outline)
				(anchor circle)
			)
			(primitives
				(gr_poly
					(pts
						(xy 0 0.9017) (xy -0.03175 0.89916) (xy -0.0635 0.889) (xy -0.09144 0.87376) (xy -0.11684 0.85344)
						(xy -0.13716 0.82804) (xy -0.1524 0.8001) (xy -0.16256 0.76835) (xy -0.1651 0.7366) (xy -0.1651 0.44958)
						(xy -0.17272 0.44196) (xy -0.19812 0.4064) (xy -0.2032 0.39624) (xy -0.20701 0.38735) (xy -0.21209 0.37719)
						(xy -0.2159 0.36703) (xy -0.21844 0.35687) (xy -0.22225 0.34544) (xy -0.22352 0.33528) (xy -0.22606 0.32512)
						(xy -0.22733 0.31369) (xy -0.22733 0.30353) (xy -0.2286 0.2921) (xy -0.22733 0.28067) (xy -0.22733 0.27051)
						(xy -0.22606 0.25908) (xy -0.22352 0.24892) (xy -0.22225 0.23876) (xy -0.21844 0.22733) (xy -0.2159 0.21717)
						(xy -0.21209 0.20701) (xy -0.20701 0.19685) (xy -0.2032 0.18796) (xy -0.19812 0.1778) (xy -0.17272 0.14224)
						(xy -0.1651 0.13462) (xy -0.1651 -0.7366) (xy -0.16256 -0.76835) (xy -0.1524 -0.8001) (xy -0.13716 -0.82804)
						(xy -0.11684 -0.85344) (xy -0.09144 -0.87376) (xy -0.0635 -0.889) (xy -0.03175 -0.89916) (xy 0 -0.9017)
						(xy 0.03175 -0.89916) (xy 0.0635 -0.889) (xy 0.09144 -0.87376) (xy 0.11684 -0.85344) (xy 0.13716 -0.82804)
						(xy 0.1524 -0.8001) (xy 0.16256 -0.76835) (xy 0.1651 -0.7366) (xy 0.1651 0.13462) (xy 0.17272 0.14224)
						(xy 0.19812 0.1778) (xy 0.2032 0.18796) (xy 0.20701 0.19685) (xy 0.21209 0.20701) (xy 0.2159 0.21717)
						(xy 0.21844 0.22733) (xy 0.22225 0.23876) (xy 0.22352 0.24892) (xy 0.22606 0.25908) (xy 0.22733 0.27051)
						(xy 0.22733 0.28067) (xy 0.2286 0.2921) (xy 0.22733 0.30353) (xy 0.22733 0.31369) (xy 0.22606 0.32512)
						(xy 0.22352 0.33528) (xy 0.22225 0.34544) (xy 0.21844 0.35687) (xy 0.2159 0.36703) (xy 0.21209 0.37719)
						(xy 0.20701 0.38735) (xy 0.2032 0.39624) (xy 0.19812 0.4064) (xy 0.17272 0.44196) (xy 0.1651 0.44958)
						(xy 0.1651 0.7366) (xy 0.16256 0.76835) (xy 0.1524 0.8001) (xy 0.13716 0.82804) (xy 0.11684 0.85344)
						(xy 0.09144 0.87376) (xy 0.0635 0.889) (xy 0.03175 0.89916)
					)
					(width 0)
					(fill yes)
				)
			)
		)
		(pad "19" smd custom
			(at -26.249884 4.106672 180)
			(size 0.1143 0.1143)
			(layers "F.Cu" "F.Mask" "F.Paste")
			(net "M_A_DQ12")
			(options
				(clearance outline)
				(anchor circle)
			)
			(primitives
				(gr_poly
					(pts
						(xy 0 0.9017) (xy -0.03175 0.89916) (xy -0.0635 0.889) (xy -0.09144 0.87376) (xy -0.11684 0.85344)
						(xy -0.13716 0.82804) (xy -0.1524 0.8001) (xy -0.16256 0.76835) (xy -0.1651 0.7366) (xy -0.1651 0.11938)
						(xy -0.17272 0.11176) (xy -0.19812 0.0762) (xy -0.2032 0.06604) (xy -0.20701 0.05715) (xy -0.21209 0.04699)
						(xy -0.2159 0.03683) (xy -0.21844 0.02667) (xy -0.22225 0.01524) (xy -0.22352 0.00508) (xy -0.22606 -0.00508)
						(xy -0.22733 -0.01651) (xy -0.22733 -0.02667) (xy -0.2286 -0.0381) (xy -0.22733 -0.04953) (xy -0.22733 -0.05969)
						(xy -0.22606 -0.07112) (xy -0.22352 -0.08128) (xy -0.22225 -0.09144) (xy -0.21844 -0.10287) (xy -0.2159 -0.11303)
						(xy -0.21209 -0.12319) (xy -0.20701 -0.13335) (xy -0.2032 -0.14224) (xy -0.19812 -0.1524) (xy -0.17272 -0.18796)
						(xy -0.1651 -0.19558) (xy -0.1651 -0.7366) (xy -0.16256 -0.76835) (xy -0.1524 -0.8001) (xy -0.13716 -0.82804)
						(xy -0.11684 -0.85344) (xy -0.09144 -0.87376) (xy -0.0635 -0.889) (xy -0.03175 -0.89916) (xy 0 -0.9017)
						(xy 0.03175 -0.89916) (xy 0.0635 -0.889) (xy 0.09144 -0.87376) (xy 0.11684 -0.85344) (xy 0.13716 -0.82804)
						(xy 0.1524 -0.8001) (xy 0.16256 -0.76835) (xy 0.1651 -0.7366) (xy 0.1651 -0.19685) (xy 0.17272 -0.18923)
						(xy 0.17907 -0.18034) (xy 0.18669 -0.17145) (xy 0.19177 -0.16256) (xy 0.19812 -0.15367) (xy 0.20828 -0.13335)
						(xy 0.21971 -0.10287) (xy 0.22225 -0.09271) (xy 0.22479 -0.08128) (xy 0.22606 -0.07112) (xy 0.2286 -0.05969)
						(xy 0.2286 -0.01651) (xy 0.22606 -0.00508) (xy 0.22479 0.00508) (xy 0.22225 0.01651) (xy 0.21971 0.02667)
						(xy 0.20828 0.05715) (xy 0.19812 0.07747) (xy 0.19177 0.08636) (xy 0.18669 0.09525) (xy 0.17907 0.10414)
						(xy 0.17272 0.11303) (xy 0.1651 0.12065) (xy 0.1651 0.7366) (xy 0.16256 0.76835) (xy 0.1524 0.8001)
						(xy 0.13716 0.82804) (xy 0.11684 0.85344) (xy 0.09144 0.87376) (xy 0.0635 0.889) (xy 0.03175 0.89916)
					)
					(width 0)
					(fill yes)
				)
			)
		)
		(pad "20" smd custom
			(at -25.94991 -4.106672 180)
			(size 0.1143 0.1143)
			(layers "F.Cu" "F.Mask" "F.Paste")
			(net "GND")
			(options
				(clearance outline)
				(anchor circle)
			)
			(primitives
				(gr_poly
					(pts
						(xy 0 0.9017) (xy -0.03175 0.89916) (xy -0.0635 0.889) (xy -0.09144 0.87376) (xy -0.11684 0.85344)
						(xy -0.13716 0.82804) (xy -0.1524 0.8001) (xy -0.16256 0.76835) (xy -0.1651 0.7366) (xy -0.1651 0.19685)
						(xy -0.17272 0.18923) (xy -0.17907 0.18034) (xy -0.18669 0.17145) (xy -0.19177 0.16256) (xy -0.19812 0.15367)
						(xy -0.20828 0.13335) (xy -0.21971 0.10287) (xy -0.22225 0.09271) (xy -0.22479 0.08128) (xy -0.22606 0.07112)
						(xy -0.2286 0.05969) (xy -0.2286 0.01651) (xy -0.22606 0.00508) (xy -0.22479 -0.00508) (xy -0.22225 -0.01651)
						(xy -0.21971 -0.02667) (xy -0.20828 -0.05715) (xy -0.19812 -0.07747) (xy -0.19177 -0.08636) (xy -0.18669 -0.09525)
						(xy -0.17907 -0.10414) (xy -0.17272 -0.11303) (xy -0.1651 -0.12065) (xy -0.1651 -0.7366) (xy -0.16256 -0.76835)
						(xy -0.1524 -0.8001) (xy -0.13716 -0.82804) (xy -0.11684 -0.85344) (xy -0.09144 -0.87376) (xy -0.0635 -0.889)
						(xy -0.03175 -0.89916) (xy 0 -0.9017) (xy 0.03175 -0.89916) (xy 0.0635 -0.889) (xy 0.09144 -0.87376)
						(xy 0.11684 -0.85344) (xy 0.13716 -0.82804) (xy 0.1524 -0.8001) (xy 0.16256 -0.76835) (xy 0.1651 -0.7366)
						(xy 0.1651 -0.11938) (xy 0.17272 -0.11176) (xy 0.19812 -0.0762) (xy 0.2032 -0.06604) (xy 0.20701 -0.05715)
						(xy 0.21209 -0.04699) (xy 0.2159 -0.03683) (xy 0.21844 -0.02667) (xy 0.22225 -0.01524) (xy 0.22352 -0.00508)
						(xy 0.22606 0.00508) (xy 0.22733 0.01651) (xy 0.22733 0.02667) (xy 0.2286 0.0381) (xy 0.22733 0.04953)
						(xy 0.22733 0.05969) (xy 0.22606 0.07112) (xy 0.22352 0.08128) (xy 0.22225 0.09144) (xy 0.21844 0.10287)
						(xy 0.2159 0.11303) (xy 0.21209 0.12319) (xy 0.20701 0.13335) (xy 0.2032 0.14224) (xy 0.19812 0.1524)
						(xy 0.17272 0.18796) (xy 0.1651 0.19558) (xy 0.1651 0.7366) (xy 0.16256 0.76835) (xy 0.1524 0.8001)
						(xy 0.13716 0.82804) (xy 0.11684 0.85344) (xy 0.09144 0.87376) (xy 0.0635 0.889) (xy 0.03175 0.89916)
					)
					(width 0)
					(fill yes)
				)
			)
		)
		(pad "21" smd custom
			(at -25.649936 4.106672 180)
			(size 0.1143 0.1143)
			(layers "F.Cu" "F.Mask" "F.Paste")
			(net "M_A_DQ13")
			(options
				(clearance outline)
				(anchor circle)
			)
			(primitives
				(gr_poly
					(pts
						(xy 0 0.9017) (xy -0.03175 0.89916) (xy -0.0635 0.889) (xy -0.09144 0.87376) (xy -0.11684 0.85344)
						(xy -0.13716 0.82804) (xy -0.1524 0.8001) (xy -0.16256 0.76835) (xy -0.1651 0.7366) (xy -0.1651 -0.13462)
						(xy -0.17272 -0.14224) (xy -0.19812 -0.1778) (xy -0.2032 -0.18796) (xy -0.20701 -0.19685) (xy -0.21209 -0.20701)
						(xy -0.2159 -0.21717) (xy -0.21844 -0.22733) (xy -0.22225 -0.23876) (xy -0.22352 -0.24892) (xy -0.22606 -0.25908)
						(xy -0.22733 -0.27051) (xy -0.22733 -0.28067) (xy -0.2286 -0.2921) (xy -0.22733 -0.30353) (xy -0.22733 -0.31369)
						(xy -0.22606 -0.32512) (xy -0.22352 -0.33528) (xy -0.22225 -0.34544) (xy -0.21844 -0.35687) (xy -0.2159 -0.36703)
						(xy -0.21209 -0.37719) (xy -0.20701 -0.38735) (xy -0.2032 -0.39624) (xy -0.19812 -0.4064) (xy -0.17272 -0.44196)
						(xy -0.1651 -0.44958) (xy -0.1651 -0.7366) (xy -0.16256 -0.76835) (xy -0.1524 -0.8001) (xy -0.13716 -0.82804)
						(xy -0.11684 -0.85344) (xy -0.09144 -0.87376) (xy -0.0635 -0.889) (xy -0.03175 -0.89916) (xy 0 -0.9017)
						(xy 0.03175 -0.89916) (xy 0.0635 -0.889) (xy 0.09144 -0.87376) (xy 0.11684 -0.85344) (xy 0.13716 -0.82804)
						(xy 0.1524 -0.8001) (xy 0.16256 -0.76835) (xy 0.1651 -0.7366) (xy 0.1651 -0.44958) (xy 0.17272 -0.44196)
						(xy 0.19812 -0.4064) (xy 0.2032 -0.39624) (xy 0.20701 -0.38735) (xy 0.21209 -0.37719) (xy 0.2159 -0.36703)
						(xy 0.21844 -0.35687) (xy 0.22225 -0.34544) (xy 0.22352 -0.33528) (xy 0.22606 -0.32512) (xy 0.22733 -0.31369)
						(xy 0.22733 -0.30353) (xy 0.2286 -0.2921) (xy 0.22733 -0.28067) (xy 0.22733 -0.27051) (xy 0.22606 -0.25908)
						(xy 0.22352 -0.24892) (xy 0.22225 -0.23876) (xy 0.21844 -0.22733) (xy 0.2159 -0.21717) (xy 0.21209 -0.20701)
						(xy 0.20701 -0.19685) (xy 0.2032 -0.18796) (xy 0.19812 -0.1778) (xy 0.17272 -0.14224) (xy 0.1651 -0.13462)
						(xy 0.1651 0.7366) (xy 0.16256 0.76835) (xy 0.1524 0.8001) (xy 0.13716 0.82804) (xy 0.11684 0.85344)
						(xy 0.09144 0.87376) (xy 0.0635 0.889) (xy 0.03175 0.89916)
					)
					(width 0)
					(fill yes)
				)
			)
		)
		(pad "22" smd custom
			(at -25.349962 -4.106672 180)
			(size 0.1143 0.1143)
			(layers "F.Cu" "F.Mask" "F.Paste")
			(net "M_A_DQ8")
			(options
				(clearance outline)
				(anchor circle)
			)
			(primitives
				(gr_poly
					(pts
						(xy 0 0.9017) (xy -0.03175 0.89916) (xy -0.0635 0.889) (xy -0.09144 0.87376) (xy -0.11684 0.85344)
						(xy -0.13716 0.82804) (xy -0.1524 0.8001) (xy -0.16256 0.76835) (xy -0.1651 0.7366) (xy -0.1651 0.44958)
						(xy -0.17272 0.44196) (xy -0.19812 0.4064) (xy -0.2032 0.39624) (xy -0.20701 0.38735) (xy -0.21209 0.37719)
						(xy -0.2159 0.36703) (xy -0.21844 0.35687) (xy -0.22225 0.34544) (xy -0.22352 0.33528) (xy -0.22606 0.32512)
						(xy -0.22733 0.31369) (xy -0.22733 0.30353) (xy -0.2286 0.2921) (xy -0.22733 0.28067) (xy -0.22733 0.27051)
						(xy -0.22606 0.25908) (xy -0.22352 0.24892) (xy -0.22225 0.23876) (xy -0.21844 0.22733) (xy -0.2159 0.21717)
						(xy -0.21209 0.20701) (xy -0.20701 0.19685) (xy -0.2032 0.18796) (xy -0.19812 0.1778) (xy -0.17272 0.14224)
						(xy -0.1651 0.13462) (xy -0.1651 -0.7366) (xy -0.16256 -0.76835) (xy -0.1524 -0.8001) (xy -0.13716 -0.82804)
						(xy -0.11684 -0.85344) (xy -0.09144 -0.87376) (xy -0.0635 -0.889) (xy -0.03175 -0.89916) (xy 0 -0.9017)
						(xy 0.03175 -0.89916) (xy 0.0635 -0.889) (xy 0.09144 -0.87376) (xy 0.11684 -0.85344) (xy 0.13716 -0.82804)
						(xy 0.1524 -0.8001) (xy 0.16256 -0.76835) (xy 0.1651 -0.7366) (xy 0.1651 0.13462) (xy 0.17272 0.14224)
						(xy 0.19812 0.1778) (xy 0.2032 0.18796) (xy 0.20701 0.19685) (xy 0.21209 0.20701) (xy 0.2159 0.21717)
						(xy 0.21844 0.22733) (xy 0.22225 0.23876) (xy 0.22352 0.24892) (xy 0.22606 0.25908) (xy 0.22733 0.27051)
						(xy 0.22733 0.28067) (xy 0.2286 0.2921) (xy 0.22733 0.30353) (xy 0.22733 0.31369) (xy 0.22606 0.32512)
						(xy 0.22352 0.33528) (xy 0.22225 0.34544) (xy 0.21844 0.35687) (xy 0.2159 0.36703) (xy 0.21209 0.37719)
						(xy 0.20701 0.38735) (xy 0.2032 0.39624) (xy 0.19812 0.4064) (xy 0.17272 0.44196) (xy 0.1651 0.44958)
						(xy 0.1651 0.7366) (xy 0.16256 0.76835) (xy 0.1524 0.8001) (xy 0.13716 0.82804) (xy 0.11684 0.85344)
						(xy 0.09144 0.87376) (xy 0.0635 0.889) (xy 0.03175 0.89916)
					)
					(width 0)
					(fill yes)
				)
			)
		)
		(pad "23" smd custom
			(at -25.049988 4.106672 180)
			(size 0.1143 0.1143)
			(layers "F.Cu" "F.Mask" "F.Paste")
			(net "GND")
			(options
				(clearance outline)
				(anchor circle)
			)
			(primitives
				(gr_poly
					(pts
						(xy 0 0.9017) (xy -0.03175 0.89916) (xy -0.0635 0.889) (xy -0.09144 0.87376) (xy -0.11684 0.85344)
						(xy -0.13716 0.82804) (xy -0.1524 0.8001) (xy -0.16256 0.76835) (xy -0.1651 0.7366) (xy -0.1651 0.11938)
						(xy -0.17272 0.11176) (xy -0.19812 0.0762) (xy -0.2032 0.06604) (xy -0.20701 0.05715) (xy -0.21209 0.04699)
						(xy -0.2159 0.03683) (xy -0.21844 0.02667) (xy -0.22225 0.01524) (xy -0.22352 0.00508) (xy -0.22606 -0.00508)
						(xy -0.22733 -0.01651) (xy -0.22733 -0.02667) (xy -0.2286 -0.0381) (xy -0.22733 -0.04953) (xy -0.22733 -0.05969)
						(xy -0.22606 -0.07112) (xy -0.22352 -0.08128) (xy -0.22225 -0.09144) (xy -0.21844 -0.10287) (xy -0.2159 -0.11303)
						(xy -0.21209 -0.12319) (xy -0.20701 -0.13335) (xy -0.2032 -0.14224) (xy -0.19812 -0.1524) (xy -0.17272 -0.18796)
						(xy -0.1651 -0.19558) (xy -0.1651 -0.7366) (xy -0.16256 -0.76835) (xy -0.1524 -0.8001) (xy -0.13716 -0.82804)
						(xy -0.11684 -0.85344) (xy -0.09144 -0.87376) (xy -0.0635 -0.889) (xy -0.03175 -0.89916) (xy 0 -0.9017)
						(xy 0.03175 -0.89916) (xy 0.0635 -0.889) (xy 0.09144 -0.87376) (xy 0.11684 -0.85344) (xy 0.13716 -0.82804)
						(xy 0.1524 -0.8001) (xy 0.16256 -0.76835) (xy 0.1651 -0.7366) (xy 0.1651 -0.19685) (xy 0.17272 -0.18923)
						(xy 0.17907 -0.18034) (xy 0.18669 -0.17145) (xy 0.19177 -0.16256) (xy 0.19812 -0.15367) (xy 0.20828 -0.13335)
						(xy 0.21971 -0.10287) (xy 0.22225 -0.09271) (xy 0.22479 -0.08128) (xy 0.22606 -0.07112) (xy 0.2286 -0.05969)
						(xy 0.2286 -0.01651) (xy 0.22606 -0.00508) (xy 0.22479 0.00508) (xy 0.22225 0.01651) (xy 0.21971 0.02667)
						(xy 0.20828 0.05715) (xy 0.19812 0.07747) (xy 0.19177 0.08636) (xy 0.18669 0.09525) (xy 0.17907 0.10414)
						(xy 0.17272 0.11303) (xy 0.1651 0.12065) (xy 0.1651 0.7366) (xy 0.16256 0.76835) (xy 0.1524 0.8001)
						(xy 0.13716 0.82804) (xy 0.11684 0.85344) (xy 0.09144 0.87376) (xy 0.0635 0.889) (xy 0.03175 0.89916)
					)
					(width 0)
					(fill yes)
				)
			)
		)
		(pad "24" smd custom
			(at -24.750014 -4.106672 180)
			(size 0.1143 0.1143)
			(layers "F.Cu" "F.Mask" "F.Paste")
			(net "M_A_DQ9")
			(options
				(clearance outline)
				(anchor circle)
			)
			(primitives
				(gr_poly
					(pts
						(xy 0 0.9017) (xy -0.03175 0.89916) (xy -0.0635 0.889) (xy -0.09144 0.87376) (xy -0.11684 0.85344)
						(xy -0.13716 0.82804) (xy -0.1524 0.8001) (xy -0.16256 0.76835) (xy -0.1651 0.7366) (xy -0.1651 0.19685)
						(xy -0.17272 0.18923) (xy -0.17907 0.18034) (xy -0.18669 0.17145) (xy -0.19177 0.16256) (xy -0.19812 0.15367)
						(xy -0.20828 0.13335) (xy -0.21971 0.10287) (xy -0.22225 0.09271) (xy -0.22479 0.08128) (xy -0.22606 0.07112)
						(xy -0.2286 0.05969) (xy -0.2286 0.01651) (xy -0.22606 0.00508) (xy -0.22479 -0.00508) (xy -0.22225 -0.01651)
						(xy -0.21971 -0.02667) (xy -0.20828 -0.05715) (xy -0.19812 -0.07747) (xy -0.19177 -0.08636) (xy -0.18669 -0.09525)
						(xy -0.17907 -0.10414) (xy -0.17272 -0.11303) (xy -0.1651 -0.12065) (xy -0.1651 -0.7366) (xy -0.16256 -0.76835)
						(xy -0.1524 -0.8001) (xy -0.13716 -0.82804) (xy -0.11684 -0.85344) (xy -0.09144 -0.87376) (xy -0.0635 -0.889)
						(xy -0.03175 -0.89916) (xy 0 -0.9017) (xy 0.03175 -0.89916) (xy 0.0635 -0.889) (xy 0.09144 -0.87376)
						(xy 0.11684 -0.85344) (xy 0.13716 -0.82804) (xy 0.1524 -0.8001) (xy 0.16256 -0.76835) (xy 0.1651 -0.7366)
						(xy 0.1651 -0.11938) (xy 0.17272 -0.11176) (xy 0.19812 -0.0762) (xy 0.2032 -0.06604) (xy 0.20701 -0.05715)
						(xy 0.21209 -0.04699) (xy 0.2159 -0.03683) (xy 0.21844 -0.02667) (xy 0.22225 -0.01524) (xy 0.22352 -0.00508)
						(xy 0.22606 0.00508) (xy 0.22733 0.01651) (xy 0.22733 0.02667) (xy 0.2286 0.0381) (xy 0.22733 0.04953)
						(xy 0.22733 0.05969) (xy 0.22606 0.07112) (xy 0.22352 0.08128) (xy 0.22225 0.09144) (xy 0.21844 0.10287)
						(xy 0.2159 0.11303) (xy 0.21209 0.12319) (xy 0.20701 0.13335) (xy 0.2032 0.14224) (xy 0.19812 0.1524)
						(xy 0.17272 0.18796) (xy 0.1651 0.19558) (xy 0.1651 0.7366) (xy 0.16256 0.76835) (xy 0.1524 0.8001)
						(xy 0.13716 0.82804) (xy 0.11684 0.85344) (xy 0.09144 0.87376) (xy 0.0635 0.889) (xy 0.03175 0.89916)
					)
					(width 0)
					(fill yes)
				)
			)
		)
		(pad "25" smd custom
			(at -24.45004 4.106672 180)
			(size 0.1143 0.1143)
			(layers "F.Cu" "F.Mask" "F.Paste")
			(net "M_A_DQS_DN1")
			(options
				(clearance outline)
				(anchor circle)
			)
			(primitives
				(gr_poly
					(pts
						(xy 0 0.9017) (xy -0.03175 0.89916) (xy -0.0635 0.889) (xy -0.09144 0.87376) (xy -0.11684 0.85344)
						(xy -0.13716 0.82804) (xy -0.1524 0.8001) (xy -0.16256 0.76835) (xy -0.1651 0.7366) (xy -0.1651 -0.13462)
						(xy -0.17272 -0.14224) (xy -0.19812 -0.1778) (xy -0.2032 -0.18796) (xy -0.20701 -0.19685) (xy -0.21209 -0.20701)
						(xy -0.2159 -0.21717) (xy -0.21844 -0.22733) (xy -0.22225 -0.23876) (xy -0.22352 -0.24892) (xy -0.22606 -0.25908)
						(xy -0.22733 -0.27051) (xy -0.22733 -0.28067) (xy -0.2286 -0.2921) (xy -0.22733 -0.30353) (xy -0.22733 -0.31369)
						(xy -0.22606 -0.32512) (xy -0.22352 -0.33528) (xy -0.22225 -0.34544) (xy -0.21844 -0.35687) (xy -0.2159 -0.36703)
						(xy -0.21209 -0.37719) (xy -0.20701 -0.38735) (xy -0.2032 -0.39624) (xy -0.19812 -0.4064) (xy -0.17272 -0.44196)
						(xy -0.1651 -0.44958) (xy -0.1651 -0.7366) (xy -0.16256 -0.76835) (xy -0.1524 -0.8001) (xy -0.13716 -0.82804)
						(xy -0.11684 -0.85344) (xy -0.09144 -0.87376) (xy -0.0635 -0.889) (xy -0.03175 -0.89916) (xy 0 -0.9017)
						(xy 0.03175 -0.89916) (xy 0.0635 -0.889) (xy 0.09144 -0.87376) (xy 0.11684 -0.85344) (xy 0.13716 -0.82804)
						(xy 0.1524 -0.8001) (xy 0.16256 -0.76835) (xy 0.1651 -0.7366) (xy 0.1651 -0.44958) (xy 0.17272 -0.44196)
						(xy 0.19812 -0.4064) (xy 0.2032 -0.39624) (xy 0.20701 -0.38735) (xy 0.21209 -0.37719) (xy 0.2159 -0.36703)
						(xy 0.21844 -0.35687) (xy 0.22225 -0.34544) (xy 0.22352 -0.33528) (xy 0.22606 -0.32512) (xy 0.22733 -0.31369)
						(xy 0.22733 -0.30353) (xy 0.2286 -0.2921) (xy 0.22733 -0.28067) (xy 0.22733 -0.27051) (xy 0.22606 -0.25908)
						(xy 0.22352 -0.24892) (xy 0.22225 -0.23876) (xy 0.21844 -0.22733) (xy 0.2159 -0.21717) (xy 0.21209 -0.20701)
						(xy 0.20701 -0.19685) (xy 0.2032 -0.18796) (xy 0.19812 -0.1778) (xy 0.17272 -0.14224) (xy 0.1651 -0.13462)
						(xy 0.1651 0.7366) (xy 0.16256 0.76835) (xy 0.1524 0.8001) (xy 0.13716 0.82804) (xy 0.11684 0.85344)
						(xy 0.09144 0.87376) (xy 0.0635 0.889) (xy 0.03175 0.89916)
					)
					(width 0)
					(fill yes)
				)
			)
		)
		(pad "26" smd custom
			(at -24.150066 -4.106672 180)
			(size 0.1143 0.1143)
			(layers "F.Cu" "F.Mask" "F.Paste")
			(net "GND")
			(options
				(clearance outline)
				(anchor circle)
			)
			(primitives
				(gr_poly
					(pts
						(xy 0 0.9017) (xy -0.03175 0.89916) (xy -0.0635 0.889) (xy -0.09144 0.87376) (xy -0.11684 0.85344)
						(xy -0.13716 0.82804) (xy -0.1524 0.8001) (xy -0.16256 0.76835) (xy -0.1651 0.7366) (xy -0.1651 0.44958)
						(xy -0.17272 0.44196) (xy -0.19812 0.4064) (xy -0.2032 0.39624) (xy -0.20701 0.38735) (xy -0.21209 0.37719)
						(xy -0.2159 0.36703) (xy -0.21844 0.35687) (xy -0.22225 0.34544) (xy -0.22352 0.33528) (xy -0.22606 0.32512)
						(xy -0.22733 0.31369) (xy -0.22733 0.30353) (xy -0.2286 0.2921) (xy -0.22733 0.28067) (xy -0.22733 0.27051)
						(xy -0.22606 0.25908) (xy -0.22352 0.24892) (xy -0.22225 0.23876) (xy -0.21844 0.22733) (xy -0.2159 0.21717)
						(xy -0.21209 0.20701) (xy -0.20701 0.19685) (xy -0.2032 0.18796) (xy -0.19812 0.1778) (xy -0.17272 0.14224)
						(xy -0.1651 0.13462) (xy -0.1651 -0.7366) (xy -0.16256 -0.76835) (xy -0.1524 -0.8001) (xy -0.13716 -0.82804)
						(xy -0.11684 -0.85344) (xy -0.09144 -0.87376) (xy -0.0635 -0.889) (xy -0.03175 -0.89916) (xy 0 -0.9017)
						(xy 0.03175 -0.89916) (xy 0.0635 -0.889) (xy 0.09144 -0.87376) (xy 0.11684 -0.85344) (xy 0.13716 -0.82804)
						(xy 0.1524 -0.8001) (xy 0.16256 -0.76835) (xy 0.1651 -0.7366) (xy 0.1651 0.13462) (xy 0.17272 0.14224)
						(xy 0.19812 0.1778) (xy 0.2032 0.18796) (xy 0.20701 0.19685) (xy 0.21209 0.20701) (xy 0.2159 0.21717)
						(xy 0.21844 0.22733) (xy 0.22225 0.23876) (xy 0.22352 0.24892) (xy 0.22606 0.25908) (xy 0.22733 0.27051)
						(xy 0.22733 0.28067) (xy 0.2286 0.2921) (xy 0.22733 0.30353) (xy 0.22733 0.31369) (xy 0.22606 0.32512)
						(xy 0.22352 0.33528) (xy 0.22225 0.34544) (xy 0.21844 0.35687) (xy 0.2159 0.36703) (xy 0.21209 0.37719)
						(xy 0.20701 0.38735) (xy 0.2032 0.39624) (xy 0.19812 0.4064) (xy 0.17272 0.44196) (xy 0.1651 0.44958)
						(xy 0.1651 0.7366) (xy 0.16256 0.76835) (xy 0.1524 0.8001) (xy 0.13716 0.82804) (xy 0.11684 0.85344)
						(xy 0.09144 0.87376) (xy 0.0635 0.889) (xy 0.03175 0.89916)
					)
					(width 0)
					(fill yes)
				)
			)
		)
		(pad "27" smd custom
			(at -23.850092 4.106672 180)
			(size 0.1143 0.1143)
			(layers "F.Cu" "F.Mask" "F.Paste")
			(net "M_A_DQS_DP1")
			(options
				(clearance outline)
				(anchor circle)
			)
			(primitives
				(gr_poly
					(pts
						(xy 0 0.9017) (xy -0.03175 0.89916) (xy -0.0635 0.889) (xy -0.09144 0.87376) (xy -0.11684 0.85344)
						(xy -0.13716 0.82804) (xy -0.1524 0.8001) (xy -0.16256 0.76835) (xy -0.1651 0.7366) (xy -0.1651 0.11938)
						(xy -0.17272 0.11176) (xy -0.19812 0.0762) (xy -0.2032 0.06604) (xy -0.20701 0.05715) (xy -0.21209 0.04699)
						(xy -0.2159 0.03683) (xy -0.21844 0.02667) (xy -0.22225 0.01524) (xy -0.22352 0.00508) (xy -0.22606 -0.00508)
						(xy -0.22733 -0.01651) (xy -0.22733 -0.02667) (xy -0.2286 -0.0381) (xy -0.22733 -0.04953) (xy -0.22733 -0.05969)
						(xy -0.22606 -0.07112) (xy -0.22352 -0.08128) (xy -0.22225 -0.09144) (xy -0.21844 -0.10287) (xy -0.2159 -0.11303)
						(xy -0.21209 -0.12319) (xy -0.20701 -0.13335) (xy -0.2032 -0.14224) (xy -0.19812 -0.1524) (xy -0.17272 -0.18796)
						(xy -0.1651 -0.19558) (xy -0.1651 -0.7366) (xy -0.16256 -0.76835) (xy -0.1524 -0.8001) (xy -0.13716 -0.82804)
						(xy -0.11684 -0.85344) (xy -0.09144 -0.87376) (xy -0.0635 -0.889) (xy -0.03175 -0.89916) (xy 0 -0.9017)
						(xy 0.03175 -0.89916) (xy 0.0635 -0.889) (xy 0.09144 -0.87376) (xy 0.11684 -0.85344) (xy 0.13716 -0.82804)
						(xy 0.1524 -0.8001) (xy 0.16256 -0.76835) (xy 0.1651 -0.7366) (xy 0.1651 -0.19685) (xy 0.17272 -0.18923)
						(xy 0.17907 -0.18034) (xy 0.18669 -0.17145) (xy 0.19177 -0.16256) (xy 0.19812 -0.15367) (xy 0.20828 -0.13335)
						(xy 0.21971 -0.10287) (xy 0.22225 -0.09271) (xy 0.22479 -0.08128) (xy 0.22606 -0.07112) (xy 0.2286 -0.05969)
						(xy 0.2286 -0.01651) (xy 0.22606 -0.00508) (xy 0.22479 0.00508) (xy 0.22225 0.01651) (xy 0.21971 0.02667)
						(xy 0.20828 0.05715) (xy 0.19812 0.07747) (xy 0.19177 0.08636) (xy 0.18669 0.09525) (xy 0.17907 0.10414)
						(xy 0.17272 0.11303) (xy 0.1651 0.12065) (xy 0.1651 0.7366) (xy 0.16256 0.76835) (xy 0.1524 0.8001)
						(xy 0.13716 0.82804) (xy 0.11684 0.85344) (xy 0.09144 0.87376) (xy 0.0635 0.889) (xy 0.03175 0.89916)
					)
					(width 0)
					(fill yes)
				)
			)
		)
		(pad "28" smd custom
			(at -23.550118 -4.106672 180)
			(size 0.1143 0.1143)
			(layers "F.Cu" "F.Mask" "F.Paste")
			(net "GND")
			(options
				(clearance outline)
				(anchor circle)
			)
			(primitives
				(gr_poly
					(pts
						(xy 0 0.9017) (xy -0.03175 0.89916) (xy -0.0635 0.889) (xy -0.09144 0.87376) (xy -0.11684 0.85344)
						(xy -0.13716 0.82804) (xy -0.1524 0.8001) (xy -0.16256 0.76835) (xy -0.1651 0.7366) (xy -0.1651 0.19685)
						(xy -0.17272 0.18923) (xy -0.17907 0.18034) (xy -0.18669 0.17145) (xy -0.19177 0.16256) (xy -0.19812 0.15367)
						(xy -0.20828 0.13335) (xy -0.21971 0.10287) (xy -0.22225 0.09271) (xy -0.22479 0.08128) (xy -0.22606 0.07112)
						(xy -0.2286 0.05969) (xy -0.2286 0.01651) (xy -0.22606 0.00508) (xy -0.22479 -0.00508) (xy -0.22225 -0.01651)
						(xy -0.21971 -0.02667) (xy -0.20828 -0.05715) (xy -0.19812 -0.07747) (xy -0.19177 -0.08636) (xy -0.18669 -0.09525)
						(xy -0.17907 -0.10414) (xy -0.17272 -0.11303) (xy -0.1651 -0.12065) (xy -0.1651 -0.7366) (xy -0.16256 -0.76835)
						(xy -0.1524 -0.8001) (xy -0.13716 -0.82804) (xy -0.11684 -0.85344) (xy -0.09144 -0.87376) (xy -0.0635 -0.889)
						(xy -0.03175 -0.89916) (xy 0 -0.9017) (xy 0.03175 -0.89916) (xy 0.0635 -0.889) (xy 0.09144 -0.87376)
						(xy 0.11684 -0.85344) (xy 0.13716 -0.82804) (xy 0.1524 -0.8001) (xy 0.16256 -0.76835) (xy 0.1651 -0.7366)
						(xy 0.1651 -0.11938) (xy 0.17272 -0.11176) (xy 0.19812 -0.0762) (xy 0.2032 -0.06604) (xy 0.20701 -0.05715)
						(xy 0.21209 -0.04699) (xy 0.2159 -0.03683) (xy 0.21844 -0.02667) (xy 0.22225 -0.01524) (xy 0.22352 -0.00508)
						(xy 0.22606 0.00508) (xy 0.22733 0.01651) (xy 0.22733 0.02667) (xy 0.2286 0.0381) (xy 0.22733 0.04953)
						(xy 0.22733 0.05969) (xy 0.22606 0.07112) (xy 0.22352 0.08128) (xy 0.22225 0.09144) (xy 0.21844 0.10287)
						(xy 0.2159 0.11303) (xy 0.21209 0.12319) (xy 0.20701 0.13335) (xy 0.2032 0.14224) (xy 0.19812 0.1524)
						(xy 0.17272 0.18796) (xy 0.1651 0.19558) (xy 0.1651 0.7366) (xy 0.16256 0.76835) (xy 0.1524 0.8001)
						(xy 0.13716 0.82804) (xy 0.11684 0.85344) (xy 0.09144 0.87376) (xy 0.0635 0.889) (xy 0.03175 0.89916)
					)
					(width 0)
					(fill yes)
				)
			)
		)
		(pad "29" smd custom
			(at -23.24989 4.106672 180)
			(size 0.1143 0.1143)
			(layers "F.Cu" "F.Mask" "F.Paste")
			(net "GND")
			(options
				(clearance outline)
				(anchor circle)
			)
			(primitives
				(gr_poly
					(pts
						(xy 0 0.9017) (xy -0.03175 0.89916) (xy -0.0635 0.889) (xy -0.09144 0.87376) (xy -0.11684 0.85344)
						(xy -0.13716 0.82804) (xy -0.1524 0.8001) (xy -0.16256 0.76835) (xy -0.1651 0.7366) (xy -0.1651 -0.13462)
						(xy -0.17272 -0.14224) (xy -0.19812 -0.1778) (xy -0.2032 -0.18796) (xy -0.20701 -0.19685) (xy -0.21209 -0.20701)
						(xy -0.2159 -0.21717) (xy -0.21844 -0.22733) (xy -0.22225 -0.23876) (xy -0.22352 -0.24892) (xy -0.22606 -0.25908)
						(xy -0.22733 -0.27051) (xy -0.22733 -0.28067) (xy -0.2286 -0.2921) (xy -0.22733 -0.30353) (xy -0.22733 -0.31369)
						(xy -0.22606 -0.32512) (xy -0.22352 -0.33528) (xy -0.22225 -0.34544) (xy -0.21844 -0.35687) (xy -0.2159 -0.36703)
						(xy -0.21209 -0.37719) (xy -0.20701 -0.38735) (xy -0.2032 -0.39624) (xy -0.19812 -0.4064) (xy -0.17272 -0.44196)
						(xy -0.1651 -0.44958) (xy -0.1651 -0.7366) (xy -0.16256 -0.76835) (xy -0.1524 -0.8001) (xy -0.13716 -0.82804)
						(xy -0.11684 -0.85344) (xy -0.09144 -0.87376) (xy -0.0635 -0.889) (xy -0.03175 -0.89916) (xy 0 -0.9017)
						(xy 0.03175 -0.89916) (xy 0.0635 -0.889) (xy 0.09144 -0.87376) (xy 0.11684 -0.85344) (xy 0.13716 -0.82804)
						(xy 0.1524 -0.8001) (xy 0.16256 -0.76835) (xy 0.1651 -0.7366) (xy 0.1651 -0.44958) (xy 0.17272 -0.44196)
						(xy 0.19812 -0.4064) (xy 0.2032 -0.39624) (xy 0.20701 -0.38735) (xy 0.21209 -0.37719) (xy 0.2159 -0.36703)
						(xy 0.21844 -0.35687) (xy 0.22225 -0.34544) (xy 0.22352 -0.33528) (xy 0.22606 -0.32512) (xy 0.22733 -0.31369)
						(xy 0.22733 -0.30353) (xy 0.2286 -0.2921) (xy 0.22733 -0.28067) (xy 0.22733 -0.27051) (xy 0.22606 -0.25908)
						(xy 0.22352 -0.24892) (xy 0.22225 -0.23876) (xy 0.21844 -0.22733) (xy 0.2159 -0.21717) (xy 0.21209 -0.20701)
						(xy 0.20701 -0.19685) (xy 0.2032 -0.18796) (xy 0.19812 -0.1778) (xy 0.17272 -0.14224) (xy 0.1651 -0.13462)
						(xy 0.1651 0.7366) (xy 0.16256 0.76835) (xy 0.1524 0.8001) (xy 0.13716 0.82804) (xy 0.11684 0.85344)
						(xy 0.09144 0.87376) (xy 0.0635 0.889) (xy 0.03175 0.89916)
					)
					(width 0)
					(fill yes)
				)
			)
		)
		(pad "30" smd custom
			(at -22.949916 -4.106672 180)
			(size 0.1143 0.1143)
			(layers "F.Cu" "F.Mask" "F.Paste")
			(net "M_A_RESET#")
			(options
				(clearance outline)
				(anchor circle)
			)
			(primitives
				(gr_poly
					(pts
						(xy 0 0.9017) (xy -0.03175 0.89916) (xy -0.0635 0.889) (xy -0.09144 0.87376) (xy -0.11684 0.85344)
						(xy -0.13716 0.82804) (xy -0.1524 0.8001) (xy -0.16256 0.76835) (xy -0.1651 0.7366) (xy -0.1651 0.44958)
						(xy -0.17272 0.44196) (xy -0.19812 0.4064) (xy -0.2032 0.39624) (xy -0.20701 0.38735) (xy -0.21209 0.37719)
						(xy -0.2159 0.36703) (xy -0.21844 0.35687) (xy -0.22225 0.34544) (xy -0.22352 0.33528) (xy -0.22606 0.32512)
						(xy -0.22733 0.31369) (xy -0.22733 0.30353) (xy -0.2286 0.2921) (xy -0.22733 0.28067) (xy -0.22733 0.27051)
						(xy -0.22606 0.25908) (xy -0.22352 0.24892) (xy -0.22225 0.23876) (xy -0.21844 0.22733) (xy -0.2159 0.21717)
						(xy -0.21209 0.20701) (xy -0.20701 0.19685) (xy -0.2032 0.18796) (xy -0.19812 0.1778) (xy -0.17272 0.14224)
						(xy -0.1651 0.13462) (xy -0.1651 -0.7366) (xy -0.16256 -0.76835) (xy -0.1524 -0.8001) (xy -0.13716 -0.82804)
						(xy -0.11684 -0.85344) (xy -0.09144 -0.87376) (xy -0.0635 -0.889) (xy -0.03175 -0.89916) (xy 0 -0.9017)
						(xy 0.03175 -0.89916) (xy 0.0635 -0.889) (xy 0.09144 -0.87376) (xy 0.11684 -0.85344) (xy 0.13716 -0.82804)
						(xy 0.1524 -0.8001) (xy 0.16256 -0.76835) (xy 0.1651 -0.7366) (xy 0.1651 0.13462) (xy 0.17272 0.14224)
						(xy 0.19812 0.1778) (xy 0.2032 0.18796) (xy 0.20701 0.19685) (xy 0.21209 0.20701) (xy 0.2159 0.21717)
						(xy 0.21844 0.22733) (xy 0.22225 0.23876) (xy 0.22352 0.24892) (xy 0.22606 0.25908) (xy 0.22733 0.27051)
						(xy 0.22733 0.28067) (xy 0.2286 0.2921) (xy 0.22733 0.30353) (xy 0.22733 0.31369) (xy 0.22606 0.32512)
						(xy 0.22352 0.33528) (xy 0.22225 0.34544) (xy 0.21844 0.35687) (xy 0.2159 0.36703) (xy 0.21209 0.37719)
						(xy 0.20701 0.38735) (xy 0.2032 0.39624) (xy 0.19812 0.4064) (xy 0.17272 0.44196) (xy 0.1651 0.44958)
						(xy 0.1651 0.7366) (xy 0.16256 0.76835) (xy 0.1524 0.8001) (xy 0.13716 0.82804) (xy 0.11684 0.85344)
						(xy 0.09144 0.87376) (xy 0.0635 0.889) (xy 0.03175 0.89916)
					)
					(width 0)
					(fill yes)
				)
			)
		)
		(pad "31" smd custom
			(at -22.649942 4.106672 180)
			(size 0.1143 0.1143)
			(layers "F.Cu" "F.Mask" "F.Paste")
			(net "M_A_DQ14")
			(options
				(clearance outline)
				(anchor circle)
			)
			(primitives
				(gr_poly
					(pts
						(xy 0 0.9017) (xy -0.03175 0.89916) (xy -0.0635 0.889) (xy -0.09144 0.87376) (xy -0.11684 0.85344)
						(xy -0.13716 0.82804) (xy -0.1524 0.8001) (xy -0.16256 0.76835) (xy -0.1651 0.7366) (xy -0.1651 0.11938)
						(xy -0.17272 0.11176) (xy -0.19812 0.0762) (xy -0.2032 0.06604) (xy -0.20701 0.05715) (xy -0.21209 0.04699)
						(xy -0.2159 0.03683) (xy -0.21844 0.02667) (xy -0.22225 0.01524) (xy -0.22352 0.00508) (xy -0.22606 -0.00508)
						(xy -0.22733 -0.01651) (xy -0.22733 -0.02667) (xy -0.2286 -0.0381) (xy -0.22733 -0.04953) (xy -0.22733 -0.05969)
						(xy -0.22606 -0.07112) (xy -0.22352 -0.08128) (xy -0.22225 -0.09144) (xy -0.21844 -0.10287) (xy -0.2159 -0.11303)
						(xy -0.21209 -0.12319) (xy -0.20701 -0.13335) (xy -0.2032 -0.14224) (xy -0.19812 -0.1524) (xy -0.17272 -0.18796)
						(xy -0.1651 -0.19558) (xy -0.1651 -0.7366) (xy -0.16256 -0.76835) (xy -0.1524 -0.8001) (xy -0.13716 -0.82804)
						(xy -0.11684 -0.85344) (xy -0.09144 -0.87376) (xy -0.0635 -0.889) (xy -0.03175 -0.89916) (xy 0 -0.9017)
						(xy 0.03175 -0.89916) (xy 0.0635 -0.889) (xy 0.09144 -0.87376) (xy 0.11684 -0.85344) (xy 0.13716 -0.82804)
						(xy 0.1524 -0.8001) (xy 0.16256 -0.76835) (xy 0.1651 -0.7366) (xy 0.1651 -0.19685) (xy 0.17272 -0.18923)
						(xy 0.17907 -0.18034) (xy 0.18669 -0.17145) (xy 0.19177 -0.16256) (xy 0.19812 -0.15367) (xy 0.20828 -0.13335)
						(xy 0.21971 -0.10287) (xy 0.22225 -0.09271) (xy 0.22479 -0.08128) (xy 0.22606 -0.07112) (xy 0.2286 -0.05969)
						(xy 0.2286 -0.01651) (xy 0.22606 -0.00508) (xy 0.22479 0.00508) (xy 0.22225 0.01651) (xy 0.21971 0.02667)
						(xy 0.20828 0.05715) (xy 0.19812 0.07747) (xy 0.19177 0.08636) (xy 0.18669 0.09525) (xy 0.17907 0.10414)
						(xy 0.17272 0.11303) (xy 0.1651 0.12065) (xy 0.1651 0.7366) (xy 0.16256 0.76835) (xy 0.1524 0.8001)
						(xy 0.13716 0.82804) (xy 0.11684 0.85344) (xy 0.09144 0.87376) (xy 0.0635 0.889) (xy 0.03175 0.89916)
					)
					(width 0)
					(fill yes)
				)
			)
		)
		(pad "32" smd custom
			(at -22.349968 -4.106672 180)
			(size 0.1143 0.1143)
			(layers "F.Cu" "F.Mask" "F.Paste")
			(net "GND")
			(options
				(clearance outline)
				(anchor circle)
			)
			(primitives
				(gr_poly
					(pts
						(xy 0 0.9017) (xy -0.03175 0.89916) (xy -0.0635 0.889) (xy -0.09144 0.87376) (xy -0.11684 0.85344)
						(xy -0.13716 0.82804) (xy -0.1524 0.8001) (xy -0.16256 0.76835) (xy -0.1651 0.7366) (xy -0.1651 0.19685)
						(xy -0.17272 0.18923) (xy -0.17907 0.18034) (xy -0.18669 0.17145) (xy -0.19177 0.16256) (xy -0.19812 0.15367)
						(xy -0.20828 0.13335) (xy -0.21971 0.10287) (xy -0.22225 0.09271) (xy -0.22479 0.08128) (xy -0.22606 0.07112)
						(xy -0.2286 0.05969) (xy -0.2286 0.01651) (xy -0.22606 0.00508) (xy -0.22479 -0.00508) (xy -0.22225 -0.01651)
						(xy -0.21971 -0.02667) (xy -0.20828 -0.05715) (xy -0.19812 -0.07747) (xy -0.19177 -0.08636) (xy -0.18669 -0.09525)
						(xy -0.17907 -0.10414) (xy -0.17272 -0.11303) (xy -0.1651 -0.12065) (xy -0.1651 -0.7366) (xy -0.16256 -0.76835)
						(xy -0.1524 -0.8001) (xy -0.13716 -0.82804) (xy -0.11684 -0.85344) (xy -0.09144 -0.87376) (xy -0.0635 -0.889)
						(xy -0.03175 -0.89916) (xy 0 -0.9017) (xy 0.03175 -0.89916) (xy 0.0635 -0.889) (xy 0.09144 -0.87376)
						(xy 0.11684 -0.85344) (xy 0.13716 -0.82804) (xy 0.1524 -0.8001) (xy 0.16256 -0.76835) (xy 0.1651 -0.7366)
						(xy 0.1651 -0.11938) (xy 0.17272 -0.11176) (xy 0.19812 -0.0762) (xy 0.2032 -0.06604) (xy 0.20701 -0.05715)
						(xy 0.21209 -0.04699) (xy 0.2159 -0.03683) (xy 0.21844 -0.02667) (xy 0.22225 -0.01524) (xy 0.22352 -0.00508)
						(xy 0.22606 0.00508) (xy 0.22733 0.01651) (xy 0.22733 0.02667) (xy 0.2286 0.0381) (xy 0.22733 0.04953)
						(xy 0.22733 0.05969) (xy 0.22606 0.07112) (xy 0.22352 0.08128) (xy 0.22225 0.09144) (xy 0.21844 0.10287)
						(xy 0.2159 0.11303) (xy 0.21209 0.12319) (xy 0.20701 0.13335) (xy 0.2032 0.14224) (xy 0.19812 0.1524)
						(xy 0.17272 0.18796) (xy 0.1651 0.19558) (xy 0.1651 0.7366) (xy 0.16256 0.76835) (xy 0.1524 0.8001)
						(xy 0.13716 0.82804) (xy 0.11684 0.85344) (xy 0.09144 0.87376) (xy 0.0635 0.889) (xy 0.03175 0.89916)
					)
					(width 0)
					(fill yes)
				)
			)
		)
		(pad "33" smd custom
			(at -22.049994 4.106672 180)
			(size 0.1143 0.1143)
			(layers "F.Cu" "F.Mask" "F.Paste")
			(net "M_A_DQ15")
			(options
				(clearance outline)
				(anchor circle)
			)
			(primitives
				(gr_poly
					(pts
						(xy 0 0.9017) (xy -0.03175 0.89916) (xy -0.0635 0.889) (xy -0.09144 0.87376) (xy -0.11684 0.85344)
						(xy -0.13716 0.82804) (xy -0.1524 0.8001) (xy -0.16256 0.76835) (xy -0.1651 0.7366) (xy -0.1651 -0.13462)
						(xy -0.17272 -0.14224) (xy -0.19812 -0.1778) (xy -0.2032 -0.18796) (xy -0.20701 -0.19685) (xy -0.21209 -0.20701)
						(xy -0.2159 -0.21717) (xy -0.21844 -0.22733) (xy -0.22225 -0.23876) (xy -0.22352 -0.24892) (xy -0.22606 -0.25908)
						(xy -0.22733 -0.27051) (xy -0.22733 -0.28067) (xy -0.2286 -0.2921) (xy -0.22733 -0.30353) (xy -0.22733 -0.31369)
						(xy -0.22606 -0.32512) (xy -0.22352 -0.33528) (xy -0.22225 -0.34544) (xy -0.21844 -0.35687) (xy -0.2159 -0.36703)
						(xy -0.21209 -0.37719) (xy -0.20701 -0.38735) (xy -0.2032 -0.39624) (xy -0.19812 -0.4064) (xy -0.17272 -0.44196)
						(xy -0.1651 -0.44958) (xy -0.1651 -0.7366) (xy -0.16256 -0.76835) (xy -0.1524 -0.8001) (xy -0.13716 -0.82804)
						(xy -0.11684 -0.85344) (xy -0.09144 -0.87376) (xy -0.0635 -0.889) (xy -0.03175 -0.89916) (xy 0 -0.9017)
						(xy 0.03175 -0.89916) (xy 0.0635 -0.889) (xy 0.09144 -0.87376) (xy 0.11684 -0.85344) (xy 0.13716 -0.82804)
						(xy 0.1524 -0.8001) (xy 0.16256 -0.76835) (xy 0.1651 -0.7366) (xy 0.1651 -0.44958) (xy 0.17272 -0.44196)
						(xy 0.19812 -0.4064) (xy 0.2032 -0.39624) (xy 0.20701 -0.38735) (xy 0.21209 -0.37719) (xy 0.2159 -0.36703)
						(xy 0.21844 -0.35687) (xy 0.22225 -0.34544) (xy 0.22352 -0.33528) (xy 0.22606 -0.32512) (xy 0.22733 -0.31369)
						(xy 0.22733 -0.30353) (xy 0.2286 -0.2921) (xy 0.22733 -0.28067) (xy 0.22733 -0.27051) (xy 0.22606 -0.25908)
						(xy 0.22352 -0.24892) (xy 0.22225 -0.23876) (xy 0.21844 -0.22733) (xy 0.2159 -0.21717) (xy 0.21209 -0.20701)
						(xy 0.20701 -0.19685) (xy 0.2032 -0.18796) (xy 0.19812 -0.1778) (xy 0.17272 -0.14224) (xy 0.1651 -0.13462)
						(xy 0.1651 0.7366) (xy 0.16256 0.76835) (xy 0.1524 0.8001) (xy 0.13716 0.82804) (xy 0.11684 0.85344)
						(xy 0.09144 0.87376) (xy 0.0635 0.889) (xy 0.03175 0.89916)
					)
					(width 0)
					(fill yes)
				)
			)
		)
		(pad "34" smd custom
			(at -21.75002 -4.106672 180)
			(size 0.1143 0.1143)
			(layers "F.Cu" "F.Mask" "F.Paste")
			(net "M_A_DQ10")
			(options
				(clearance outline)
				(anchor circle)
			)
			(primitives
				(gr_poly
					(pts
						(xy 0 0.9017) (xy -0.03175 0.89916) (xy -0.0635 0.889) (xy -0.09144 0.87376) (xy -0.11684 0.85344)
						(xy -0.13716 0.82804) (xy -0.1524 0.8001) (xy -0.16256 0.76835) (xy -0.1651 0.7366) (xy -0.1651 0.44958)
						(xy -0.17272 0.44196) (xy -0.19812 0.4064) (xy -0.2032 0.39624) (xy -0.20701 0.38735) (xy -0.21209 0.37719)
						(xy -0.2159 0.36703) (xy -0.21844 0.35687) (xy -0.22225 0.34544) (xy -0.22352 0.33528) (xy -0.22606 0.32512)
						(xy -0.22733 0.31369) (xy -0.22733 0.30353) (xy -0.2286 0.2921) (xy -0.22733 0.28067) (xy -0.22733 0.27051)
						(xy -0.22606 0.25908) (xy -0.22352 0.24892) (xy -0.22225 0.23876) (xy -0.21844 0.22733) (xy -0.2159 0.21717)
						(xy -0.21209 0.20701) (xy -0.20701 0.19685) (xy -0.2032 0.18796) (xy -0.19812 0.1778) (xy -0.17272 0.14224)
						(xy -0.1651 0.13462) (xy -0.1651 -0.7366) (xy -0.16256 -0.76835) (xy -0.1524 -0.8001) (xy -0.13716 -0.82804)
						(xy -0.11684 -0.85344) (xy -0.09144 -0.87376) (xy -0.0635 -0.889) (xy -0.03175 -0.89916) (xy 0 -0.9017)
						(xy 0.03175 -0.89916) (xy 0.0635 -0.889) (xy 0.09144 -0.87376) (xy 0.11684 -0.85344) (xy 0.13716 -0.82804)
						(xy 0.1524 -0.8001) (xy 0.16256 -0.76835) (xy 0.1651 -0.7366) (xy 0.1651 0.13462) (xy 0.17272 0.14224)
						(xy 0.19812 0.1778) (xy 0.2032 0.18796) (xy 0.20701 0.19685) (xy 0.21209 0.20701) (xy 0.2159 0.21717)
						(xy 0.21844 0.22733) (xy 0.22225 0.23876) (xy 0.22352 0.24892) (xy 0.22606 0.25908) (xy 0.22733 0.27051)
						(xy 0.22733 0.28067) (xy 0.2286 0.2921) (xy 0.22733 0.30353) (xy 0.22733 0.31369) (xy 0.22606 0.32512)
						(xy 0.22352 0.33528) (xy 0.22225 0.34544) (xy 0.21844 0.35687) (xy 0.2159 0.36703) (xy 0.21209 0.37719)
						(xy 0.20701 0.38735) (xy 0.2032 0.39624) (xy 0.19812 0.4064) (xy 0.17272 0.44196) (xy 0.1651 0.44958)
						(xy 0.1651 0.7366) (xy 0.16256 0.76835) (xy 0.1524 0.8001) (xy 0.13716 0.82804) (xy 0.11684 0.85344)
						(xy 0.09144 0.87376) (xy 0.0635 0.889) (xy 0.03175 0.89916)
					)
					(width 0)
					(fill yes)
				)
			)
		)
		(pad "35" smd custom
			(at -21.450046 4.106672 180)
			(size 0.1143 0.1143)
			(layers "F.Cu" "F.Mask" "F.Paste")
			(net "GND")
			(options
				(clearance outline)
				(anchor circle)
			)
			(primitives
				(gr_poly
					(pts
						(xy 0 0.9017) (xy -0.03175 0.89916) (xy -0.0635 0.889) (xy -0.09144 0.87376) (xy -0.11684 0.85344)
						(xy -0.13716 0.82804) (xy -0.1524 0.8001) (xy -0.16256 0.76835) (xy -0.1651 0.7366) (xy -0.1651 0.11938)
						(xy -0.17272 0.11176) (xy -0.19812 0.0762) (xy -0.2032 0.06604) (xy -0.20701 0.05715) (xy -0.21209 0.04699)
						(xy -0.2159 0.03683) (xy -0.21844 0.02667) (xy -0.22225 0.01524) (xy -0.22352 0.00508) (xy -0.22606 -0.00508)
						(xy -0.22733 -0.01651) (xy -0.22733 -0.02667) (xy -0.2286 -0.0381) (xy -0.22733 -0.04953) (xy -0.22733 -0.05969)
						(xy -0.22606 -0.07112) (xy -0.22352 -0.08128) (xy -0.22225 -0.09144) (xy -0.21844 -0.10287) (xy -0.2159 -0.11303)
						(xy -0.21209 -0.12319) (xy -0.20701 -0.13335) (xy -0.2032 -0.14224) (xy -0.19812 -0.1524) (xy -0.17272 -0.18796)
						(xy -0.1651 -0.19558) (xy -0.1651 -0.7366) (xy -0.16256 -0.76835) (xy -0.1524 -0.8001) (xy -0.13716 -0.82804)
						(xy -0.11684 -0.85344) (xy -0.09144 -0.87376) (xy -0.0635 -0.889) (xy -0.03175 -0.89916) (xy 0 -0.9017)
						(xy 0.03175 -0.89916) (xy 0.0635 -0.889) (xy 0.09144 -0.87376) (xy 0.11684 -0.85344) (xy 0.13716 -0.82804)
						(xy 0.1524 -0.8001) (xy 0.16256 -0.76835) (xy 0.1651 -0.7366) (xy 0.1651 -0.19685) (xy 0.17272 -0.18923)
						(xy 0.17907 -0.18034) (xy 0.18669 -0.17145) (xy 0.19177 -0.16256) (xy 0.19812 -0.15367) (xy 0.20828 -0.13335)
						(xy 0.21971 -0.10287) (xy 0.22225 -0.09271) (xy 0.22479 -0.08128) (xy 0.22606 -0.07112) (xy 0.2286 -0.05969)
						(xy 0.2286 -0.01651) (xy 0.22606 -0.00508) (xy 0.22479 0.00508) (xy 0.22225 0.01651) (xy 0.21971 0.02667)
						(xy 0.20828 0.05715) (xy 0.19812 0.07747) (xy 0.19177 0.08636) (xy 0.18669 0.09525) (xy 0.17907 0.10414)
						(xy 0.17272 0.11303) (xy 0.1651 0.12065) (xy 0.1651 0.7366) (xy 0.16256 0.76835) (xy 0.1524 0.8001)
						(xy 0.13716 0.82804) (xy 0.11684 0.85344) (xy 0.09144 0.87376) (xy 0.0635 0.889) (xy 0.03175 0.89916)
					)
					(width 0)
					(fill yes)
				)
			)
		)
		(pad "36" smd custom
			(at -21.150072 -4.106672 180)
			(size 0.1143 0.1143)
			(layers "F.Cu" "F.Mask" "F.Paste")
			(net "M_A_DQ11")
			(options
				(clearance outline)
				(anchor circle)
			)
			(primitives
				(gr_poly
					(pts
						(xy 0 0.9017) (xy -0.03175 0.89916) (xy -0.0635 0.889) (xy -0.09144 0.87376) (xy -0.11684 0.85344)
						(xy -0.13716 0.82804) (xy -0.1524 0.8001) (xy -0.16256 0.76835) (xy -0.1651 0.7366) (xy -0.1651 0.19685)
						(xy -0.17272 0.18923) (xy -0.17907 0.18034) (xy -0.18669 0.17145) (xy -0.19177 0.16256) (xy -0.19812 0.15367)
						(xy -0.20828 0.13335) (xy -0.21971 0.10287) (xy -0.22225 0.09271) (xy -0.22479 0.08128) (xy -0.22606 0.07112)
						(xy -0.2286 0.05969) (xy -0.2286 0.01651) (xy -0.22606 0.00508) (xy -0.22479 -0.00508) (xy -0.22225 -0.01651)
						(xy -0.21971 -0.02667) (xy -0.20828 -0.05715) (xy -0.19812 -0.07747) (xy -0.19177 -0.08636) (xy -0.18669 -0.09525)
						(xy -0.17907 -0.10414) (xy -0.17272 -0.11303) (xy -0.1651 -0.12065) (xy -0.1651 -0.7366) (xy -0.16256 -0.76835)
						(xy -0.1524 -0.8001) (xy -0.13716 -0.82804) (xy -0.11684 -0.85344) (xy -0.09144 -0.87376) (xy -0.0635 -0.889)
						(xy -0.03175 -0.89916) (xy 0 -0.9017) (xy 0.03175 -0.89916) (xy 0.0635 -0.889) (xy 0.09144 -0.87376)
						(xy 0.11684 -0.85344) (xy 0.13716 -0.82804) (xy 0.1524 -0.8001) (xy 0.16256 -0.76835) (xy 0.1651 -0.7366)
						(xy 0.1651 -0.11938) (xy 0.17272 -0.11176) (xy 0.19812 -0.0762) (xy 0.2032 -0.06604) (xy 0.20701 -0.05715)
						(xy 0.21209 -0.04699) (xy 0.2159 -0.03683) (xy 0.21844 -0.02667) (xy 0.22225 -0.01524) (xy 0.22352 -0.00508)
						(xy 0.22606 0.00508) (xy 0.22733 0.01651) (xy 0.22733 0.02667) (xy 0.2286 0.0381) (xy 0.22733 0.04953)
						(xy 0.22733 0.05969) (xy 0.22606 0.07112) (xy 0.22352 0.08128) (xy 0.22225 0.09144) (xy 0.21844 0.10287)
						(xy 0.2159 0.11303) (xy 0.21209 0.12319) (xy 0.20701 0.13335) (xy 0.2032 0.14224) (xy 0.19812 0.1524)
						(xy 0.17272 0.18796) (xy 0.1651 0.19558) (xy 0.1651 0.7366) (xy 0.16256 0.76835) (xy 0.1524 0.8001)
						(xy 0.13716 0.82804) (xy 0.11684 0.85344) (xy 0.09144 0.87376) (xy 0.0635 0.889) (xy 0.03175 0.89916)
					)
					(width 0)
					(fill yes)
				)
			)
		)
		(pad "37" smd custom
			(at -20.850098 4.106672 180)
			(size 0.1143 0.1143)
			(layers "F.Cu" "F.Mask" "F.Paste")
			(net "M_A_DQ20")
			(options
				(clearance outline)
				(anchor circle)
			)
			(primitives
				(gr_poly
					(pts
						(xy 0 0.9017) (xy -0.03175 0.89916) (xy -0.0635 0.889) (xy -0.09144 0.87376) (xy -0.11684 0.85344)
						(xy -0.13716 0.82804) (xy -0.1524 0.8001) (xy -0.16256 0.76835) (xy -0.1651 0.7366) (xy -0.1651 -0.13462)
						(xy -0.17272 -0.14224) (xy -0.19812 -0.1778) (xy -0.2032 -0.18796) (xy -0.20701 -0.19685) (xy -0.21209 -0.20701)
						(xy -0.2159 -0.21717) (xy -0.21844 -0.22733) (xy -0.22225 -0.23876) (xy -0.22352 -0.24892) (xy -0.22606 -0.25908)
						(xy -0.22733 -0.27051) (xy -0.22733 -0.28067) (xy -0.2286 -0.2921) (xy -0.22733 -0.30353) (xy -0.22733 -0.31369)
						(xy -0.22606 -0.32512) (xy -0.22352 -0.33528) (xy -0.22225 -0.34544) (xy -0.21844 -0.35687) (xy -0.2159 -0.36703)
						(xy -0.21209 -0.37719) (xy -0.20701 -0.38735) (xy -0.2032 -0.39624) (xy -0.19812 -0.4064) (xy -0.17272 -0.44196)
						(xy -0.1651 -0.44958) (xy -0.1651 -0.7366) (xy -0.16256 -0.76835) (xy -0.1524 -0.8001) (xy -0.13716 -0.82804)
						(xy -0.11684 -0.85344) (xy -0.09144 -0.87376) (xy -0.0635 -0.889) (xy -0.03175 -0.89916) (xy 0 -0.9017)
						(xy 0.03175 -0.89916) (xy 0.0635 -0.889) (xy 0.09144 -0.87376) (xy 0.11684 -0.85344) (xy 0.13716 -0.82804)
						(xy 0.1524 -0.8001) (xy 0.16256 -0.76835) (xy 0.1651 -0.7366) (xy 0.1651 -0.44958) (xy 0.17272 -0.44196)
						(xy 0.19812 -0.4064) (xy 0.2032 -0.39624) (xy 0.20701 -0.38735) (xy 0.21209 -0.37719) (xy 0.2159 -0.36703)
						(xy 0.21844 -0.35687) (xy 0.22225 -0.34544) (xy 0.22352 -0.33528) (xy 0.22606 -0.32512) (xy 0.22733 -0.31369)
						(xy 0.22733 -0.30353) (xy 0.2286 -0.2921) (xy 0.22733 -0.28067) (xy 0.22733 -0.27051) (xy 0.22606 -0.25908)
						(xy 0.22352 -0.24892) (xy 0.22225 -0.23876) (xy 0.21844 -0.22733) (xy 0.2159 -0.21717) (xy 0.21209 -0.20701)
						(xy 0.20701 -0.19685) (xy 0.2032 -0.18796) (xy 0.19812 -0.1778) (xy 0.17272 -0.14224) (xy 0.1651 -0.13462)
						(xy 0.1651 0.7366) (xy 0.16256 0.76835) (xy 0.1524 0.8001) (xy 0.13716 0.82804) (xy 0.11684 0.85344)
						(xy 0.09144 0.87376) (xy 0.0635 0.889) (xy 0.03175 0.89916)
					)
					(width 0)
					(fill yes)
				)
			)
		)
		(pad "38" smd custom
			(at -20.550124 -4.106672 180)
			(size 0.1143 0.1143)
			(layers "F.Cu" "F.Mask" "F.Paste")
			(net "GND")
			(options
				(clearance outline)
				(anchor circle)
			)
			(primitives
				(gr_poly
					(pts
						(xy 0 0.9017) (xy -0.03175 0.89916) (xy -0.0635 0.889) (xy -0.09144 0.87376) (xy -0.11684 0.85344)
						(xy -0.13716 0.82804) (xy -0.1524 0.8001) (xy -0.16256 0.76835) (xy -0.1651 0.7366) (xy -0.1651 0.44958)
						(xy -0.17272 0.44196) (xy -0.19812 0.4064) (xy -0.2032 0.39624) (xy -0.20701 0.38735) (xy -0.21209 0.37719)
						(xy -0.2159 0.36703) (xy -0.21844 0.35687) (xy -0.22225 0.34544) (xy -0.22352 0.33528) (xy -0.22606 0.32512)
						(xy -0.22733 0.31369) (xy -0.22733 0.30353) (xy -0.2286 0.2921) (xy -0.22733 0.28067) (xy -0.22733 0.27051)
						(xy -0.22606 0.25908) (xy -0.22352 0.24892) (xy -0.22225 0.23876) (xy -0.21844 0.22733) (xy -0.2159 0.21717)
						(xy -0.21209 0.20701) (xy -0.20701 0.19685) (xy -0.2032 0.18796) (xy -0.19812 0.1778) (xy -0.17272 0.14224)
						(xy -0.1651 0.13462) (xy -0.1651 -0.7366) (xy -0.16256 -0.76835) (xy -0.1524 -0.8001) (xy -0.13716 -0.82804)
						(xy -0.11684 -0.85344) (xy -0.09144 -0.87376) (xy -0.0635 -0.889) (xy -0.03175 -0.89916) (xy 0 -0.9017)
						(xy 0.03175 -0.89916) (xy 0.0635 -0.889) (xy 0.09144 -0.87376) (xy 0.11684 -0.85344) (xy 0.13716 -0.82804)
						(xy 0.1524 -0.8001) (xy 0.16256 -0.76835) (xy 0.1651 -0.7366) (xy 0.1651 0.13462) (xy 0.17272 0.14224)
						(xy 0.19812 0.1778) (xy 0.2032 0.18796) (xy 0.20701 0.19685) (xy 0.21209 0.20701) (xy 0.2159 0.21717)
						(xy 0.21844 0.22733) (xy 0.22225 0.23876) (xy 0.22352 0.24892) (xy 0.22606 0.25908) (xy 0.22733 0.27051)
						(xy 0.22733 0.28067) (xy 0.2286 0.2921) (xy 0.22733 0.30353) (xy 0.22733 0.31369) (xy 0.22606 0.32512)
						(xy 0.22352 0.33528) (xy 0.22225 0.34544) (xy 0.21844 0.35687) (xy 0.2159 0.36703) (xy 0.21209 0.37719)
						(xy 0.20701 0.38735) (xy 0.2032 0.39624) (xy 0.19812 0.4064) (xy 0.17272 0.44196) (xy 0.1651 0.44958)
						(xy 0.1651 0.7366) (xy 0.16256 0.76835) (xy 0.1524 0.8001) (xy 0.13716 0.82804) (xy 0.11684 0.85344)
						(xy 0.09144 0.87376) (xy 0.0635 0.889) (xy 0.03175 0.89916)
					)
					(width 0)
					(fill yes)
				)
			)
		)
		(pad "39" smd custom
			(at -20.249896 4.106672 180)
			(size 0.1143 0.1143)
			(layers "F.Cu" "F.Mask" "F.Paste")
			(net "M_A_DQ21")
			(options
				(clearance outline)
				(anchor circle)
			)
			(primitives
				(gr_poly
					(pts
						(xy 0 0.9017) (xy -0.03175 0.89916) (xy -0.0635 0.889) (xy -0.09144 0.87376) (xy -0.11684 0.85344)
						(xy -0.13716 0.82804) (xy -0.1524 0.8001) (xy -0.16256 0.76835) (xy -0.1651 0.7366) (xy -0.1651 0.11938)
						(xy -0.17272 0.11176) (xy -0.19812 0.0762) (xy -0.2032 0.06604) (xy -0.20701 0.05715) (xy -0.21209 0.04699)
						(xy -0.2159 0.03683) (xy -0.21844 0.02667) (xy -0.22225 0.01524) (xy -0.22352 0.00508) (xy -0.22606 -0.00508)
						(xy -0.22733 -0.01651) (xy -0.22733 -0.02667) (xy -0.2286 -0.0381) (xy -0.22733 -0.04953) (xy -0.22733 -0.05969)
						(xy -0.22606 -0.07112) (xy -0.22352 -0.08128) (xy -0.22225 -0.09144) (xy -0.21844 -0.10287) (xy -0.2159 -0.11303)
						(xy -0.21209 -0.12319) (xy -0.20701 -0.13335) (xy -0.2032 -0.14224) (xy -0.19812 -0.1524) (xy -0.17272 -0.18796)
						(xy -0.1651 -0.19558) (xy -0.1651 -0.7366) (xy -0.16256 -0.76835) (xy -0.1524 -0.8001) (xy -0.13716 -0.82804)
						(xy -0.11684 -0.85344) (xy -0.09144 -0.87376) (xy -0.0635 -0.889) (xy -0.03175 -0.89916) (xy 0 -0.9017)
						(xy 0.03175 -0.89916) (xy 0.0635 -0.889) (xy 0.09144 -0.87376) (xy 0.11684 -0.85344) (xy 0.13716 -0.82804)
						(xy 0.1524 -0.8001) (xy 0.16256 -0.76835) (xy 0.1651 -0.7366) (xy 0.1651 -0.19685) (xy 0.17272 -0.18923)
						(xy 0.17907 -0.18034) (xy 0.18669 -0.17145) (xy 0.19177 -0.16256) (xy 0.19812 -0.15367) (xy 0.20828 -0.13335)
						(xy 0.21971 -0.10287) (xy 0.22225 -0.09271) (xy 0.22479 -0.08128) (xy 0.22606 -0.07112) (xy 0.2286 -0.05969)
						(xy 0.2286 -0.01651) (xy 0.22606 -0.00508) (xy 0.22479 0.00508) (xy 0.22225 0.01651) (xy 0.21971 0.02667)
						(xy 0.20828 0.05715) (xy 0.19812 0.07747) (xy 0.19177 0.08636) (xy 0.18669 0.09525) (xy 0.17907 0.10414)
						(xy 0.17272 0.11303) (xy 0.1651 0.12065) (xy 0.1651 0.7366) (xy 0.16256 0.76835) (xy 0.1524 0.8001)
						(xy 0.13716 0.82804) (xy 0.11684 0.85344) (xy 0.09144 0.87376) (xy 0.0635 0.889) (xy 0.03175 0.89916)
					)
					(width 0)
					(fill yes)
				)
			)
		)
		(pad "40" smd custom
			(at -19.949922 -4.106672 180)
			(size 0.1143 0.1143)
			(layers "F.Cu" "F.Mask" "F.Paste")
			(net "M_A_DQ16")
			(options
				(clearance outline)
				(anchor circle)
			)
			(primitives
				(gr_poly
					(pts
						(xy 0 0.9017) (xy -0.03175 0.89916) (xy -0.0635 0.889) (xy -0.09144 0.87376) (xy -0.11684 0.85344)
						(xy -0.13716 0.82804) (xy -0.1524 0.8001) (xy -0.16256 0.76835) (xy -0.1651 0.7366) (xy -0.1651 0.19685)
						(xy -0.17272 0.18923) (xy -0.17907 0.18034) (xy -0.18669 0.17145) (xy -0.19177 0.16256) (xy -0.19812 0.15367)
						(xy -0.20828 0.13335) (xy -0.21971 0.10287) (xy -0.22225 0.09271) (xy -0.22479 0.08128) (xy -0.22606 0.07112)
						(xy -0.2286 0.05969) (xy -0.2286 0.01651) (xy -0.22606 0.00508) (xy -0.22479 -0.00508) (xy -0.22225 -0.01651)
						(xy -0.21971 -0.02667) (xy -0.20828 -0.05715) (xy -0.19812 -0.07747) (xy -0.19177 -0.08636) (xy -0.18669 -0.09525)
						(xy -0.17907 -0.10414) (xy -0.17272 -0.11303) (xy -0.1651 -0.12065) (xy -0.1651 -0.7366) (xy -0.16256 -0.76835)
						(xy -0.1524 -0.8001) (xy -0.13716 -0.82804) (xy -0.11684 -0.85344) (xy -0.09144 -0.87376) (xy -0.0635 -0.889)
						(xy -0.03175 -0.89916) (xy 0 -0.9017) (xy 0.03175 -0.89916) (xy 0.0635 -0.889) (xy 0.09144 -0.87376)
						(xy 0.11684 -0.85344) (xy 0.13716 -0.82804) (xy 0.1524 -0.8001) (xy 0.16256 -0.76835) (xy 0.1651 -0.7366)
						(xy 0.1651 -0.11938) (xy 0.17272 -0.11176) (xy 0.19812 -0.0762) (xy 0.2032 -0.06604) (xy 0.20701 -0.05715)
						(xy 0.21209 -0.04699) (xy 0.2159 -0.03683) (xy 0.21844 -0.02667) (xy 0.22225 -0.01524) (xy 0.22352 -0.00508)
						(xy 0.22606 0.00508) (xy 0.22733 0.01651) (xy 0.22733 0.02667) (xy 0.2286 0.0381) (xy 0.22733 0.04953)
						(xy 0.22733 0.05969) (xy 0.22606 0.07112) (xy 0.22352 0.08128) (xy 0.22225 0.09144) (xy 0.21844 0.10287)
						(xy 0.2159 0.11303) (xy 0.21209 0.12319) (xy 0.20701 0.13335) (xy 0.2032 0.14224) (xy 0.19812 0.1524)
						(xy 0.17272 0.18796) (xy 0.1651 0.19558) (xy 0.1651 0.7366) (xy 0.16256 0.76835) (xy 0.1524 0.8001)
						(xy 0.13716 0.82804) (xy 0.11684 0.85344) (xy 0.09144 0.87376) (xy 0.0635 0.889) (xy 0.03175 0.89916)
					)
					(width 0)
					(fill yes)
				)
			)
		)
		(pad "41" smd custom
			(at -19.649948 4.106672 180)
			(size 0.1143 0.1143)
			(layers "F.Cu" "F.Mask" "F.Paste")
			(net "GND")
			(options
				(clearance outline)
				(anchor circle)
			)
			(primitives
				(gr_poly
					(pts
						(xy 0 0.9017) (xy -0.03175 0.89916) (xy -0.0635 0.889) (xy -0.09144 0.87376) (xy -0.11684 0.85344)
						(xy -0.13716 0.82804) (xy -0.1524 0.8001) (xy -0.16256 0.76835) (xy -0.1651 0.7366) (xy -0.1651 -0.13462)
						(xy -0.17272 -0.14224) (xy -0.19812 -0.1778) (xy -0.2032 -0.18796) (xy -0.20701 -0.19685) (xy -0.21209 -0.20701)
						(xy -0.2159 -0.21717) (xy -0.21844 -0.22733) (xy -0.22225 -0.23876) (xy -0.22352 -0.24892) (xy -0.22606 -0.25908)
						(xy -0.22733 -0.27051) (xy -0.22733 -0.28067) (xy -0.2286 -0.2921) (xy -0.22733 -0.30353) (xy -0.22733 -0.31369)
						(xy -0.22606 -0.32512) (xy -0.22352 -0.33528) (xy -0.22225 -0.34544) (xy -0.21844 -0.35687) (xy -0.2159 -0.36703)
						(xy -0.21209 -0.37719) (xy -0.20701 -0.38735) (xy -0.2032 -0.39624) (xy -0.19812 -0.4064) (xy -0.17272 -0.44196)
						(xy -0.1651 -0.44958) (xy -0.1651 -0.7366) (xy -0.16256 -0.76835) (xy -0.1524 -0.8001) (xy -0.13716 -0.82804)
						(xy -0.11684 -0.85344) (xy -0.09144 -0.87376) (xy -0.0635 -0.889) (xy -0.03175 -0.89916) (xy 0 -0.9017)
						(xy 0.03175 -0.89916) (xy 0.0635 -0.889) (xy 0.09144 -0.87376) (xy 0.11684 -0.85344) (xy 0.13716 -0.82804)
						(xy 0.1524 -0.8001) (xy 0.16256 -0.76835) (xy 0.1651 -0.7366) (xy 0.1651 -0.44958) (xy 0.17272 -0.44196)
						(xy 0.19812 -0.4064) (xy 0.2032 -0.39624) (xy 0.20701 -0.38735) (xy 0.21209 -0.37719) (xy 0.2159 -0.36703)
						(xy 0.21844 -0.35687) (xy 0.22225 -0.34544) (xy 0.22352 -0.33528) (xy 0.22606 -0.32512) (xy 0.22733 -0.31369)
						(xy 0.22733 -0.30353) (xy 0.2286 -0.2921) (xy 0.22733 -0.28067) (xy 0.22733 -0.27051) (xy 0.22606 -0.25908)
						(xy 0.22352 -0.24892) (xy 0.22225 -0.23876) (xy 0.21844 -0.22733) (xy 0.2159 -0.21717) (xy 0.21209 -0.20701)
						(xy 0.20701 -0.19685) (xy 0.2032 -0.18796) (xy 0.19812 -0.1778) (xy 0.17272 -0.14224) (xy 0.1651 -0.13462)
						(xy 0.1651 0.7366) (xy 0.16256 0.76835) (xy 0.1524 0.8001) (xy 0.13716 0.82804) (xy 0.11684 0.85344)
						(xy 0.09144 0.87376) (xy 0.0635 0.889) (xy 0.03175 0.89916)
					)
					(width 0)
					(fill yes)
				)
			)
		)
		(pad "42" smd custom
			(at -19.349974 -4.106672 180)
			(size 0.1143 0.1143)
			(layers "F.Cu" "F.Mask" "F.Paste")
			(net "M_A_DQ17")
			(options
				(clearance outline)
				(anchor circle)
			)
			(primitives
				(gr_poly
					(pts
						(xy 0 0.9017) (xy -0.03175 0.89916) (xy -0.0635 0.889) (xy -0.09144 0.87376) (xy -0.11684 0.85344)
						(xy -0.13716 0.82804) (xy -0.1524 0.8001) (xy -0.16256 0.76835) (xy -0.1651 0.7366) (xy -0.1651 0.44958)
						(xy -0.17272 0.44196) (xy -0.19812 0.4064) (xy -0.2032 0.39624) (xy -0.20701 0.38735) (xy -0.21209 0.37719)
						(xy -0.2159 0.36703) (xy -0.21844 0.35687) (xy -0.22225 0.34544) (xy -0.22352 0.33528) (xy -0.22606 0.32512)
						(xy -0.22733 0.31369) (xy -0.22733 0.30353) (xy -0.2286 0.2921) (xy -0.22733 0.28067) (xy -0.22733 0.27051)
						(xy -0.22606 0.25908) (xy -0.22352 0.24892) (xy -0.22225 0.23876) (xy -0.21844 0.22733) (xy -0.2159 0.21717)
						(xy -0.21209 0.20701) (xy -0.20701 0.19685) (xy -0.2032 0.18796) (xy -0.19812 0.1778) (xy -0.17272 0.14224)
						(xy -0.1651 0.13462) (xy -0.1651 -0.7366) (xy -0.16256 -0.76835) (xy -0.1524 -0.8001) (xy -0.13716 -0.82804)
						(xy -0.11684 -0.85344) (xy -0.09144 -0.87376) (xy -0.0635 -0.889) (xy -0.03175 -0.89916) (xy 0 -0.9017)
						(xy 0.03175 -0.89916) (xy 0.0635 -0.889) (xy 0.09144 -0.87376) (xy 0.11684 -0.85344) (xy 0.13716 -0.82804)
						(xy 0.1524 -0.8001) (xy 0.16256 -0.76835) (xy 0.1651 -0.7366) (xy 0.1651 0.13462) (xy 0.17272 0.14224)
						(xy 0.19812 0.1778) (xy 0.2032 0.18796) (xy 0.20701 0.19685) (xy 0.21209 0.20701) (xy 0.2159 0.21717)
						(xy 0.21844 0.22733) (xy 0.22225 0.23876) (xy 0.22352 0.24892) (xy 0.22606 0.25908) (xy 0.22733 0.27051)
						(xy 0.22733 0.28067) (xy 0.2286 0.2921) (xy 0.22733 0.30353) (xy 0.22733 0.31369) (xy 0.22606 0.32512)
						(xy 0.22352 0.33528) (xy 0.22225 0.34544) (xy 0.21844 0.35687) (xy 0.2159 0.36703) (xy 0.21209 0.37719)
						(xy 0.20701 0.38735) (xy 0.2032 0.39624) (xy 0.19812 0.4064) (xy 0.17272 0.44196) (xy 0.1651 0.44958)
						(xy 0.1651 0.7366) (xy 0.16256 0.76835) (xy 0.1524 0.8001) (xy 0.13716 0.82804) (xy 0.11684 0.85344)
						(xy 0.09144 0.87376) (xy 0.0635 0.889) (xy 0.03175 0.89916)
					)
					(width 0)
					(fill yes)
				)
			)
		)
		(pad "43" smd custom
			(at -19.05 4.106672 180)
			(size 0.1143 0.1143)
			(layers "F.Cu" "F.Mask" "F.Paste")
			(net "M_A_DQS_DN2")
			(options
				(clearance outline)
				(anchor circle)
			)
			(primitives
				(gr_poly
					(pts
						(xy 0 0.9017) (xy -0.03175 0.89916) (xy -0.0635 0.889) (xy -0.09144 0.87376) (xy -0.11684 0.85344)
						(xy -0.13716 0.82804) (xy -0.1524 0.8001) (xy -0.16256 0.76835) (xy -0.1651 0.7366) (xy -0.1651 0.11938)
						(xy -0.17272 0.11176) (xy -0.19812 0.0762) (xy -0.2032 0.06604) (xy -0.20701 0.05715) (xy -0.21209 0.04699)
						(xy -0.2159 0.03683) (xy -0.21844 0.02667) (xy -0.22225 0.01524) (xy -0.22352 0.00508) (xy -0.22606 -0.00508)
						(xy -0.22733 -0.01651) (xy -0.22733 -0.02667) (xy -0.2286 -0.0381) (xy -0.22733 -0.04953) (xy -0.22733 -0.05969)
						(xy -0.22606 -0.07112) (xy -0.22352 -0.08128) (xy -0.22225 -0.09144) (xy -0.21844 -0.10287) (xy -0.2159 -0.11303)
						(xy -0.21209 -0.12319) (xy -0.20701 -0.13335) (xy -0.2032 -0.14224) (xy -0.19812 -0.1524) (xy -0.17272 -0.18796)
						(xy -0.1651 -0.19558) (xy -0.1651 -0.7366) (xy -0.16256 -0.76835) (xy -0.1524 -0.8001) (xy -0.13716 -0.82804)
						(xy -0.11684 -0.85344) (xy -0.09144 -0.87376) (xy -0.0635 -0.889) (xy -0.03175 -0.89916) (xy 0 -0.9017)
						(xy 0.03175 -0.89916) (xy 0.0635 -0.889) (xy 0.09144 -0.87376) (xy 0.11684 -0.85344) (xy 0.13716 -0.82804)
						(xy 0.1524 -0.8001) (xy 0.16256 -0.76835) (xy 0.1651 -0.7366) (xy 0.1651 -0.19685) (xy 0.17272 -0.18923)
						(xy 0.17907 -0.18034) (xy 0.18669 -0.17145) (xy 0.19177 -0.16256) (xy 0.19812 -0.15367) (xy 0.20828 -0.13335)
						(xy 0.21971 -0.10287) (xy 0.22225 -0.09271) (xy 0.22479 -0.08128) (xy 0.22606 -0.07112) (xy 0.2286 -0.05969)
						(xy 0.2286 -0.01651) (xy 0.22606 -0.00508) (xy 0.22479 0.00508) (xy 0.22225 0.01651) (xy 0.21971 0.02667)
						(xy 0.20828 0.05715) (xy 0.19812 0.07747) (xy 0.19177 0.08636) (xy 0.18669 0.09525) (xy 0.17907 0.10414)
						(xy 0.17272 0.11303) (xy 0.1651 0.12065) (xy 0.1651 0.7366) (xy 0.16256 0.76835) (xy 0.1524 0.8001)
						(xy 0.13716 0.82804) (xy 0.11684 0.85344) (xy 0.09144 0.87376) (xy 0.0635 0.889) (xy 0.03175 0.89916)
					)
					(width 0)
					(fill yes)
				)
			)
		)
		(pad "44" smd custom
			(at -18.750026 -4.106672 180)
			(size 0.1143 0.1143)
			(layers "F.Cu" "F.Mask" "F.Paste")
			(net "GND")
			(options
				(clearance outline)
				(anchor circle)
			)
			(primitives
				(gr_poly
					(pts
						(xy 0 0.9017) (xy -0.03175 0.89916) (xy -0.0635 0.889) (xy -0.09144 0.87376) (xy -0.11684 0.85344)
						(xy -0.13716 0.82804) (xy -0.1524 0.8001) (xy -0.16256 0.76835) (xy -0.1651 0.7366) (xy -0.1651 0.19685)
						(xy -0.17272 0.18923) (xy -0.17907 0.18034) (xy -0.18669 0.17145) (xy -0.19177 0.16256) (xy -0.19812 0.15367)
						(xy -0.20828 0.13335) (xy -0.21971 0.10287) (xy -0.22225 0.09271) (xy -0.22479 0.08128) (xy -0.22606 0.07112)
						(xy -0.2286 0.05969) (xy -0.2286 0.01651) (xy -0.22606 0.00508) (xy -0.22479 -0.00508) (xy -0.22225 -0.01651)
						(xy -0.21971 -0.02667) (xy -0.20828 -0.05715) (xy -0.19812 -0.07747) (xy -0.19177 -0.08636) (xy -0.18669 -0.09525)
						(xy -0.17907 -0.10414) (xy -0.17272 -0.11303) (xy -0.1651 -0.12065) (xy -0.1651 -0.7366) (xy -0.16256 -0.76835)
						(xy -0.1524 -0.8001) (xy -0.13716 -0.82804) (xy -0.11684 -0.85344) (xy -0.09144 -0.87376) (xy -0.0635 -0.889)
						(xy -0.03175 -0.89916) (xy 0 -0.9017) (xy 0.03175 -0.89916) (xy 0.0635 -0.889) (xy 0.09144 -0.87376)
						(xy 0.11684 -0.85344) (xy 0.13716 -0.82804) (xy 0.1524 -0.8001) (xy 0.16256 -0.76835) (xy 0.1651 -0.7366)
						(xy 0.1651 -0.11938) (xy 0.17272 -0.11176) (xy 0.19812 -0.0762) (xy 0.2032 -0.06604) (xy 0.20701 -0.05715)
						(xy 0.21209 -0.04699) (xy 0.2159 -0.03683) (xy 0.21844 -0.02667) (xy 0.22225 -0.01524) (xy 0.22352 -0.00508)
						(xy 0.22606 0.00508) (xy 0.22733 0.01651) (xy 0.22733 0.02667) (xy 0.2286 0.0381) (xy 0.22733 0.04953)
						(xy 0.22733 0.05969) (xy 0.22606 0.07112) (xy 0.22352 0.08128) (xy 0.22225 0.09144) (xy 0.21844 0.10287)
						(xy 0.2159 0.11303) (xy 0.21209 0.12319) (xy 0.20701 0.13335) (xy 0.2032 0.14224) (xy 0.19812 0.1524)
						(xy 0.17272 0.18796) (xy 0.1651 0.19558) (xy 0.1651 0.7366) (xy 0.16256 0.76835) (xy 0.1524 0.8001)
						(xy 0.13716 0.82804) (xy 0.11684 0.85344) (xy 0.09144 0.87376) (xy 0.0635 0.889) (xy 0.03175 0.89916)
					)
					(width 0)
					(fill yes)
				)
			)
		)
		(pad "45" smd custom
			(at -18.450052 4.106672 180)
			(size 0.1143 0.1143)
			(layers "F.Cu" "F.Mask" "F.Paste")
			(net "M_A_DQS_DP2")
			(options
				(clearance outline)
				(anchor circle)
			)
			(primitives
				(gr_poly
					(pts
						(xy 0 0.9017) (xy -0.03175 0.89916) (xy -0.0635 0.889) (xy -0.09144 0.87376) (xy -0.11684 0.85344)
						(xy -0.13716 0.82804) (xy -0.1524 0.8001) (xy -0.16256 0.76835) (xy -0.1651 0.7366) (xy -0.1651 -0.13462)
						(xy -0.17272 -0.14224) (xy -0.19812 -0.1778) (xy -0.2032 -0.18796) (xy -0.20701 -0.19685) (xy -0.21209 -0.20701)
						(xy -0.2159 -0.21717) (xy -0.21844 -0.22733) (xy -0.22225 -0.23876) (xy -0.22352 -0.24892) (xy -0.22606 -0.25908)
						(xy -0.22733 -0.27051) (xy -0.22733 -0.28067) (xy -0.2286 -0.2921) (xy -0.22733 -0.30353) (xy -0.22733 -0.31369)
						(xy -0.22606 -0.32512) (xy -0.22352 -0.33528) (xy -0.22225 -0.34544) (xy -0.21844 -0.35687) (xy -0.2159 -0.36703)
						(xy -0.21209 -0.37719) (xy -0.20701 -0.38735) (xy -0.2032 -0.39624) (xy -0.19812 -0.4064) (xy -0.17272 -0.44196)
						(xy -0.1651 -0.44958) (xy -0.1651 -0.7366) (xy -0.16256 -0.76835) (xy -0.1524 -0.8001) (xy -0.13716 -0.82804)
						(xy -0.11684 -0.85344) (xy -0.09144 -0.87376) (xy -0.0635 -0.889) (xy -0.03175 -0.89916) (xy 0 -0.9017)
						(xy 0.03175 -0.89916) (xy 0.0635 -0.889) (xy 0.09144 -0.87376) (xy 0.11684 -0.85344) (xy 0.13716 -0.82804)
						(xy 0.1524 -0.8001) (xy 0.16256 -0.76835) (xy 0.1651 -0.7366) (xy 0.1651 -0.44958) (xy 0.17272 -0.44196)
						(xy 0.19812 -0.4064) (xy 0.2032 -0.39624) (xy 0.20701 -0.38735) (xy 0.21209 -0.37719) (xy 0.2159 -0.36703)
						(xy 0.21844 -0.35687) (xy 0.22225 -0.34544) (xy 0.22352 -0.33528) (xy 0.22606 -0.32512) (xy 0.22733 -0.31369)
						(xy 0.22733 -0.30353) (xy 0.2286 -0.2921) (xy 0.22733 -0.28067) (xy 0.22733 -0.27051) (xy 0.22606 -0.25908)
						(xy 0.22352 -0.24892) (xy 0.22225 -0.23876) (xy 0.21844 -0.22733) (xy 0.2159 -0.21717) (xy 0.21209 -0.20701)
						(xy 0.20701 -0.19685) (xy 0.2032 -0.18796) (xy 0.19812 -0.1778) (xy 0.17272 -0.14224) (xy 0.1651 -0.13462)
						(xy 0.1651 0.7366) (xy 0.16256 0.76835) (xy 0.1524 0.8001) (xy 0.13716 0.82804) (xy 0.11684 0.85344)
						(xy 0.09144 0.87376) (xy 0.0635 0.889) (xy 0.03175 0.89916)
					)
					(width 0)
					(fill yes)
				)
			)
		)
		(pad "46" smd custom
			(at -18.150078 -4.106672 180)
			(size 0.1143 0.1143)
			(layers "F.Cu" "F.Mask" "F.Paste")
			(net "GND")
			(options
				(clearance outline)
				(anchor circle)
			)
			(primitives
				(gr_poly
					(pts
						(xy 0 0.9017) (xy -0.03175 0.89916) (xy -0.0635 0.889) (xy -0.09144 0.87376) (xy -0.11684 0.85344)
						(xy -0.13716 0.82804) (xy -0.1524 0.8001) (xy -0.16256 0.76835) (xy -0.1651 0.7366) (xy -0.1651 0.44958)
						(xy -0.17272 0.44196) (xy -0.19812 0.4064) (xy -0.2032 0.39624) (xy -0.20701 0.38735) (xy -0.21209 0.37719)
						(xy -0.2159 0.36703) (xy -0.21844 0.35687) (xy -0.22225 0.34544) (xy -0.22352 0.33528) (xy -0.22606 0.32512)
						(xy -0.22733 0.31369) (xy -0.22733 0.30353) (xy -0.2286 0.2921) (xy -0.22733 0.28067) (xy -0.22733 0.27051)
						(xy -0.22606 0.25908) (xy -0.22352 0.24892) (xy -0.22225 0.23876) (xy -0.21844 0.22733) (xy -0.2159 0.21717)
						(xy -0.21209 0.20701) (xy -0.20701 0.19685) (xy -0.2032 0.18796) (xy -0.19812 0.1778) (xy -0.17272 0.14224)
						(xy -0.1651 0.13462) (xy -0.1651 -0.7366) (xy -0.16256 -0.76835) (xy -0.1524 -0.8001) (xy -0.13716 -0.82804)
						(xy -0.11684 -0.85344) (xy -0.09144 -0.87376) (xy -0.0635 -0.889) (xy -0.03175 -0.89916) (xy 0 -0.9017)
						(xy 0.03175 -0.89916) (xy 0.0635 -0.889) (xy 0.09144 -0.87376) (xy 0.11684 -0.85344) (xy 0.13716 -0.82804)
						(xy 0.1524 -0.8001) (xy 0.16256 -0.76835) (xy 0.1651 -0.7366) (xy 0.1651 0.13462) (xy 0.17272 0.14224)
						(xy 0.19812 0.1778) (xy 0.2032 0.18796) (xy 0.20701 0.19685) (xy 0.21209 0.20701) (xy 0.2159 0.21717)
						(xy 0.21844 0.22733) (xy 0.22225 0.23876) (xy 0.22352 0.24892) (xy 0.22606 0.25908) (xy 0.22733 0.27051)
						(xy 0.22733 0.28067) (xy 0.2286 0.2921) (xy 0.22733 0.30353) (xy 0.22733 0.31369) (xy 0.22606 0.32512)
						(xy 0.22352 0.33528) (xy 0.22225 0.34544) (xy 0.21844 0.35687) (xy 0.2159 0.36703) (xy 0.21209 0.37719)
						(xy 0.20701 0.38735) (xy 0.2032 0.39624) (xy 0.19812 0.4064) (xy 0.17272 0.44196) (xy 0.1651 0.44958)
						(xy 0.1651 0.7366) (xy 0.16256 0.76835) (xy 0.1524 0.8001) (xy 0.13716 0.82804) (xy 0.11684 0.85344)
						(xy 0.09144 0.87376) (xy 0.0635 0.889) (xy 0.03175 0.89916)
					)
					(width 0)
					(fill yes)
				)
			)
		)
		(pad "47" smd custom
			(at -17.850104 4.106672 180)
			(size 0.1143 0.1143)
			(layers "F.Cu" "F.Mask" "F.Paste")
			(net "GND")
			(options
				(clearance outline)
				(anchor circle)
			)
			(primitives
				(gr_poly
					(pts
						(xy 0 0.9017) (xy -0.03175 0.89916) (xy -0.0635 0.889) (xy -0.09144 0.87376) (xy -0.11684 0.85344)
						(xy -0.13716 0.82804) (xy -0.1524 0.8001) (xy -0.16256 0.76835) (xy -0.1651 0.7366) (xy -0.1651 0.11938)
						(xy -0.17272 0.11176) (xy -0.19812 0.0762) (xy -0.2032 0.06604) (xy -0.20701 0.05715) (xy -0.21209 0.04699)
						(xy -0.2159 0.03683) (xy -0.21844 0.02667) (xy -0.22225 0.01524) (xy -0.22352 0.00508) (xy -0.22606 -0.00508)
						(xy -0.22733 -0.01651) (xy -0.22733 -0.02667) (xy -0.2286 -0.0381) (xy -0.22733 -0.04953) (xy -0.22733 -0.05969)
						(xy -0.22606 -0.07112) (xy -0.22352 -0.08128) (xy -0.22225 -0.09144) (xy -0.21844 -0.10287) (xy -0.2159 -0.11303)
						(xy -0.21209 -0.12319) (xy -0.20701 -0.13335) (xy -0.2032 -0.14224) (xy -0.19812 -0.1524) (xy -0.17272 -0.18796)
						(xy -0.1651 -0.19558) (xy -0.1651 -0.7366) (xy -0.16256 -0.76835) (xy -0.1524 -0.8001) (xy -0.13716 -0.82804)
						(xy -0.11684 -0.85344) (xy -0.09144 -0.87376) (xy -0.0635 -0.889) (xy -0.03175 -0.89916) (xy 0 -0.9017)
						(xy 0.03175 -0.89916) (xy 0.0635 -0.889) (xy 0.09144 -0.87376) (xy 0.11684 -0.85344) (xy 0.13716 -0.82804)
						(xy 0.1524 -0.8001) (xy 0.16256 -0.76835) (xy 0.1651 -0.7366) (xy 0.1651 -0.19685) (xy 0.17272 -0.18923)
						(xy 0.17907 -0.18034) (xy 0.18669 -0.17145) (xy 0.19177 -0.16256) (xy 0.19812 -0.15367) (xy 0.20828 -0.13335)
						(xy 0.21971 -0.10287) (xy 0.22225 -0.09271) (xy 0.22479 -0.08128) (xy 0.22606 -0.07112) (xy 0.2286 -0.05969)
						(xy 0.2286 -0.01651) (xy 0.22606 -0.00508) (xy 0.22479 0.00508) (xy 0.22225 0.01651) (xy 0.21971 0.02667)
						(xy 0.20828 0.05715) (xy 0.19812 0.07747) (xy 0.19177 0.08636) (xy 0.18669 0.09525) (xy 0.17907 0.10414)
						(xy 0.17272 0.11303) (xy 0.1651 0.12065) (xy 0.1651 0.7366) (xy 0.16256 0.76835) (xy 0.1524 0.8001)
						(xy 0.13716 0.82804) (xy 0.11684 0.85344) (xy 0.09144 0.87376) (xy 0.0635 0.889) (xy 0.03175 0.89916)
					)
					(width 0)
					(fill yes)
				)
			)
		)
		(pad "48" smd custom
			(at -17.549876 -4.106672 180)
			(size 0.1143 0.1143)
			(layers "F.Cu" "F.Mask" "F.Paste")
			(net "M_A_DQ18")
			(options
				(clearance outline)
				(anchor circle)
			)
			(primitives
				(gr_poly
					(pts
						(xy 0 0.9017) (xy -0.03175 0.89916) (xy -0.0635 0.889) (xy -0.09144 0.87376) (xy -0.11684 0.85344)
						(xy -0.13716 0.82804) (xy -0.1524 0.8001) (xy -0.16256 0.76835) (xy -0.1651 0.7366) (xy -0.1651 0.19685)
						(xy -0.17272 0.18923) (xy -0.17907 0.18034) (xy -0.18669 0.17145) (xy -0.19177 0.16256) (xy -0.19812 0.15367)
						(xy -0.20828 0.13335) (xy -0.21971 0.10287) (xy -0.22225 0.09271) (xy -0.22479 0.08128) (xy -0.22606 0.07112)
						(xy -0.2286 0.05969) (xy -0.2286 0.01651) (xy -0.22606 0.00508) (xy -0.22479 -0.00508) (xy -0.22225 -0.01651)
						(xy -0.21971 -0.02667) (xy -0.20828 -0.05715) (xy -0.19812 -0.07747) (xy -0.19177 -0.08636) (xy -0.18669 -0.09525)
						(xy -0.17907 -0.10414) (xy -0.17272 -0.11303) (xy -0.1651 -0.12065) (xy -0.1651 -0.7366) (xy -0.16256 -0.76835)
						(xy -0.1524 -0.8001) (xy -0.13716 -0.82804) (xy -0.11684 -0.85344) (xy -0.09144 -0.87376) (xy -0.0635 -0.889)
						(xy -0.03175 -0.89916) (xy 0 -0.9017) (xy 0.03175 -0.89916) (xy 0.0635 -0.889) (xy 0.09144 -0.87376)
						(xy 0.11684 -0.85344) (xy 0.13716 -0.82804) (xy 0.1524 -0.8001) (xy 0.16256 -0.76835) (xy 0.1651 -0.7366)
						(xy 0.1651 -0.11938) (xy 0.17272 -0.11176) (xy 0.19812 -0.0762) (xy 0.2032 -0.06604) (xy 0.20701 -0.05715)
						(xy 0.21209 -0.04699) (xy 0.2159 -0.03683) (xy 0.21844 -0.02667) (xy 0.22225 -0.01524) (xy 0.22352 -0.00508)
						(xy 0.22606 0.00508) (xy 0.22733 0.01651) (xy 0.22733 0.02667) (xy 0.2286 0.0381) (xy 0.22733 0.04953)
						(xy 0.22733 0.05969) (xy 0.22606 0.07112) (xy 0.22352 0.08128) (xy 0.22225 0.09144) (xy 0.21844 0.10287)
						(xy 0.2159 0.11303) (xy 0.21209 0.12319) (xy 0.20701 0.13335) (xy 0.2032 0.14224) (xy 0.19812 0.1524)
						(xy 0.17272 0.18796) (xy 0.1651 0.19558) (xy 0.1651 0.7366) (xy 0.16256 0.76835) (xy 0.1524 0.8001)
						(xy 0.13716 0.82804) (xy 0.11684 0.85344) (xy 0.09144 0.87376) (xy 0.0635 0.889) (xy 0.03175 0.89916)
					)
					(width 0)
					(fill yes)
				)
			)
		)
		(pad "49" smd custom
			(at -17.249902 4.106672 180)
			(size 0.1143 0.1143)
			(layers "F.Cu" "F.Mask" "F.Paste")
			(net "M_A_DQ22")
			(options
				(clearance outline)
				(anchor circle)
			)
			(primitives
				(gr_poly
					(pts
						(xy 0 0.9017) (xy -0.03175 0.89916) (xy -0.0635 0.889) (xy -0.09144 0.87376) (xy -0.11684 0.85344)
						(xy -0.13716 0.82804) (xy -0.1524 0.8001) (xy -0.16256 0.76835) (xy -0.1651 0.7366) (xy -0.1651 -0.13462)
						(xy -0.17272 -0.14224) (xy -0.19812 -0.1778) (xy -0.2032 -0.18796) (xy -0.20701 -0.19685) (xy -0.21209 -0.20701)
						(xy -0.2159 -0.21717) (xy -0.21844 -0.22733) (xy -0.22225 -0.23876) (xy -0.22352 -0.24892) (xy -0.22606 -0.25908)
						(xy -0.22733 -0.27051) (xy -0.22733 -0.28067) (xy -0.2286 -0.2921) (xy -0.22733 -0.30353) (xy -0.22733 -0.31369)
						(xy -0.22606 -0.32512) (xy -0.22352 -0.33528) (xy -0.22225 -0.34544) (xy -0.21844 -0.35687) (xy -0.2159 -0.36703)
						(xy -0.21209 -0.37719) (xy -0.20701 -0.38735) (xy -0.2032 -0.39624) (xy -0.19812 -0.4064) (xy -0.17272 -0.44196)
						(xy -0.1651 -0.44958) (xy -0.1651 -0.7366) (xy -0.16256 -0.76835) (xy -0.1524 -0.8001) (xy -0.13716 -0.82804)
						(xy -0.11684 -0.85344) (xy -0.09144 -0.87376) (xy -0.0635 -0.889) (xy -0.03175 -0.89916) (xy 0 -0.9017)
						(xy 0.03175 -0.89916) (xy 0.0635 -0.889) (xy 0.09144 -0.87376) (xy 0.11684 -0.85344) (xy 0.13716 -0.82804)
						(xy 0.1524 -0.8001) (xy 0.16256 -0.76835) (xy 0.1651 -0.7366) (xy 0.1651 -0.44958) (xy 0.17272 -0.44196)
						(xy 0.19812 -0.4064) (xy 0.2032 -0.39624) (xy 0.20701 -0.38735) (xy 0.21209 -0.37719) (xy 0.2159 -0.36703)
						(xy 0.21844 -0.35687) (xy 0.22225 -0.34544) (xy 0.22352 -0.33528) (xy 0.22606 -0.32512) (xy 0.22733 -0.31369)
						(xy 0.22733 -0.30353) (xy 0.2286 -0.2921) (xy 0.22733 -0.28067) (xy 0.22733 -0.27051) (xy 0.22606 -0.25908)
						(xy 0.22352 -0.24892) (xy 0.22225 -0.23876) (xy 0.21844 -0.22733) (xy 0.2159 -0.21717) (xy 0.21209 -0.20701)
						(xy 0.20701 -0.19685) (xy 0.2032 -0.18796) (xy 0.19812 -0.1778) (xy 0.17272 -0.14224) (xy 0.1651 -0.13462)
						(xy 0.1651 0.7366) (xy 0.16256 0.76835) (xy 0.1524 0.8001) (xy 0.13716 0.82804) (xy 0.11684 0.85344)
						(xy 0.09144 0.87376) (xy 0.0635 0.889) (xy 0.03175 0.89916)
					)
					(width 0)
					(fill yes)
				)
			)
		)
		(pad "50" smd custom
			(at -16.949928 -4.106672 180)
			(size 0.1143 0.1143)
			(layers "F.Cu" "F.Mask" "F.Paste")
			(net "M_A_DQ19")
			(options
				(clearance outline)
				(anchor circle)
			)
			(primitives
				(gr_poly
					(pts
						(xy 0 0.9017) (xy -0.03175 0.89916) (xy -0.0635 0.889) (xy -0.09144 0.87376) (xy -0.11684 0.85344)
						(xy -0.13716 0.82804) (xy -0.1524 0.8001) (xy -0.16256 0.76835) (xy -0.1651 0.7366) (xy -0.1651 0.44958)
						(xy -0.17272 0.44196) (xy -0.19812 0.4064) (xy -0.2032 0.39624) (xy -0.20701 0.38735) (xy -0.21209 0.37719)
						(xy -0.2159 0.36703) (xy -0.21844 0.35687) (xy -0.22225 0.34544) (xy -0.22352 0.33528) (xy -0.22606 0.32512)
						(xy -0.22733 0.31369) (xy -0.22733 0.30353) (xy -0.2286 0.2921) (xy -0.22733 0.28067) (xy -0.22733 0.27051)
						(xy -0.22606 0.25908) (xy -0.22352 0.24892) (xy -0.22225 0.23876) (xy -0.21844 0.22733) (xy -0.2159 0.21717)
						(xy -0.21209 0.20701) (xy -0.20701 0.19685) (xy -0.2032 0.18796) (xy -0.19812 0.1778) (xy -0.17272 0.14224)
						(xy -0.1651 0.13462) (xy -0.1651 -0.7366) (xy -0.16256 -0.76835) (xy -0.1524 -0.8001) (xy -0.13716 -0.82804)
						(xy -0.11684 -0.85344) (xy -0.09144 -0.87376) (xy -0.0635 -0.889) (xy -0.03175 -0.89916) (xy 0 -0.9017)
						(xy 0.03175 -0.89916) (xy 0.0635 -0.889) (xy 0.09144 -0.87376) (xy 0.11684 -0.85344) (xy 0.13716 -0.82804)
						(xy 0.1524 -0.8001) (xy 0.16256 -0.76835) (xy 0.1651 -0.7366) (xy 0.1651 0.13462) (xy 0.17272 0.14224)
						(xy 0.19812 0.1778) (xy 0.2032 0.18796) (xy 0.20701 0.19685) (xy 0.21209 0.20701) (xy 0.2159 0.21717)
						(xy 0.21844 0.22733) (xy 0.22225 0.23876) (xy 0.22352 0.24892) (xy 0.22606 0.25908) (xy 0.22733 0.27051)
						(xy 0.22733 0.28067) (xy 0.2286 0.2921) (xy 0.22733 0.30353) (xy 0.22733 0.31369) (xy 0.22606 0.32512)
						(xy 0.22352 0.33528) (xy 0.22225 0.34544) (xy 0.21844 0.35687) (xy 0.2159 0.36703) (xy 0.21209 0.37719)
						(xy 0.20701 0.38735) (xy 0.2032 0.39624) (xy 0.19812 0.4064) (xy 0.17272 0.44196) (xy 0.1651 0.44958)
						(xy 0.1651 0.7366) (xy 0.16256 0.76835) (xy 0.1524 0.8001) (xy 0.13716 0.82804) (xy 0.11684 0.85344)
						(xy 0.09144 0.87376) (xy 0.0635 0.889) (xy 0.03175 0.89916)
					)
					(width 0)
					(fill yes)
				)
			)
		)
		(pad "51" smd custom
			(at -16.649954 4.106672 180)
			(size 0.1143 0.1143)
			(layers "F.Cu" "F.Mask" "F.Paste")
			(net "M_A_DQ23")
			(options
				(clearance outline)
				(anchor circle)
			)
			(primitives
				(gr_poly
					(pts
						(xy 0 0.9017) (xy -0.03175 0.89916) (xy -0.0635 0.889) (xy -0.09144 0.87376) (xy -0.11684 0.85344)
						(xy -0.13716 0.82804) (xy -0.1524 0.8001) (xy -0.16256 0.76835) (xy -0.1651 0.7366) (xy -0.1651 0.11938)
						(xy -0.17272 0.11176) (xy -0.19812 0.0762) (xy -0.2032 0.06604) (xy -0.20701 0.05715) (xy -0.21209 0.04699)
						(xy -0.2159 0.03683) (xy -0.21844 0.02667) (xy -0.22225 0.01524) (xy -0.22352 0.00508) (xy -0.22606 -0.00508)
						(xy -0.22733 -0.01651) (xy -0.22733 -0.02667) (xy -0.2286 -0.0381) (xy -0.22733 -0.04953) (xy -0.22733 -0.05969)
						(xy -0.22606 -0.07112) (xy -0.22352 -0.08128) (xy -0.22225 -0.09144) (xy -0.21844 -0.10287) (xy -0.2159 -0.11303)
						(xy -0.21209 -0.12319) (xy -0.20701 -0.13335) (xy -0.2032 -0.14224) (xy -0.19812 -0.1524) (xy -0.17272 -0.18796)
						(xy -0.1651 -0.19558) (xy -0.1651 -0.7366) (xy -0.16256 -0.76835) (xy -0.1524 -0.8001) (xy -0.13716 -0.82804)
						(xy -0.11684 -0.85344) (xy -0.09144 -0.87376) (xy -0.0635 -0.889) (xy -0.03175 -0.89916) (xy 0 -0.9017)
						(xy 0.03175 -0.89916) (xy 0.0635 -0.889) (xy 0.09144 -0.87376) (xy 0.11684 -0.85344) (xy 0.13716 -0.82804)
						(xy 0.1524 -0.8001) (xy 0.16256 -0.76835) (xy 0.1651 -0.7366) (xy 0.1651 -0.19685) (xy 0.17272 -0.18923)
						(xy 0.17907 -0.18034) (xy 0.18669 -0.17145) (xy 0.19177 -0.16256) (xy 0.19812 -0.15367) (xy 0.20828 -0.13335)
						(xy 0.21971 -0.10287) (xy 0.22225 -0.09271) (xy 0.22479 -0.08128) (xy 0.22606 -0.07112) (xy 0.2286 -0.05969)
						(xy 0.2286 -0.01651) (xy 0.22606 -0.00508) (xy 0.22479 0.00508) (xy 0.22225 0.01651) (xy 0.21971 0.02667)
						(xy 0.20828 0.05715) (xy 0.19812 0.07747) (xy 0.19177 0.08636) (xy 0.18669 0.09525) (xy 0.17907 0.10414)
						(xy 0.17272 0.11303) (xy 0.1651 0.12065) (xy 0.1651 0.7366) (xy 0.16256 0.76835) (xy 0.1524 0.8001)
						(xy 0.13716 0.82804) (xy 0.11684 0.85344) (xy 0.09144 0.87376) (xy 0.0635 0.889) (xy 0.03175 0.89916)
					)
					(width 0)
					(fill yes)
				)
			)
		)
		(pad "52" smd custom
			(at -16.34998 -4.106672 180)
			(size 0.1143 0.1143)
			(layers "F.Cu" "F.Mask" "F.Paste")
			(net "GND")
			(options
				(clearance outline)
				(anchor circle)
			)
			(primitives
				(gr_poly
					(pts
						(xy 0 0.9017) (xy -0.03175 0.89916) (xy -0.0635 0.889) (xy -0.09144 0.87376) (xy -0.11684 0.85344)
						(xy -0.13716 0.82804) (xy -0.1524 0.8001) (xy -0.16256 0.76835) (xy -0.1651 0.7366) (xy -0.1651 0.19685)
						(xy -0.17272 0.18923) (xy -0.17907 0.18034) (xy -0.18669 0.17145) (xy -0.19177 0.16256) (xy -0.19812 0.15367)
						(xy -0.20828 0.13335) (xy -0.21971 0.10287) (xy -0.22225 0.09271) (xy -0.22479 0.08128) (xy -0.22606 0.07112)
						(xy -0.2286 0.05969) (xy -0.2286 0.01651) (xy -0.22606 0.00508) (xy -0.22479 -0.00508) (xy -0.22225 -0.01651)
						(xy -0.21971 -0.02667) (xy -0.20828 -0.05715) (xy -0.19812 -0.07747) (xy -0.19177 -0.08636) (xy -0.18669 -0.09525)
						(xy -0.17907 -0.10414) (xy -0.17272 -0.11303) (xy -0.1651 -0.12065) (xy -0.1651 -0.7366) (xy -0.16256 -0.76835)
						(xy -0.1524 -0.8001) (xy -0.13716 -0.82804) (xy -0.11684 -0.85344) (xy -0.09144 -0.87376) (xy -0.0635 -0.889)
						(xy -0.03175 -0.89916) (xy 0 -0.9017) (xy 0.03175 -0.89916) (xy 0.0635 -0.889) (xy 0.09144 -0.87376)
						(xy 0.11684 -0.85344) (xy 0.13716 -0.82804) (xy 0.1524 -0.8001) (xy 0.16256 -0.76835) (xy 0.1651 -0.7366)
						(xy 0.1651 -0.11938) (xy 0.17272 -0.11176) (xy 0.19812 -0.0762) (xy 0.2032 -0.06604) (xy 0.20701 -0.05715)
						(xy 0.21209 -0.04699) (xy 0.2159 -0.03683) (xy 0.21844 -0.02667) (xy 0.22225 -0.01524) (xy 0.22352 -0.00508)
						(xy 0.22606 0.00508) (xy 0.22733 0.01651) (xy 0.22733 0.02667) (xy 0.2286 0.0381) (xy 0.22733 0.04953)
						(xy 0.22733 0.05969) (xy 0.22606 0.07112) (xy 0.22352 0.08128) (xy 0.22225 0.09144) (xy 0.21844 0.10287)
						(xy 0.2159 0.11303) (xy 0.21209 0.12319) (xy 0.20701 0.13335) (xy 0.2032 0.14224) (xy 0.19812 0.1524)
						(xy 0.17272 0.18796) (xy 0.1651 0.19558) (xy 0.1651 0.7366) (xy 0.16256 0.76835) (xy 0.1524 0.8001)
						(xy 0.13716 0.82804) (xy 0.11684 0.85344) (xy 0.09144 0.87376) (xy 0.0635 0.889) (xy 0.03175 0.89916)
					)
					(width 0)
					(fill yes)
				)
			)
		)
		(pad "53" smd custom
			(at -16.050006 4.106672 180)
			(size 0.1143 0.1143)
			(layers "F.Cu" "F.Mask" "F.Paste")
			(net "GND")
			(options
				(clearance outline)
				(anchor circle)
			)
			(primitives
				(gr_poly
					(pts
						(xy 0 0.9017) (xy -0.03175 0.89916) (xy -0.0635 0.889) (xy -0.09144 0.87376) (xy -0.11684 0.85344)
						(xy -0.13716 0.82804) (xy -0.1524 0.8001) (xy -0.16256 0.76835) (xy -0.1651 0.7366) (xy -0.1651 -0.13462)
						(xy -0.17272 -0.14224) (xy -0.19812 -0.1778) (xy -0.2032 -0.18796) (xy -0.20701 -0.19685) (xy -0.21209 -0.20701)
						(xy -0.2159 -0.21717) (xy -0.21844 -0.22733) (xy -0.22225 -0.23876) (xy -0.22352 -0.24892) (xy -0.22606 -0.25908)
						(xy -0.22733 -0.27051) (xy -0.22733 -0.28067) (xy -0.2286 -0.2921) (xy -0.22733 -0.30353) (xy -0.22733 -0.31369)
						(xy -0.22606 -0.32512) (xy -0.22352 -0.33528) (xy -0.22225 -0.34544) (xy -0.21844 -0.35687) (xy -0.2159 -0.36703)
						(xy -0.21209 -0.37719) (xy -0.20701 -0.38735) (xy -0.2032 -0.39624) (xy -0.19812 -0.4064) (xy -0.17272 -0.44196)
						(xy -0.1651 -0.44958) (xy -0.1651 -0.7366) (xy -0.16256 -0.76835) (xy -0.1524 -0.8001) (xy -0.13716 -0.82804)
						(xy -0.11684 -0.85344) (xy -0.09144 -0.87376) (xy -0.0635 -0.889) (xy -0.03175 -0.89916) (xy 0 -0.9017)
						(xy 0.03175 -0.89916) (xy 0.0635 -0.889) (xy 0.09144 -0.87376) (xy 0.11684 -0.85344) (xy 0.13716 -0.82804)
						(xy 0.1524 -0.8001) (xy 0.16256 -0.76835) (xy 0.1651 -0.7366) (xy 0.1651 -0.44958) (xy 0.17272 -0.44196)
						(xy 0.19812 -0.4064) (xy 0.2032 -0.39624) (xy 0.20701 -0.38735) (xy 0.21209 -0.37719) (xy 0.2159 -0.36703)
						(xy 0.21844 -0.35687) (xy 0.22225 -0.34544) (xy 0.22352 -0.33528) (xy 0.22606 -0.32512) (xy 0.22733 -0.31369)
						(xy 0.22733 -0.30353) (xy 0.2286 -0.2921) (xy 0.22733 -0.28067) (xy 0.22733 -0.27051) (xy 0.22606 -0.25908)
						(xy 0.22352 -0.24892) (xy 0.22225 -0.23876) (xy 0.21844 -0.22733) (xy 0.2159 -0.21717) (xy 0.21209 -0.20701)
						(xy 0.20701 -0.19685) (xy 0.2032 -0.18796) (xy 0.19812 -0.1778) (xy 0.17272 -0.14224) (xy 0.1651 -0.13462)
						(xy 0.1651 0.7366) (xy 0.16256 0.76835) (xy 0.1524 0.8001) (xy 0.13716 0.82804) (xy 0.11684 0.85344)
						(xy 0.09144 0.87376) (xy 0.0635 0.889) (xy 0.03175 0.89916)
					)
					(width 0)
					(fill yes)
				)
			)
		)
		(pad "54" smd custom
			(at -15.750032 -4.106672 180)
			(size 0.1143 0.1143)
			(layers "F.Cu" "F.Mask" "F.Paste")
			(net "M_A_DQ24")
			(options
				(clearance outline)
				(anchor circle)
			)
			(primitives
				(gr_poly
					(pts
						(xy 0 0.9017) (xy -0.03175 0.89916) (xy -0.0635 0.889) (xy -0.09144 0.87376) (xy -0.11684 0.85344)
						(xy -0.13716 0.82804) (xy -0.1524 0.8001) (xy -0.16256 0.76835) (xy -0.1651 0.7366) (xy -0.1651 0.44958)
						(xy -0.17272 0.44196) (xy -0.19812 0.4064) (xy -0.2032 0.39624) (xy -0.20701 0.38735) (xy -0.21209 0.37719)
						(xy -0.2159 0.36703) (xy -0.21844 0.35687) (xy -0.22225 0.34544) (xy -0.22352 0.33528) (xy -0.22606 0.32512)
						(xy -0.22733 0.31369) (xy -0.22733 0.30353) (xy -0.2286 0.2921) (xy -0.22733 0.28067) (xy -0.22733 0.27051)
						(xy -0.22606 0.25908) (xy -0.22352 0.24892) (xy -0.22225 0.23876) (xy -0.21844 0.22733) (xy -0.2159 0.21717)
						(xy -0.21209 0.20701) (xy -0.20701 0.19685) (xy -0.2032 0.18796) (xy -0.19812 0.1778) (xy -0.17272 0.14224)
						(xy -0.1651 0.13462) (xy -0.1651 -0.7366) (xy -0.16256 -0.76835) (xy -0.1524 -0.8001) (xy -0.13716 -0.82804)
						(xy -0.11684 -0.85344) (xy -0.09144 -0.87376) (xy -0.0635 -0.889) (xy -0.03175 -0.89916) (xy 0 -0.9017)
						(xy 0.03175 -0.89916) (xy 0.0635 -0.889) (xy 0.09144 -0.87376) (xy 0.11684 -0.85344) (xy 0.13716 -0.82804)
						(xy 0.1524 -0.8001) (xy 0.16256 -0.76835) (xy 0.1651 -0.7366) (xy 0.1651 0.13462) (xy 0.17272 0.14224)
						(xy 0.19812 0.1778) (xy 0.2032 0.18796) (xy 0.20701 0.19685) (xy 0.21209 0.20701) (xy 0.2159 0.21717)
						(xy 0.21844 0.22733) (xy 0.22225 0.23876) (xy 0.22352 0.24892) (xy 0.22606 0.25908) (xy 0.22733 0.27051)
						(xy 0.22733 0.28067) (xy 0.2286 0.2921) (xy 0.22733 0.30353) (xy 0.22733 0.31369) (xy 0.22606 0.32512)
						(xy 0.22352 0.33528) (xy 0.22225 0.34544) (xy 0.21844 0.35687) (xy 0.2159 0.36703) (xy 0.21209 0.37719)
						(xy 0.20701 0.38735) (xy 0.2032 0.39624) (xy 0.19812 0.4064) (xy 0.17272 0.44196) (xy 0.1651 0.44958)
						(xy 0.1651 0.7366) (xy 0.16256 0.76835) (xy 0.1524 0.8001) (xy 0.13716 0.82804) (xy 0.11684 0.85344)
						(xy 0.09144 0.87376) (xy 0.0635 0.889) (xy 0.03175 0.89916)
					)
					(width 0)
					(fill yes)
				)
			)
		)
		(pad "55" smd custom
			(at -15.450058 4.106672 180)
			(size 0.1143 0.1143)
			(layers "F.Cu" "F.Mask" "F.Paste")
			(net "M_A_DQ28")
			(options
				(clearance outline)
				(anchor circle)
			)
			(primitives
				(gr_poly
					(pts
						(xy 0 0.9017) (xy -0.03175 0.89916) (xy -0.0635 0.889) (xy -0.09144 0.87376) (xy -0.11684 0.85344)
						(xy -0.13716 0.82804) (xy -0.1524 0.8001) (xy -0.16256 0.76835) (xy -0.1651 0.7366) (xy -0.1651 0.11938)
						(xy -0.17272 0.11176) (xy -0.19812 0.0762) (xy -0.2032 0.06604) (xy -0.20701 0.05715) (xy -0.21209 0.04699)
						(xy -0.2159 0.03683) (xy -0.21844 0.02667) (xy -0.22225 0.01524) (xy -0.22352 0.00508) (xy -0.22606 -0.00508)
						(xy -0.22733 -0.01651) (xy -0.22733 -0.02667) (xy -0.2286 -0.0381) (xy -0.22733 -0.04953) (xy -0.22733 -0.05969)
						(xy -0.22606 -0.07112) (xy -0.22352 -0.08128) (xy -0.22225 -0.09144) (xy -0.21844 -0.10287) (xy -0.2159 -0.11303)
						(xy -0.21209 -0.12319) (xy -0.20701 -0.13335) (xy -0.2032 -0.14224) (xy -0.19812 -0.1524) (xy -0.17272 -0.18796)
						(xy -0.1651 -0.19558) (xy -0.1651 -0.7366) (xy -0.16256 -0.76835) (xy -0.1524 -0.8001) (xy -0.13716 -0.82804)
						(xy -0.11684 -0.85344) (xy -0.09144 -0.87376) (xy -0.0635 -0.889) (xy -0.03175 -0.89916) (xy 0 -0.9017)
						(xy 0.03175 -0.89916) (xy 0.0635 -0.889) (xy 0.09144 -0.87376) (xy 0.11684 -0.85344) (xy 0.13716 -0.82804)
						(xy 0.1524 -0.8001) (xy 0.16256 -0.76835) (xy 0.1651 -0.7366) (xy 0.1651 -0.19685) (xy 0.17272 -0.18923)
						(xy 0.17907 -0.18034) (xy 0.18669 -0.17145) (xy 0.19177 -0.16256) (xy 0.19812 -0.15367) (xy 0.20828 -0.13335)
						(xy 0.21971 -0.10287) (xy 0.22225 -0.09271) (xy 0.22479 -0.08128) (xy 0.22606 -0.07112) (xy 0.2286 -0.05969)
						(xy 0.2286 -0.01651) (xy 0.22606 -0.00508) (xy 0.22479 0.00508) (xy 0.22225 0.01651) (xy 0.21971 0.02667)
						(xy 0.20828 0.05715) (xy 0.19812 0.07747) (xy 0.19177 0.08636) (xy 0.18669 0.09525) (xy 0.17907 0.10414)
						(xy 0.17272 0.11303) (xy 0.1651 0.12065) (xy 0.1651 0.7366) (xy 0.16256 0.76835) (xy 0.1524 0.8001)
						(xy 0.13716 0.82804) (xy 0.11684 0.85344) (xy 0.09144 0.87376) (xy 0.0635 0.889) (xy 0.03175 0.89916)
					)
					(width 0)
					(fill yes)
				)
			)
		)
		(pad "56" smd custom
			(at -15.150084 -4.106672 180)
			(size 0.1143 0.1143)
			(layers "F.Cu" "F.Mask" "F.Paste")
			(net "M_A_DQ25")
			(options
				(clearance outline)
				(anchor circle)
			)
			(primitives
				(gr_poly
					(pts
						(xy 0 0.9017) (xy -0.03175 0.89916) (xy -0.0635 0.889) (xy -0.09144 0.87376) (xy -0.11684 0.85344)
						(xy -0.13716 0.82804) (xy -0.1524 0.8001) (xy -0.16256 0.76835) (xy -0.1651 0.7366) (xy -0.1651 0.19685)
						(xy -0.17272 0.18923) (xy -0.17907 0.18034) (xy -0.18669 0.17145) (xy -0.19177 0.16256) (xy -0.19812 0.15367)
						(xy -0.20828 0.13335) (xy -0.21971 0.10287) (xy -0.22225 0.09271) (xy -0.22479 0.08128) (xy -0.22606 0.07112)
						(xy -0.2286 0.05969) (xy -0.2286 0.01651) (xy -0.22606 0.00508) (xy -0.22479 -0.00508) (xy -0.22225 -0.01651)
						(xy -0.21971 -0.02667) (xy -0.20828 -0.05715) (xy -0.19812 -0.07747) (xy -0.19177 -0.08636) (xy -0.18669 -0.09525)
						(xy -0.17907 -0.10414) (xy -0.17272 -0.11303) (xy -0.1651 -0.12065) (xy -0.1651 -0.7366) (xy -0.16256 -0.76835)
						(xy -0.1524 -0.8001) (xy -0.13716 -0.82804) (xy -0.11684 -0.85344) (xy -0.09144 -0.87376) (xy -0.0635 -0.889)
						(xy -0.03175 -0.89916) (xy 0 -0.9017) (xy 0.03175 -0.89916) (xy 0.0635 -0.889) (xy 0.09144 -0.87376)
						(xy 0.11684 -0.85344) (xy 0.13716 -0.82804) (xy 0.1524 -0.8001) (xy 0.16256 -0.76835) (xy 0.1651 -0.7366)
						(xy 0.1651 -0.11938) (xy 0.17272 -0.11176) (xy 0.19812 -0.0762) (xy 0.2032 -0.06604) (xy 0.20701 -0.05715)
						(xy 0.21209 -0.04699) (xy 0.2159 -0.03683) (xy 0.21844 -0.02667) (xy 0.22225 -0.01524) (xy 0.22352 -0.00508)
						(xy 0.22606 0.00508) (xy 0.22733 0.01651) (xy 0.22733 0.02667) (xy 0.2286 0.0381) (xy 0.22733 0.04953)
						(xy 0.22733 0.05969) (xy 0.22606 0.07112) (xy 0.22352 0.08128) (xy 0.22225 0.09144) (xy 0.21844 0.10287)
						(xy 0.2159 0.11303) (xy 0.21209 0.12319) (xy 0.20701 0.13335) (xy 0.2032 0.14224) (xy 0.19812 0.1524)
						(xy 0.17272 0.18796) (xy 0.1651 0.19558) (xy 0.1651 0.7366) (xy 0.16256 0.76835) (xy 0.1524 0.8001)
						(xy 0.13716 0.82804) (xy 0.11684 0.85344) (xy 0.09144 0.87376) (xy 0.0635 0.889) (xy 0.03175 0.89916)
					)
					(width 0)
					(fill yes)
				)
			)
		)
		(pad "57" smd custom
			(at -14.85011 4.106672 180)
			(size 0.1143 0.1143)
			(layers "F.Cu" "F.Mask" "F.Paste")
			(net "M_A_DQ29")
			(options
				(clearance outline)
				(anchor circle)
			)
			(primitives
				(gr_poly
					(pts
						(xy 0 0.9017) (xy -0.03175 0.89916) (xy -0.0635 0.889) (xy -0.09144 0.87376) (xy -0.11684 0.85344)
						(xy -0.13716 0.82804) (xy -0.1524 0.8001) (xy -0.16256 0.76835) (xy -0.1651 0.7366) (xy -0.1651 -0.13462)
						(xy -0.17272 -0.14224) (xy -0.19812 -0.1778) (xy -0.2032 -0.18796) (xy -0.20701 -0.19685) (xy -0.21209 -0.20701)
						(xy -0.2159 -0.21717) (xy -0.21844 -0.22733) (xy -0.22225 -0.23876) (xy -0.22352 -0.24892) (xy -0.22606 -0.25908)
						(xy -0.22733 -0.27051) (xy -0.22733 -0.28067) (xy -0.2286 -0.2921) (xy -0.22733 -0.30353) (xy -0.22733 -0.31369)
						(xy -0.22606 -0.32512) (xy -0.22352 -0.33528) (xy -0.22225 -0.34544) (xy -0.21844 -0.35687) (xy -0.2159 -0.36703)
						(xy -0.21209 -0.37719) (xy -0.20701 -0.38735) (xy -0.2032 -0.39624) (xy -0.19812 -0.4064) (xy -0.17272 -0.44196)
						(xy -0.1651 -0.44958) (xy -0.1651 -0.7366) (xy -0.16256 -0.76835) (xy -0.1524 -0.8001) (xy -0.13716 -0.82804)
						(xy -0.11684 -0.85344) (xy -0.09144 -0.87376) (xy -0.0635 -0.889) (xy -0.03175 -0.89916) (xy 0 -0.9017)
						(xy 0.03175 -0.89916) (xy 0.0635 -0.889) (xy 0.09144 -0.87376) (xy 0.11684 -0.85344) (xy 0.13716 -0.82804)
						(xy 0.1524 -0.8001) (xy 0.16256 -0.76835) (xy 0.1651 -0.7366) (xy 0.1651 -0.44958) (xy 0.17272 -0.44196)
						(xy 0.19812 -0.4064) (xy 0.2032 -0.39624) (xy 0.20701 -0.38735) (xy 0.21209 -0.37719) (xy 0.2159 -0.36703)
						(xy 0.21844 -0.35687) (xy 0.22225 -0.34544) (xy 0.22352 -0.33528) (xy 0.22606 -0.32512) (xy 0.22733 -0.31369)
						(xy 0.22733 -0.30353) (xy 0.2286 -0.2921) (xy 0.22733 -0.28067) (xy 0.22733 -0.27051) (xy 0.22606 -0.25908)
						(xy 0.22352 -0.24892) (xy 0.22225 -0.23876) (xy 0.21844 -0.22733) (xy 0.2159 -0.21717) (xy 0.21209 -0.20701)
						(xy 0.20701 -0.19685) (xy 0.2032 -0.18796) (xy 0.19812 -0.1778) (xy 0.17272 -0.14224) (xy 0.1651 -0.13462)
						(xy 0.1651 0.7366) (xy 0.16256 0.76835) (xy 0.1524 0.8001) (xy 0.13716 0.82804) (xy 0.11684 0.85344)
						(xy 0.09144 0.87376) (xy 0.0635 0.889) (xy 0.03175 0.89916)
					)
					(width 0)
					(fill yes)
				)
			)
		)
		(pad "58" smd custom
			(at -14.549882 -4.106672 180)
			(size 0.1143 0.1143)
			(layers "F.Cu" "F.Mask" "F.Paste")
			(net "GND")
			(options
				(clearance outline)
				(anchor circle)
			)
			(primitives
				(gr_poly
					(pts
						(xy 0 0.9017) (xy -0.03175 0.89916) (xy -0.0635 0.889) (xy -0.09144 0.87376) (xy -0.11684 0.85344)
						(xy -0.13716 0.82804) (xy -0.1524 0.8001) (xy -0.16256 0.76835) (xy -0.1651 0.7366) (xy -0.1651 0.44958)
						(xy -0.17272 0.44196) (xy -0.19812 0.4064) (xy -0.2032 0.39624) (xy -0.20701 0.38735) (xy -0.21209 0.37719)
						(xy -0.2159 0.36703) (xy -0.21844 0.35687) (xy -0.22225 0.34544) (xy -0.22352 0.33528) (xy -0.22606 0.32512)
						(xy -0.22733 0.31369) (xy -0.22733 0.30353) (xy -0.2286 0.2921) (xy -0.22733 0.28067) (xy -0.22733 0.27051)
						(xy -0.22606 0.25908) (xy -0.22352 0.24892) (xy -0.22225 0.23876) (xy -0.21844 0.22733) (xy -0.2159 0.21717)
						(xy -0.21209 0.20701) (xy -0.20701 0.19685) (xy -0.2032 0.18796) (xy -0.19812 0.1778) (xy -0.17272 0.14224)
						(xy -0.1651 0.13462) (xy -0.1651 -0.7366) (xy -0.16256 -0.76835) (xy -0.1524 -0.8001) (xy -0.13716 -0.82804)
						(xy -0.11684 -0.85344) (xy -0.09144 -0.87376) (xy -0.0635 -0.889) (xy -0.03175 -0.89916) (xy 0 -0.9017)
						(xy 0.03175 -0.89916) (xy 0.0635 -0.889) (xy 0.09144 -0.87376) (xy 0.11684 -0.85344) (xy 0.13716 -0.82804)
						(xy 0.1524 -0.8001) (xy 0.16256 -0.76835) (xy 0.1651 -0.7366) (xy 0.1651 0.13462) (xy 0.17272 0.14224)
						(xy 0.19812 0.1778) (xy 0.2032 0.18796) (xy 0.20701 0.19685) (xy 0.21209 0.20701) (xy 0.2159 0.21717)
						(xy 0.21844 0.22733) (xy 0.22225 0.23876) (xy 0.22352 0.24892) (xy 0.22606 0.25908) (xy 0.22733 0.27051)
						(xy 0.22733 0.28067) (xy 0.2286 0.2921) (xy 0.22733 0.30353) (xy 0.22733 0.31369) (xy 0.22606 0.32512)
						(xy 0.22352 0.33528) (xy 0.22225 0.34544) (xy 0.21844 0.35687) (xy 0.2159 0.36703) (xy 0.21209 0.37719)
						(xy 0.20701 0.38735) (xy 0.2032 0.39624) (xy 0.19812 0.4064) (xy 0.17272 0.44196) (xy 0.1651 0.44958)
						(xy 0.1651 0.7366) (xy 0.16256 0.76835) (xy 0.1524 0.8001) (xy 0.13716 0.82804) (xy 0.11684 0.85344)
						(xy 0.09144 0.87376) (xy 0.0635 0.889) (xy 0.03175 0.89916)
					)
					(width 0)
					(fill yes)
				)
			)
		)
		(pad "59" smd custom
			(at -14.249908 4.106672 180)
			(size 0.1143 0.1143)
			(layers "F.Cu" "F.Mask" "F.Paste")
			(net "GND")
			(options
				(clearance outline)
				(anchor circle)
			)
			(primitives
				(gr_poly
					(pts
						(xy 0 0.9017) (xy -0.03175 0.89916) (xy -0.0635 0.889) (xy -0.09144 0.87376) (xy -0.11684 0.85344)
						(xy -0.13716 0.82804) (xy -0.1524 0.8001) (xy -0.16256 0.76835) (xy -0.1651 0.7366) (xy -0.1651 0.11938)
						(xy -0.17272 0.11176) (xy -0.19812 0.0762) (xy -0.2032 0.06604) (xy -0.20701 0.05715) (xy -0.21209 0.04699)
						(xy -0.2159 0.03683) (xy -0.21844 0.02667) (xy -0.22225 0.01524) (xy -0.22352 0.00508) (xy -0.22606 -0.00508)
						(xy -0.22733 -0.01651) (xy -0.22733 -0.02667) (xy -0.2286 -0.0381) (xy -0.22733 -0.04953) (xy -0.22733 -0.05969)
						(xy -0.22606 -0.07112) (xy -0.22352 -0.08128) (xy -0.22225 -0.09144) (xy -0.21844 -0.10287) (xy -0.2159 -0.11303)
						(xy -0.21209 -0.12319) (xy -0.20701 -0.13335) (xy -0.2032 -0.14224) (xy -0.19812 -0.1524) (xy -0.17272 -0.18796)
						(xy -0.1651 -0.19558) (xy -0.1651 -0.7366) (xy -0.16256 -0.76835) (xy -0.1524 -0.8001) (xy -0.13716 -0.82804)
						(xy -0.11684 -0.85344) (xy -0.09144 -0.87376) (xy -0.0635 -0.889) (xy -0.03175 -0.89916) (xy 0 -0.9017)
						(xy 0.03175 -0.89916) (xy 0.0635 -0.889) (xy 0.09144 -0.87376) (xy 0.11684 -0.85344) (xy 0.13716 -0.82804)
						(xy 0.1524 -0.8001) (xy 0.16256 -0.76835) (xy 0.1651 -0.7366) (xy 0.1651 -0.19685) (xy 0.17272 -0.18923)
						(xy 0.17907 -0.18034) (xy 0.18669 -0.17145) (xy 0.19177 -0.16256) (xy 0.19812 -0.15367) (xy 0.20828 -0.13335)
						(xy 0.21971 -0.10287) (xy 0.22225 -0.09271) (xy 0.22479 -0.08128) (xy 0.22606 -0.07112) (xy 0.2286 -0.05969)
						(xy 0.2286 -0.01651) (xy 0.22606 -0.00508) (xy 0.22479 0.00508) (xy 0.22225 0.01651) (xy 0.21971 0.02667)
						(xy 0.20828 0.05715) (xy 0.19812 0.07747) (xy 0.19177 0.08636) (xy 0.18669 0.09525) (xy 0.17907 0.10414)
						(xy 0.17272 0.11303) (xy 0.1651 0.12065) (xy 0.1651 0.7366) (xy 0.16256 0.76835) (xy 0.1524 0.8001)
						(xy 0.13716 0.82804) (xy 0.11684 0.85344) (xy 0.09144 0.87376) (xy 0.0635 0.889) (xy 0.03175 0.89916)
					)
					(width 0)
					(fill yes)
				)
			)
		)
		(pad "60" smd custom
			(at -13.949934 -4.106672 180)
			(size 0.1143 0.1143)
			(layers "F.Cu" "F.Mask" "F.Paste")
			(net "M_A_DQS_DN3")
			(options
				(clearance outline)
				(anchor circle)
			)
			(primitives
				(gr_poly
					(pts
						(xy 0 0.9017) (xy -0.03175 0.89916) (xy -0.0635 0.889) (xy -0.09144 0.87376) (xy -0.11684 0.85344)
						(xy -0.13716 0.82804) (xy -0.1524 0.8001) (xy -0.16256 0.76835) (xy -0.1651 0.7366) (xy -0.1651 0.19685)
						(xy -0.17272 0.18923) (xy -0.17907 0.18034) (xy -0.18669 0.17145) (xy -0.19177 0.16256) (xy -0.19812 0.15367)
						(xy -0.20828 0.13335) (xy -0.21971 0.10287) (xy -0.22225 0.09271) (xy -0.22479 0.08128) (xy -0.22606 0.07112)
						(xy -0.2286 0.05969) (xy -0.2286 0.01651) (xy -0.22606 0.00508) (xy -0.22479 -0.00508) (xy -0.22225 -0.01651)
						(xy -0.21971 -0.02667) (xy -0.20828 -0.05715) (xy -0.19812 -0.07747) (xy -0.19177 -0.08636) (xy -0.18669 -0.09525)
						(xy -0.17907 -0.10414) (xy -0.17272 -0.11303) (xy -0.1651 -0.12065) (xy -0.1651 -0.7366) (xy -0.16256 -0.76835)
						(xy -0.1524 -0.8001) (xy -0.13716 -0.82804) (xy -0.11684 -0.85344) (xy -0.09144 -0.87376) (xy -0.0635 -0.889)
						(xy -0.03175 -0.89916) (xy 0 -0.9017) (xy 0.03175 -0.89916) (xy 0.0635 -0.889) (xy 0.09144 -0.87376)
						(xy 0.11684 -0.85344) (xy 0.13716 -0.82804) (xy 0.1524 -0.8001) (xy 0.16256 -0.76835) (xy 0.1651 -0.7366)
						(xy 0.1651 -0.11938) (xy 0.17272 -0.11176) (xy 0.19812 -0.0762) (xy 0.2032 -0.06604) (xy 0.20701 -0.05715)
						(xy 0.21209 -0.04699) (xy 0.2159 -0.03683) (xy 0.21844 -0.02667) (xy 0.22225 -0.01524) (xy 0.22352 -0.00508)
						(xy 0.22606 0.00508) (xy 0.22733 0.01651) (xy 0.22733 0.02667) (xy 0.2286 0.0381) (xy 0.22733 0.04953)
						(xy 0.22733 0.05969) (xy 0.22606 0.07112) (xy 0.22352 0.08128) (xy 0.22225 0.09144) (xy 0.21844 0.10287)
						(xy 0.2159 0.11303) (xy 0.21209 0.12319) (xy 0.20701 0.13335) (xy 0.2032 0.14224) (xy 0.19812 0.1524)
						(xy 0.17272 0.18796) (xy 0.1651 0.19558) (xy 0.1651 0.7366) (xy 0.16256 0.76835) (xy 0.1524 0.8001)
						(xy 0.13716 0.82804) (xy 0.11684 0.85344) (xy 0.09144 0.87376) (xy 0.0635 0.889) (xy 0.03175 0.89916)
					)
					(width 0)
					(fill yes)
				)
			)
		)
		(pad "61" smd custom
			(at -13.64996 4.106672 180)
			(size 0.1143 0.1143)
			(layers "F.Cu" "F.Mask" "F.Paste")
			(net "GND")
			(options
				(clearance outline)
				(anchor circle)
			)
			(primitives
				(gr_poly
					(pts
						(xy 0 0.9017) (xy -0.03175 0.89916) (xy -0.0635 0.889) (xy -0.09144 0.87376) (xy -0.11684 0.85344)
						(xy -0.13716 0.82804) (xy -0.1524 0.8001) (xy -0.16256 0.76835) (xy -0.1651 0.7366) (xy -0.1651 -0.13462)
						(xy -0.17272 -0.14224) (xy -0.19812 -0.1778) (xy -0.2032 -0.18796) (xy -0.20701 -0.19685) (xy -0.21209 -0.20701)
						(xy -0.2159 -0.21717) (xy -0.21844 -0.22733) (xy -0.22225 -0.23876) (xy -0.22352 -0.24892) (xy -0.22606 -0.25908)
						(xy -0.22733 -0.27051) (xy -0.22733 -0.28067) (xy -0.2286 -0.2921) (xy -0.22733 -0.30353) (xy -0.22733 -0.31369)
						(xy -0.22606 -0.32512) (xy -0.22352 -0.33528) (xy -0.22225 -0.34544) (xy -0.21844 -0.35687) (xy -0.2159 -0.36703)
						(xy -0.21209 -0.37719) (xy -0.20701 -0.38735) (xy -0.2032 -0.39624) (xy -0.19812 -0.4064) (xy -0.17272 -0.44196)
						(xy -0.1651 -0.44958) (xy -0.1651 -0.7366) (xy -0.16256 -0.76835) (xy -0.1524 -0.8001) (xy -0.13716 -0.82804)
						(xy -0.11684 -0.85344) (xy -0.09144 -0.87376) (xy -0.0635 -0.889) (xy -0.03175 -0.89916) (xy 0 -0.9017)
						(xy 0.03175 -0.89916) (xy 0.0635 -0.889) (xy 0.09144 -0.87376) (xy 0.11684 -0.85344) (xy 0.13716 -0.82804)
						(xy 0.1524 -0.8001) (xy 0.16256 -0.76835) (xy 0.1651 -0.7366) (xy 0.1651 -0.44958) (xy 0.17272 -0.44196)
						(xy 0.19812 -0.4064) (xy 0.2032 -0.39624) (xy 0.20701 -0.38735) (xy 0.21209 -0.37719) (xy 0.2159 -0.36703)
						(xy 0.21844 -0.35687) (xy 0.22225 -0.34544) (xy 0.22352 -0.33528) (xy 0.22606 -0.32512) (xy 0.22733 -0.31369)
						(xy 0.22733 -0.30353) (xy 0.2286 -0.2921) (xy 0.22733 -0.28067) (xy 0.22733 -0.27051) (xy 0.22606 -0.25908)
						(xy 0.22352 -0.24892) (xy 0.22225 -0.23876) (xy 0.21844 -0.22733) (xy 0.2159 -0.21717) (xy 0.21209 -0.20701)
						(xy 0.20701 -0.19685) (xy 0.2032 -0.18796) (xy 0.19812 -0.1778) (xy 0.17272 -0.14224) (xy 0.1651 -0.13462)
						(xy 0.1651 0.7366) (xy 0.16256 0.76835) (xy 0.1524 0.8001) (xy 0.13716 0.82804) (xy 0.11684 0.85344)
						(xy 0.09144 0.87376) (xy 0.0635 0.889) (xy 0.03175 0.89916)
					)
					(width 0)
					(fill yes)
				)
			)
		)
		(pad "62" smd custom
			(at -13.349986 -4.106672 180)
			(size 0.1143 0.1143)
			(layers "F.Cu" "F.Mask" "F.Paste")
			(net "M_A_DQS_DP3")
			(options
				(clearance outline)
				(anchor circle)
			)
			(primitives
				(gr_poly
					(pts
						(xy 0 0.9017) (xy -0.03175 0.89916) (xy -0.0635 0.889) (xy -0.09144 0.87376) (xy -0.11684 0.85344)
						(xy -0.13716 0.82804) (xy -0.1524 0.8001) (xy -0.16256 0.76835) (xy -0.1651 0.7366) (xy -0.1651 0.44958)
						(xy -0.17272 0.44196) (xy -0.19812 0.4064) (xy -0.2032 0.39624) (xy -0.20701 0.38735) (xy -0.21209 0.37719)
						(xy -0.2159 0.36703) (xy -0.21844 0.35687) (xy -0.22225 0.34544) (xy -0.22352 0.33528) (xy -0.22606 0.32512)
						(xy -0.22733 0.31369) (xy -0.22733 0.30353) (xy -0.2286 0.2921) (xy -0.22733 0.28067) (xy -0.22733 0.27051)
						(xy -0.22606 0.25908) (xy -0.22352 0.24892) (xy -0.22225 0.23876) (xy -0.21844 0.22733) (xy -0.2159 0.21717)
						(xy -0.21209 0.20701) (xy -0.20701 0.19685) (xy -0.2032 0.18796) (xy -0.19812 0.1778) (xy -0.17272 0.14224)
						(xy -0.1651 0.13462) (xy -0.1651 -0.7366) (xy -0.16256 -0.76835) (xy -0.1524 -0.8001) (xy -0.13716 -0.82804)
						(xy -0.11684 -0.85344) (xy -0.09144 -0.87376) (xy -0.0635 -0.889) (xy -0.03175 -0.89916) (xy 0 -0.9017)
						(xy 0.03175 -0.89916) (xy 0.0635 -0.889) (xy 0.09144 -0.87376) (xy 0.11684 -0.85344) (xy 0.13716 -0.82804)
						(xy 0.1524 -0.8001) (xy 0.16256 -0.76835) (xy 0.1651 -0.7366) (xy 0.1651 0.13462) (xy 0.17272 0.14224)
						(xy 0.19812 0.1778) (xy 0.2032 0.18796) (xy 0.20701 0.19685) (xy 0.21209 0.20701) (xy 0.2159 0.21717)
						(xy 0.21844 0.22733) (xy 0.22225 0.23876) (xy 0.22352 0.24892) (xy 0.22606 0.25908) (xy 0.22733 0.27051)
						(xy 0.22733 0.28067) (xy 0.2286 0.2921) (xy 0.22733 0.30353) (xy 0.22733 0.31369) (xy 0.22606 0.32512)
						(xy 0.22352 0.33528) (xy 0.22225 0.34544) (xy 0.21844 0.35687) (xy 0.2159 0.36703) (xy 0.21209 0.37719)
						(xy 0.20701 0.38735) (xy 0.2032 0.39624) (xy 0.19812 0.4064) (xy 0.17272 0.44196) (xy 0.1651 0.44958)
						(xy 0.1651 0.7366) (xy 0.16256 0.76835) (xy 0.1524 0.8001) (xy 0.13716 0.82804) (xy 0.11684 0.85344)
						(xy 0.09144 0.87376) (xy 0.0635 0.889) (xy 0.03175 0.89916)
					)
					(width 0)
					(fill yes)
				)
			)
		)
		(pad "63" smd custom
			(at -13.050012 4.106672 180)
			(size 0.1143 0.1143)
			(layers "F.Cu" "F.Mask" "F.Paste")
			(net "M_A_DQ30")
			(options
				(clearance outline)
				(anchor circle)
			)
			(primitives
				(gr_poly
					(pts
						(xy 0 0.9017) (xy -0.03175 0.89916) (xy -0.0635 0.889) (xy -0.09144 0.87376) (xy -0.11684 0.85344)
						(xy -0.13716 0.82804) (xy -0.1524 0.8001) (xy -0.16256 0.76835) (xy -0.1651 0.7366) (xy -0.1651 0.11938)
						(xy -0.17272 0.11176) (xy -0.19812 0.0762) (xy -0.2032 0.06604) (xy -0.20701 0.05715) (xy -0.21209 0.04699)
						(xy -0.2159 0.03683) (xy -0.21844 0.02667) (xy -0.22225 0.01524) (xy -0.22352 0.00508) (xy -0.22606 -0.00508)
						(xy -0.22733 -0.01651) (xy -0.22733 -0.02667) (xy -0.2286 -0.0381) (xy -0.22733 -0.04953) (xy -0.22733 -0.05969)
						(xy -0.22606 -0.07112) (xy -0.22352 -0.08128) (xy -0.22225 -0.09144) (xy -0.21844 -0.10287) (xy -0.2159 -0.11303)
						(xy -0.21209 -0.12319) (xy -0.20701 -0.13335) (xy -0.2032 -0.14224) (xy -0.19812 -0.1524) (xy -0.17272 -0.18796)
						(xy -0.1651 -0.19558) (xy -0.1651 -0.7366) (xy -0.16256 -0.76835) (xy -0.1524 -0.8001) (xy -0.13716 -0.82804)
						(xy -0.11684 -0.85344) (xy -0.09144 -0.87376) (xy -0.0635 -0.889) (xy -0.03175 -0.89916) (xy 0 -0.9017)
						(xy 0.03175 -0.89916) (xy 0.0635 -0.889) (xy 0.09144 -0.87376) (xy 0.11684 -0.85344) (xy 0.13716 -0.82804)
						(xy 0.1524 -0.8001) (xy 0.16256 -0.76835) (xy 0.1651 -0.7366) (xy 0.1651 -0.19685) (xy 0.17272 -0.18923)
						(xy 0.17907 -0.18034) (xy 0.18669 -0.17145) (xy 0.19177 -0.16256) (xy 0.19812 -0.15367) (xy 0.20828 -0.13335)
						(xy 0.21971 -0.10287) (xy 0.22225 -0.09271) (xy 0.22479 -0.08128) (xy 0.22606 -0.07112) (xy 0.2286 -0.05969)
						(xy 0.2286 -0.01651) (xy 0.22606 -0.00508) (xy 0.22479 0.00508) (xy 0.22225 0.01651) (xy 0.21971 0.02667)
						(xy 0.20828 0.05715) (xy 0.19812 0.07747) (xy 0.19177 0.08636) (xy 0.18669 0.09525) (xy 0.17907 0.10414)
						(xy 0.17272 0.11303) (xy 0.1651 0.12065) (xy 0.1651 0.7366) (xy 0.16256 0.76835) (xy 0.1524 0.8001)
						(xy 0.13716 0.82804) (xy 0.11684 0.85344) (xy 0.09144 0.87376) (xy 0.0635 0.889) (xy 0.03175 0.89916)
					)
					(width 0)
					(fill yes)
				)
			)
		)
		(pad "64" smd custom
			(at -12.750038 -4.106672 180)
			(size 0.1143 0.1143)
			(layers "F.Cu" "F.Mask" "F.Paste")
			(net "GND")
			(options
				(clearance outline)
				(anchor circle)
			)
			(primitives
				(gr_poly
					(pts
						(xy 0 0.9017) (xy -0.03175 0.89916) (xy -0.0635 0.889) (xy -0.09144 0.87376) (xy -0.11684 0.85344)
						(xy -0.13716 0.82804) (xy -0.1524 0.8001) (xy -0.16256 0.76835) (xy -0.1651 0.7366) (xy -0.1651 0.19685)
						(xy -0.17272 0.18923) (xy -0.17907 0.18034) (xy -0.18669 0.17145) (xy -0.19177 0.16256) (xy -0.19812 0.15367)
						(xy -0.20828 0.13335) (xy -0.21971 0.10287) (xy -0.22225 0.09271) (xy -0.22479 0.08128) (xy -0.22606 0.07112)
						(xy -0.2286 0.05969) (xy -0.2286 0.01651) (xy -0.22606 0.00508) (xy -0.22479 -0.00508) (xy -0.22225 -0.01651)
						(xy -0.21971 -0.02667) (xy -0.20828 -0.05715) (xy -0.19812 -0.07747) (xy -0.19177 -0.08636) (xy -0.18669 -0.09525)
						(xy -0.17907 -0.10414) (xy -0.17272 -0.11303) (xy -0.1651 -0.12065) (xy -0.1651 -0.7366) (xy -0.16256 -0.76835)
						(xy -0.1524 -0.8001) (xy -0.13716 -0.82804) (xy -0.11684 -0.85344) (xy -0.09144 -0.87376) (xy -0.0635 -0.889)
						(xy -0.03175 -0.89916) (xy 0 -0.9017) (xy 0.03175 -0.89916) (xy 0.0635 -0.889) (xy 0.09144 -0.87376)
						(xy 0.11684 -0.85344) (xy 0.13716 -0.82804) (xy 0.1524 -0.8001) (xy 0.16256 -0.76835) (xy 0.1651 -0.7366)
						(xy 0.1651 -0.11938) (xy 0.17272 -0.11176) (xy 0.19812 -0.0762) (xy 0.2032 -0.06604) (xy 0.20701 -0.05715)
						(xy 0.21209 -0.04699) (xy 0.2159 -0.03683) (xy 0.21844 -0.02667) (xy 0.22225 -0.01524) (xy 0.22352 -0.00508)
						(xy 0.22606 0.00508) (xy 0.22733 0.01651) (xy 0.22733 0.02667) (xy 0.2286 0.0381) (xy 0.22733 0.04953)
						(xy 0.22733 0.05969) (xy 0.22606 0.07112) (xy 0.22352 0.08128) (xy 0.22225 0.09144) (xy 0.21844 0.10287)
						(xy 0.2159 0.11303) (xy 0.21209 0.12319) (xy 0.20701 0.13335) (xy 0.2032 0.14224) (xy 0.19812 0.1524)
						(xy 0.17272 0.18796) (xy 0.1651 0.19558) (xy 0.1651 0.7366) (xy 0.16256 0.76835) (xy 0.1524 0.8001)
						(xy 0.13716 0.82804) (xy 0.11684 0.85344) (xy 0.09144 0.87376) (xy 0.0635 0.889) (xy 0.03175 0.89916)
					)
					(width 0)
					(fill yes)
				)
			)
		)
		(pad "65" smd custom
			(at -12.450064 4.106672 180)
			(size 0.1143 0.1143)
			(layers "F.Cu" "F.Mask" "F.Paste")
			(net "M_A_DQ31")
			(options
				(clearance outline)
				(anchor circle)
			)
			(primitives
				(gr_poly
					(pts
						(xy 0 0.9017) (xy -0.03175 0.89916) (xy -0.0635 0.889) (xy -0.09144 0.87376) (xy -0.11684 0.85344)
						(xy -0.13716 0.82804) (xy -0.1524 0.8001) (xy -0.16256 0.76835) (xy -0.1651 0.7366) (xy -0.1651 -0.13462)
						(xy -0.17272 -0.14224) (xy -0.19812 -0.1778) (xy -0.2032 -0.18796) (xy -0.20701 -0.19685) (xy -0.21209 -0.20701)
						(xy -0.2159 -0.21717) (xy -0.21844 -0.22733) (xy -0.22225 -0.23876) (xy -0.22352 -0.24892) (xy -0.22606 -0.25908)
						(xy -0.22733 -0.27051) (xy -0.22733 -0.28067) (xy -0.2286 -0.2921) (xy -0.22733 -0.30353) (xy -0.22733 -0.31369)
						(xy -0.22606 -0.32512) (xy -0.22352 -0.33528) (xy -0.22225 -0.34544) (xy -0.21844 -0.35687) (xy -0.2159 -0.36703)
						(xy -0.21209 -0.37719) (xy -0.20701 -0.38735) (xy -0.2032 -0.39624) (xy -0.19812 -0.4064) (xy -0.17272 -0.44196)
						(xy -0.1651 -0.44958) (xy -0.1651 -0.7366) (xy -0.16256 -0.76835) (xy -0.1524 -0.8001) (xy -0.13716 -0.82804)
						(xy -0.11684 -0.85344) (xy -0.09144 -0.87376) (xy -0.0635 -0.889) (xy -0.03175 -0.89916) (xy 0 -0.9017)
						(xy 0.03175 -0.89916) (xy 0.0635 -0.889) (xy 0.09144 -0.87376) (xy 0.11684 -0.85344) (xy 0.13716 -0.82804)
						(xy 0.1524 -0.8001) (xy 0.16256 -0.76835) (xy 0.1651 -0.7366) (xy 0.1651 -0.44958) (xy 0.17272 -0.44196)
						(xy 0.19812 -0.4064) (xy 0.2032 -0.39624) (xy 0.20701 -0.38735) (xy 0.21209 -0.37719) (xy 0.2159 -0.36703)
						(xy 0.21844 -0.35687) (xy 0.22225 -0.34544) (xy 0.22352 -0.33528) (xy 0.22606 -0.32512) (xy 0.22733 -0.31369)
						(xy 0.22733 -0.30353) (xy 0.2286 -0.2921) (xy 0.22733 -0.28067) (xy 0.22733 -0.27051) (xy 0.22606 -0.25908)
						(xy 0.22352 -0.24892) (xy 0.22225 -0.23876) (xy 0.21844 -0.22733) (xy 0.2159 -0.21717) (xy 0.21209 -0.20701)
						(xy 0.20701 -0.19685) (xy 0.2032 -0.18796) (xy 0.19812 -0.1778) (xy 0.17272 -0.14224) (xy 0.1651 -0.13462)
						(xy 0.1651 0.7366) (xy 0.16256 0.76835) (xy 0.1524 0.8001) (xy 0.13716 0.82804) (xy 0.11684 0.85344)
						(xy 0.09144 0.87376) (xy 0.0635 0.889) (xy 0.03175 0.89916)
					)
					(width 0)
					(fill yes)
				)
			)
		)
		(pad "66" smd custom
			(at -12.15009 -4.106672 180)
			(size 0.1143 0.1143)
			(layers "F.Cu" "F.Mask" "F.Paste")
			(net "M_A_DQ26")
			(options
				(clearance outline)
				(anchor circle)
			)
			(primitives
				(gr_poly
					(pts
						(xy 0 0.9017) (xy -0.03175 0.89916) (xy -0.0635 0.889) (xy -0.09144 0.87376) (xy -0.11684 0.85344)
						(xy -0.13716 0.82804) (xy -0.1524 0.8001) (xy -0.16256 0.76835) (xy -0.1651 0.7366) (xy -0.1651 0.44958)
						(xy -0.17272 0.44196) (xy -0.19812 0.4064) (xy -0.2032 0.39624) (xy -0.20701 0.38735) (xy -0.21209 0.37719)
						(xy -0.2159 0.36703) (xy -0.21844 0.35687) (xy -0.22225 0.34544) (xy -0.22352 0.33528) (xy -0.22606 0.32512)
						(xy -0.22733 0.31369) (xy -0.22733 0.30353) (xy -0.2286 0.2921) (xy -0.22733 0.28067) (xy -0.22733 0.27051)
						(xy -0.22606 0.25908) (xy -0.22352 0.24892) (xy -0.22225 0.23876) (xy -0.21844 0.22733) (xy -0.2159 0.21717)
						(xy -0.21209 0.20701) (xy -0.20701 0.19685) (xy -0.2032 0.18796) (xy -0.19812 0.1778) (xy -0.17272 0.14224)
						(xy -0.1651 0.13462) (xy -0.1651 -0.7366) (xy -0.16256 -0.76835) (xy -0.1524 -0.8001) (xy -0.13716 -0.82804)
						(xy -0.11684 -0.85344) (xy -0.09144 -0.87376) (xy -0.0635 -0.889) (xy -0.03175 -0.89916) (xy 0 -0.9017)
						(xy 0.03175 -0.89916) (xy 0.0635 -0.889) (xy 0.09144 -0.87376) (xy 0.11684 -0.85344) (xy 0.13716 -0.82804)
						(xy 0.1524 -0.8001) (xy 0.16256 -0.76835) (xy 0.1651 -0.7366) (xy 0.1651 0.13462) (xy 0.17272 0.14224)
						(xy 0.19812 0.1778) (xy 0.2032 0.18796) (xy 0.20701 0.19685) (xy 0.21209 0.20701) (xy 0.2159 0.21717)
						(xy 0.21844 0.22733) (xy 0.22225 0.23876) (xy 0.22352 0.24892) (xy 0.22606 0.25908) (xy 0.22733 0.27051)
						(xy 0.22733 0.28067) (xy 0.2286 0.2921) (xy 0.22733 0.30353) (xy 0.22733 0.31369) (xy 0.22606 0.32512)
						(xy 0.22352 0.33528) (xy 0.22225 0.34544) (xy 0.21844 0.35687) (xy 0.2159 0.36703) (xy 0.21209 0.37719)
						(xy 0.20701 0.38735) (xy 0.2032 0.39624) (xy 0.19812 0.4064) (xy 0.17272 0.44196) (xy 0.1651 0.44958)
						(xy 0.1651 0.7366) (xy 0.16256 0.76835) (xy 0.1524 0.8001) (xy 0.13716 0.82804) (xy 0.11684 0.85344)
						(xy 0.09144 0.87376) (xy 0.0635 0.889) (xy 0.03175 0.89916)
					)
					(width 0)
					(fill yes)
				)
			)
		)
		(pad "67" smd custom
			(at -11.850116 4.106672 180)
			(size 0.1143 0.1143)
			(layers "F.Cu" "F.Mask" "F.Paste")
			(net "GND")
			(options
				(clearance outline)
				(anchor circle)
			)
			(primitives
				(gr_poly
					(pts
						(xy 0 0.9017) (xy -0.03175 0.89916) (xy -0.0635 0.889) (xy -0.09144 0.87376) (xy -0.11684 0.85344)
						(xy -0.13716 0.82804) (xy -0.1524 0.8001) (xy -0.16256 0.76835) (xy -0.1651 0.7366) (xy -0.1651 0.11938)
						(xy -0.17272 0.11176) (xy -0.19812 0.0762) (xy -0.2032 0.06604) (xy -0.20701 0.05715) (xy -0.21209 0.04699)
						(xy -0.2159 0.03683) (xy -0.21844 0.02667) (xy -0.22225 0.01524) (xy -0.22352 0.00508) (xy -0.22606 -0.00508)
						(xy -0.22733 -0.01651) (xy -0.22733 -0.02667) (xy -0.2286 -0.0381) (xy -0.22733 -0.04953) (xy -0.22733 -0.05969)
						(xy -0.22606 -0.07112) (xy -0.22352 -0.08128) (xy -0.22225 -0.09144) (xy -0.21844 -0.10287) (xy -0.2159 -0.11303)
						(xy -0.21209 -0.12319) (xy -0.20701 -0.13335) (xy -0.2032 -0.14224) (xy -0.19812 -0.1524) (xy -0.17272 -0.18796)
						(xy -0.1651 -0.19558) (xy -0.1651 -0.7366) (xy -0.16256 -0.76835) (xy -0.1524 -0.8001) (xy -0.13716 -0.82804)
						(xy -0.11684 -0.85344) (xy -0.09144 -0.87376) (xy -0.0635 -0.889) (xy -0.03175 -0.89916) (xy 0 -0.9017)
						(xy 0.03175 -0.89916) (xy 0.0635 -0.889) (xy 0.09144 -0.87376) (xy 0.11684 -0.85344) (xy 0.13716 -0.82804)
						(xy 0.1524 -0.8001) (xy 0.16256 -0.76835) (xy 0.1651 -0.7366) (xy 0.1651 -0.19685) (xy 0.17272 -0.18923)
						(xy 0.17907 -0.18034) (xy 0.18669 -0.17145) (xy 0.19177 -0.16256) (xy 0.19812 -0.15367) (xy 0.20828 -0.13335)
						(xy 0.21971 -0.10287) (xy 0.22225 -0.09271) (xy 0.22479 -0.08128) (xy 0.22606 -0.07112) (xy 0.2286 -0.05969)
						(xy 0.2286 -0.01651) (xy 0.22606 -0.00508) (xy 0.22479 0.00508) (xy 0.22225 0.01651) (xy 0.21971 0.02667)
						(xy 0.20828 0.05715) (xy 0.19812 0.07747) (xy 0.19177 0.08636) (xy 0.18669 0.09525) (xy 0.17907 0.10414)
						(xy 0.17272 0.11303) (xy 0.1651 0.12065) (xy 0.1651 0.7366) (xy 0.16256 0.76835) (xy 0.1524 0.8001)
						(xy 0.13716 0.82804) (xy 0.11684 0.85344) (xy 0.09144 0.87376) (xy 0.0635 0.889) (xy 0.03175 0.89916)
					)
					(width 0)
					(fill yes)
				)
			)
		)
		(pad "68" smd custom
			(at -11.549888 -4.106672 180)
			(size 0.1143 0.1143)
			(layers "F.Cu" "F.Mask" "F.Paste")
			(net "M_A_DQ27")
			(options
				(clearance outline)
				(anchor circle)
			)
			(primitives
				(gr_poly
					(pts
						(xy 0 0.9017) (xy -0.03175 0.89916) (xy -0.0635 0.889) (xy -0.09144 0.87376) (xy -0.11684 0.85344)
						(xy -0.13716 0.82804) (xy -0.1524 0.8001) (xy -0.16256 0.76835) (xy -0.1651 0.7366) (xy -0.1651 0.19685)
						(xy -0.17272 0.18923) (xy -0.17907 0.18034) (xy -0.18669 0.17145) (xy -0.19177 0.16256) (xy -0.19812 0.15367)
						(xy -0.20828 0.13335) (xy -0.21971 0.10287) (xy -0.22225 0.09271) (xy -0.22479 0.08128) (xy -0.22606 0.07112)
						(xy -0.2286 0.05969) (xy -0.2286 0.01651) (xy -0.22606 0.00508) (xy -0.22479 -0.00508) (xy -0.22225 -0.01651)
						(xy -0.21971 -0.02667) (xy -0.20828 -0.05715) (xy -0.19812 -0.07747) (xy -0.19177 -0.08636) (xy -0.18669 -0.09525)
						(xy -0.17907 -0.10414) (xy -0.17272 -0.11303) (xy -0.1651 -0.12065) (xy -0.1651 -0.7366) (xy -0.16256 -0.76835)
						(xy -0.1524 -0.8001) (xy -0.13716 -0.82804) (xy -0.11684 -0.85344) (xy -0.09144 -0.87376) (xy -0.0635 -0.889)
						(xy -0.03175 -0.89916) (xy 0 -0.9017) (xy 0.03175 -0.89916) (xy 0.0635 -0.889) (xy 0.09144 -0.87376)
						(xy 0.11684 -0.85344) (xy 0.13716 -0.82804) (xy 0.1524 -0.8001) (xy 0.16256 -0.76835) (xy 0.1651 -0.7366)
						(xy 0.1651 -0.11938) (xy 0.17272 -0.11176) (xy 0.19812 -0.0762) (xy 0.2032 -0.06604) (xy 0.20701 -0.05715)
						(xy 0.21209 -0.04699) (xy 0.2159 -0.03683) (xy 0.21844 -0.02667) (xy 0.22225 -0.01524) (xy 0.22352 -0.00508)
						(xy 0.22606 0.00508) (xy 0.22733 0.01651) (xy 0.22733 0.02667) (xy 0.2286 0.0381) (xy 0.22733 0.04953)
						(xy 0.22733 0.05969) (xy 0.22606 0.07112) (xy 0.22352 0.08128) (xy 0.22225 0.09144) (xy 0.21844 0.10287)
						(xy 0.2159 0.11303) (xy 0.21209 0.12319) (xy 0.20701 0.13335) (xy 0.2032 0.14224) (xy 0.19812 0.1524)
						(xy 0.17272 0.18796) (xy 0.1651 0.19558) (xy 0.1651 0.7366) (xy 0.16256 0.76835) (xy 0.1524 0.8001)
						(xy 0.13716 0.82804) (xy 0.11684 0.85344) (xy 0.09144 0.87376) (xy 0.0635 0.889) (xy 0.03175 0.89916)
					)
					(width 0)
					(fill yes)
				)
			)
		)
		(pad "69" smd custom
			(at -11.249914 4.106672 180)
			(size 0.1143 0.1143)
			(layers "F.Cu" "F.Mask" "F.Paste")
			(net "M_A_ECC4")
			(options
				(clearance outline)
				(anchor circle)
			)
			(primitives
				(gr_poly
					(pts
						(xy 0 0.9017) (xy -0.03175 0.89916) (xy -0.0635 0.889) (xy -0.09144 0.87376) (xy -0.11684 0.85344)
						(xy -0.13716 0.82804) (xy -0.1524 0.8001) (xy -0.16256 0.76835) (xy -0.1651 0.7366) (xy -0.1651 -0.13462)
						(xy -0.17272 -0.14224) (xy -0.19812 -0.1778) (xy -0.2032 -0.18796) (xy -0.20701 -0.19685) (xy -0.21209 -0.20701)
						(xy -0.2159 -0.21717) (xy -0.21844 -0.22733) (xy -0.22225 -0.23876) (xy -0.22352 -0.24892) (xy -0.22606 -0.25908)
						(xy -0.22733 -0.27051) (xy -0.22733 -0.28067) (xy -0.2286 -0.2921) (xy -0.22733 -0.30353) (xy -0.22733 -0.31369)
						(xy -0.22606 -0.32512) (xy -0.22352 -0.33528) (xy -0.22225 -0.34544) (xy -0.21844 -0.35687) (xy -0.2159 -0.36703)
						(xy -0.21209 -0.37719) (xy -0.20701 -0.38735) (xy -0.2032 -0.39624) (xy -0.19812 -0.4064) (xy -0.17272 -0.44196)
						(xy -0.1651 -0.44958) (xy -0.1651 -0.7366) (xy -0.16256 -0.76835) (xy -0.1524 -0.8001) (xy -0.13716 -0.82804)
						(xy -0.11684 -0.85344) (xy -0.09144 -0.87376) (xy -0.0635 -0.889) (xy -0.03175 -0.89916) (xy 0 -0.9017)
						(xy 0.03175 -0.89916) (xy 0.0635 -0.889) (xy 0.09144 -0.87376) (xy 0.11684 -0.85344) (xy 0.13716 -0.82804)
						(xy 0.1524 -0.8001) (xy 0.16256 -0.76835) (xy 0.1651 -0.7366) (xy 0.1651 -0.44958) (xy 0.17272 -0.44196)
						(xy 0.19812 -0.4064) (xy 0.2032 -0.39624) (xy 0.20701 -0.38735) (xy 0.21209 -0.37719) (xy 0.2159 -0.36703)
						(xy 0.21844 -0.35687) (xy 0.22225 -0.34544) (xy 0.22352 -0.33528) (xy 0.22606 -0.32512) (xy 0.22733 -0.31369)
						(xy 0.22733 -0.30353) (xy 0.2286 -0.2921) (xy 0.22733 -0.28067) (xy 0.22733 -0.27051) (xy 0.22606 -0.25908)
						(xy 0.22352 -0.24892) (xy 0.22225 -0.23876) (xy 0.21844 -0.22733) (xy 0.2159 -0.21717) (xy 0.21209 -0.20701)
						(xy 0.20701 -0.19685) (xy 0.2032 -0.18796) (xy 0.19812 -0.1778) (xy 0.17272 -0.14224) (xy 0.1651 -0.13462)
						(xy 0.1651 0.7366) (xy 0.16256 0.76835) (xy 0.1524 0.8001) (xy 0.13716 0.82804) (xy 0.11684 0.85344)
						(xy 0.09144 0.87376) (xy 0.0635 0.889) (xy 0.03175 0.89916)
					)
					(width 0)
					(fill yes)
				)
			)
		)
		(pad "70" smd custom
			(at -10.94994 -4.106672 180)
			(size 0.1143 0.1143)
			(layers "F.Cu" "F.Mask" "F.Paste")
			(net "GND")
			(options
				(clearance outline)
				(anchor circle)
			)
			(primitives
				(gr_poly
					(pts
						(xy 0 0.9017) (xy -0.03175 0.89916) (xy -0.0635 0.889) (xy -0.09144 0.87376) (xy -0.11684 0.85344)
						(xy -0.13716 0.82804) (xy -0.1524 0.8001) (xy -0.16256 0.76835) (xy -0.1651 0.7366) (xy -0.1651 0.44958)
						(xy -0.17272 0.44196) (xy -0.19812 0.4064) (xy -0.2032 0.39624) (xy -0.20701 0.38735) (xy -0.21209 0.37719)
						(xy -0.2159 0.36703) (xy -0.21844 0.35687) (xy -0.22225 0.34544) (xy -0.22352 0.33528) (xy -0.22606 0.32512)
						(xy -0.22733 0.31369) (xy -0.22733 0.30353) (xy -0.2286 0.2921) (xy -0.22733 0.28067) (xy -0.22733 0.27051)
						(xy -0.22606 0.25908) (xy -0.22352 0.24892) (xy -0.22225 0.23876) (xy -0.21844 0.22733) (xy -0.2159 0.21717)
						(xy -0.21209 0.20701) (xy -0.20701 0.19685) (xy -0.2032 0.18796) (xy -0.19812 0.1778) (xy -0.17272 0.14224)
						(xy -0.1651 0.13462) (xy -0.1651 -0.7366) (xy -0.16256 -0.76835) (xy -0.1524 -0.8001) (xy -0.13716 -0.82804)
						(xy -0.11684 -0.85344) (xy -0.09144 -0.87376) (xy -0.0635 -0.889) (xy -0.03175 -0.89916) (xy 0 -0.9017)
						(xy 0.03175 -0.89916) (xy 0.0635 -0.889) (xy 0.09144 -0.87376) (xy 0.11684 -0.85344) (xy 0.13716 -0.82804)
						(xy 0.1524 -0.8001) (xy 0.16256 -0.76835) (xy 0.1651 -0.7366) (xy 0.1651 0.13462) (xy 0.17272 0.14224)
						(xy 0.19812 0.1778) (xy 0.2032 0.18796) (xy 0.20701 0.19685) (xy 0.21209 0.20701) (xy 0.2159 0.21717)
						(xy 0.21844 0.22733) (xy 0.22225 0.23876) (xy 0.22352 0.24892) (xy 0.22606 0.25908) (xy 0.22733 0.27051)
						(xy 0.22733 0.28067) (xy 0.2286 0.2921) (xy 0.22733 0.30353) (xy 0.22733 0.31369) (xy 0.22606 0.32512)
						(xy 0.22352 0.33528) (xy 0.22225 0.34544) (xy 0.21844 0.35687) (xy 0.2159 0.36703) (xy 0.21209 0.37719)
						(xy 0.20701 0.38735) (xy 0.2032 0.39624) (xy 0.19812 0.4064) (xy 0.17272 0.44196) (xy 0.1651 0.44958)
						(xy 0.1651 0.7366) (xy 0.16256 0.76835) (xy 0.1524 0.8001) (xy 0.13716 0.82804) (xy 0.11684 0.85344)
						(xy 0.09144 0.87376) (xy 0.0635 0.889) (xy 0.03175 0.89916)
					)
					(width 0)
					(fill yes)
				)
			)
		)
		(pad "71" smd custom
			(at -10.649966 4.106672 180)
			(size 0.1143 0.1143)
			(layers "F.Cu" "F.Mask" "F.Paste")
			(net "M_A_ECC5")
			(options
				(clearance outline)
				(anchor circle)
			)
			(primitives
				(gr_poly
					(pts
						(xy 0 0.9017) (xy -0.03175 0.89916) (xy -0.0635 0.889) (xy -0.09144 0.87376) (xy -0.11684 0.85344)
						(xy -0.13716 0.82804) (xy -0.1524 0.8001) (xy -0.16256 0.76835) (xy -0.1651 0.7366) (xy -0.1651 0.11938)
						(xy -0.17272 0.11176) (xy -0.19812 0.0762) (xy -0.2032 0.06604) (xy -0.20701 0.05715) (xy -0.21209 0.04699)
						(xy -0.2159 0.03683) (xy -0.21844 0.02667) (xy -0.22225 0.01524) (xy -0.22352 0.00508) (xy -0.22606 -0.00508)
						(xy -0.22733 -0.01651) (xy -0.22733 -0.02667) (xy -0.2286 -0.0381) (xy -0.22733 -0.04953) (xy -0.22733 -0.05969)
						(xy -0.22606 -0.07112) (xy -0.22352 -0.08128) (xy -0.22225 -0.09144) (xy -0.21844 -0.10287) (xy -0.2159 -0.11303)
						(xy -0.21209 -0.12319) (xy -0.20701 -0.13335) (xy -0.2032 -0.14224) (xy -0.19812 -0.1524) (xy -0.17272 -0.18796)
						(xy -0.1651 -0.19558) (xy -0.1651 -0.7366) (xy -0.16256 -0.76835) (xy -0.1524 -0.8001) (xy -0.13716 -0.82804)
						(xy -0.11684 -0.85344) (xy -0.09144 -0.87376) (xy -0.0635 -0.889) (xy -0.03175 -0.89916) (xy 0 -0.9017)
						(xy 0.03175 -0.89916) (xy 0.0635 -0.889) (xy 0.09144 -0.87376) (xy 0.11684 -0.85344) (xy 0.13716 -0.82804)
						(xy 0.1524 -0.8001) (xy 0.16256 -0.76835) (xy 0.1651 -0.7366) (xy 0.1651 -0.19685) (xy 0.17272 -0.18923)
						(xy 0.17907 -0.18034) (xy 0.18669 -0.17145) (xy 0.19177 -0.16256) (xy 0.19812 -0.15367) (xy 0.20828 -0.13335)
						(xy 0.21971 -0.10287) (xy 0.22225 -0.09271) (xy 0.22479 -0.08128) (xy 0.22606 -0.07112) (xy 0.2286 -0.05969)
						(xy 0.2286 -0.01651) (xy 0.22606 -0.00508) (xy 0.22479 0.00508) (xy 0.22225 0.01651) (xy 0.21971 0.02667)
						(xy 0.20828 0.05715) (xy 0.19812 0.07747) (xy 0.19177 0.08636) (xy 0.18669 0.09525) (xy 0.17907 0.10414)
						(xy 0.17272 0.11303) (xy 0.1651 0.12065) (xy 0.1651 0.7366) (xy 0.16256 0.76835) (xy 0.1524 0.8001)
						(xy 0.13716 0.82804) (xy 0.11684 0.85344) (xy 0.09144 0.87376) (xy 0.0635 0.889) (xy 0.03175 0.89916)
					)
					(width 0)
					(fill yes)
				)
			)
		)
		(pad "72" smd custom
			(at -10.349992 -4.106672 180)
			(size 0.1143 0.1143)
			(layers "F.Cu" "F.Mask" "F.Paste")
			(net "M_A_ECC0")
			(options
				(clearance outline)
				(anchor circle)
			)
			(primitives
				(gr_poly
					(pts
						(xy 0 0.9017) (xy -0.03175 0.89916) (xy -0.0635 0.889) (xy -0.09144 0.87376) (xy -0.11684 0.85344)
						(xy -0.13716 0.82804) (xy -0.1524 0.8001) (xy -0.16256 0.76835) (xy -0.1651 0.7366) (xy -0.1651 0.19685)
						(xy -0.17272 0.18923) (xy -0.17907 0.18034) (xy -0.18669 0.17145) (xy -0.19177 0.16256) (xy -0.19812 0.15367)
						(xy -0.20828 0.13335) (xy -0.21971 0.10287) (xy -0.22225 0.09271) (xy -0.22479 0.08128) (xy -0.22606 0.07112)
						(xy -0.2286 0.05969) (xy -0.2286 0.01651) (xy -0.22606 0.00508) (xy -0.22479 -0.00508) (xy -0.22225 -0.01651)
						(xy -0.21971 -0.02667) (xy -0.20828 -0.05715) (xy -0.19812 -0.07747) (xy -0.19177 -0.08636) (xy -0.18669 -0.09525)
						(xy -0.17907 -0.10414) (xy -0.17272 -0.11303) (xy -0.1651 -0.12065) (xy -0.1651 -0.7366) (xy -0.16256 -0.76835)
						(xy -0.1524 -0.8001) (xy -0.13716 -0.82804) (xy -0.11684 -0.85344) (xy -0.09144 -0.87376) (xy -0.0635 -0.889)
						(xy -0.03175 -0.89916) (xy 0 -0.9017) (xy 0.03175 -0.89916) (xy 0.0635 -0.889) (xy 0.09144 -0.87376)
						(xy 0.11684 -0.85344) (xy 0.13716 -0.82804) (xy 0.1524 -0.8001) (xy 0.16256 -0.76835) (xy 0.1651 -0.7366)
						(xy 0.1651 -0.11938) (xy 0.17272 -0.11176) (xy 0.19812 -0.0762) (xy 0.2032 -0.06604) (xy 0.20701 -0.05715)
						(xy 0.21209 -0.04699) (xy 0.2159 -0.03683) (xy 0.21844 -0.02667) (xy 0.22225 -0.01524) (xy 0.22352 -0.00508)
						(xy 0.22606 0.00508) (xy 0.22733 0.01651) (xy 0.22733 0.02667) (xy 0.2286 0.0381) (xy 0.22733 0.04953)
						(xy 0.22733 0.05969) (xy 0.22606 0.07112) (xy 0.22352 0.08128) (xy 0.22225 0.09144) (xy 0.21844 0.10287)
						(xy 0.2159 0.11303) (xy 0.21209 0.12319) (xy 0.20701 0.13335) (xy 0.2032 0.14224) (xy 0.19812 0.1524)
						(xy 0.17272 0.18796) (xy 0.1651 0.19558) (xy 0.1651 0.7366) (xy 0.16256 0.76835) (xy 0.1524 0.8001)
						(xy 0.13716 0.82804) (xy 0.11684 0.85344) (xy 0.09144 0.87376) (xy 0.0635 0.889) (xy 0.03175 0.89916)
					)
					(width 0)
					(fill yes)
				)
			)
		)
		(pad "73" smd custom
			(at -7.649972 4.106672 180)
			(size 0.1143 0.1143)
			(layers "F.Cu" "F.Mask" "F.Paste")
			(net "GND")
			(options
				(clearance outline)
				(anchor circle)
			)
			(primitives
				(gr_poly
					(pts
						(xy 0 0.9017) (xy -0.03175 0.89916) (xy -0.0635 0.889) (xy -0.09144 0.87376) (xy -0.11684 0.85344)
						(xy -0.13716 0.82804) (xy -0.1524 0.8001) (xy -0.16256 0.76835) (xy -0.1651 0.7366) (xy -0.1651 -0.13462)
						(xy -0.17272 -0.14224) (xy -0.19812 -0.1778) (xy -0.2032 -0.18796) (xy -0.20701 -0.19685) (xy -0.21209 -0.20701)
						(xy -0.2159 -0.21717) (xy -0.21844 -0.22733) (xy -0.22225 -0.23876) (xy -0.22352 -0.24892) (xy -0.22606 -0.25908)
						(xy -0.22733 -0.27051) (xy -0.22733 -0.28067) (xy -0.2286 -0.2921) (xy -0.22733 -0.30353) (xy -0.22733 -0.31369)
						(xy -0.22606 -0.32512) (xy -0.22352 -0.33528) (xy -0.22225 -0.34544) (xy -0.21844 -0.35687) (xy -0.2159 -0.36703)
						(xy -0.21209 -0.37719) (xy -0.20701 -0.38735) (xy -0.2032 -0.39624) (xy -0.19812 -0.4064) (xy -0.17272 -0.44196)
						(xy -0.1651 -0.44958) (xy -0.1651 -0.7366) (xy -0.16256 -0.76835) (xy -0.1524 -0.8001) (xy -0.13716 -0.82804)
						(xy -0.11684 -0.85344) (xy -0.09144 -0.87376) (xy -0.0635 -0.889) (xy -0.03175 -0.89916) (xy 0 -0.9017)
						(xy 0.03175 -0.89916) (xy 0.0635 -0.889) (xy 0.09144 -0.87376) (xy 0.11684 -0.85344) (xy 0.13716 -0.82804)
						(xy 0.1524 -0.8001) (xy 0.16256 -0.76835) (xy 0.1651 -0.7366) (xy 0.1651 -0.44958) (xy 0.17272 -0.44196)
						(xy 0.19812 -0.4064) (xy 0.2032 -0.39624) (xy 0.20701 -0.38735) (xy 0.21209 -0.37719) (xy 0.2159 -0.36703)
						(xy 0.21844 -0.35687) (xy 0.22225 -0.34544) (xy 0.22352 -0.33528) (xy 0.22606 -0.32512) (xy 0.22733 -0.31369)
						(xy 0.22733 -0.30353) (xy 0.2286 -0.2921) (xy 0.22733 -0.28067) (xy 0.22733 -0.27051) (xy 0.22606 -0.25908)
						(xy 0.22352 -0.24892) (xy 0.22225 -0.23876) (xy 0.21844 -0.22733) (xy 0.2159 -0.21717) (xy 0.21209 -0.20701)
						(xy 0.20701 -0.19685) (xy 0.2032 -0.18796) (xy 0.19812 -0.1778) (xy 0.17272 -0.14224) (xy 0.1651 -0.13462)
						(xy 0.1651 0.7366) (xy 0.16256 0.76835) (xy 0.1524 0.8001) (xy 0.13716 0.82804) (xy 0.11684 0.85344)
						(xy 0.09144 0.87376) (xy 0.0635 0.889) (xy 0.03175 0.89916)
					)
					(width 0)
					(fill yes)
				)
			)
		)
		(pad "74" smd custom
			(at -7.349998 -4.106672 180)
			(size 0.1143 0.1143)
			(layers "F.Cu" "F.Mask" "F.Paste")
			(net "M_A_ECC1")
			(options
				(clearance outline)
				(anchor circle)
			)
			(primitives
				(gr_poly
					(pts
						(xy 0 0.9017) (xy -0.03175 0.89916) (xy -0.0635 0.889) (xy -0.09144 0.87376) (xy -0.11684 0.85344)
						(xy -0.13716 0.82804) (xy -0.1524 0.8001) (xy -0.16256 0.76835) (xy -0.1651 0.7366) (xy -0.1651 0.44958)
						(xy -0.17272 0.44196) (xy -0.19812 0.4064) (xy -0.2032 0.39624) (xy -0.20701 0.38735) (xy -0.21209 0.37719)
						(xy -0.2159 0.36703) (xy -0.21844 0.35687) (xy -0.22225 0.34544) (xy -0.22352 0.33528) (xy -0.22606 0.32512)
						(xy -0.22733 0.31369) (xy -0.22733 0.30353) (xy -0.2286 0.2921) (xy -0.22733 0.28067) (xy -0.22733 0.27051)
						(xy -0.22606 0.25908) (xy -0.22352 0.24892) (xy -0.22225 0.23876) (xy -0.21844 0.22733) (xy -0.2159 0.21717)
						(xy -0.21209 0.20701) (xy -0.20701 0.19685) (xy -0.2032 0.18796) (xy -0.19812 0.1778) (xy -0.17272 0.14224)
						(xy -0.1651 0.13462) (xy -0.1651 -0.7366) (xy -0.16256 -0.76835) (xy -0.1524 -0.8001) (xy -0.13716 -0.82804)
						(xy -0.11684 -0.85344) (xy -0.09144 -0.87376) (xy -0.0635 -0.889) (xy -0.03175 -0.89916) (xy 0 -0.9017)
						(xy 0.03175 -0.89916) (xy 0.0635 -0.889) (xy 0.09144 -0.87376) (xy 0.11684 -0.85344) (xy 0.13716 -0.82804)
						(xy 0.1524 -0.8001) (xy 0.16256 -0.76835) (xy 0.1651 -0.7366) (xy 0.1651 0.13462) (xy 0.17272 0.14224)
						(xy 0.19812 0.1778) (xy 0.2032 0.18796) (xy 0.20701 0.19685) (xy 0.21209 0.20701) (xy 0.2159 0.21717)
						(xy 0.21844 0.22733) (xy 0.22225 0.23876) (xy 0.22352 0.24892) (xy 0.22606 0.25908) (xy 0.22733 0.27051)
						(xy 0.22733 0.28067) (xy 0.2286 0.2921) (xy 0.22733 0.30353) (xy 0.22733 0.31369) (xy 0.22606 0.32512)
						(xy 0.22352 0.33528) (xy 0.22225 0.34544) (xy 0.21844 0.35687) (xy 0.2159 0.36703) (xy 0.21209 0.37719)
						(xy 0.20701 0.38735) (xy 0.2032 0.39624) (xy 0.19812 0.4064) (xy 0.17272 0.44196) (xy 0.1651 0.44958)
						(xy 0.1651 0.7366) (xy 0.16256 0.76835) (xy 0.1524 0.8001) (xy 0.13716 0.82804) (xy 0.11684 0.85344)
						(xy 0.09144 0.87376) (xy 0.0635 0.889) (xy 0.03175 0.89916)
					)
					(width 0)
					(fill yes)
				)
			)
		)
		(pad "75" smd custom
			(at -7.050024 4.106672 180)
			(size 0.1143 0.1143)
			(layers "F.Cu" "F.Mask" "F.Paste")
			(net "M_A_DQS_DN8")
			(options
				(clearance outline)
				(anchor circle)
			)
			(primitives
				(gr_poly
					(pts
						(xy 0 0.9017) (xy -0.03175 0.89916) (xy -0.0635 0.889) (xy -0.09144 0.87376) (xy -0.11684 0.85344)
						(xy -0.13716 0.82804) (xy -0.1524 0.8001) (xy -0.16256 0.76835) (xy -0.1651 0.7366) (xy -0.1651 0.11938)
						(xy -0.17272 0.11176) (xy -0.19812 0.0762) (xy -0.2032 0.06604) (xy -0.20701 0.05715) (xy -0.21209 0.04699)
						(xy -0.2159 0.03683) (xy -0.21844 0.02667) (xy -0.22225 0.01524) (xy -0.22352 0.00508) (xy -0.22606 -0.00508)
						(xy -0.22733 -0.01651) (xy -0.22733 -0.02667) (xy -0.2286 -0.0381) (xy -0.22733 -0.04953) (xy -0.22733 -0.05969)
						(xy -0.22606 -0.07112) (xy -0.22352 -0.08128) (xy -0.22225 -0.09144) (xy -0.21844 -0.10287) (xy -0.2159 -0.11303)
						(xy -0.21209 -0.12319) (xy -0.20701 -0.13335) (xy -0.2032 -0.14224) (xy -0.19812 -0.1524) (xy -0.17272 -0.18796)
						(xy -0.1651 -0.19558) (xy -0.1651 -0.7366) (xy -0.16256 -0.76835) (xy -0.1524 -0.8001) (xy -0.13716 -0.82804)
						(xy -0.11684 -0.85344) (xy -0.09144 -0.87376) (xy -0.0635 -0.889) (xy -0.03175 -0.89916) (xy 0 -0.9017)
						(xy 0.03175 -0.89916) (xy 0.0635 -0.889) (xy 0.09144 -0.87376) (xy 0.11684 -0.85344) (xy 0.13716 -0.82804)
						(xy 0.1524 -0.8001) (xy 0.16256 -0.76835) (xy 0.1651 -0.7366) (xy 0.1651 -0.19685) (xy 0.17272 -0.18923)
						(xy 0.17907 -0.18034) (xy 0.18669 -0.17145) (xy 0.19177 -0.16256) (xy 0.19812 -0.15367) (xy 0.20828 -0.13335)
						(xy 0.21971 -0.10287) (xy 0.22225 -0.09271) (xy 0.22479 -0.08128) (xy 0.22606 -0.07112) (xy 0.2286 -0.05969)
						(xy 0.2286 -0.01651) (xy 0.22606 -0.00508) (xy 0.22479 0.00508) (xy 0.22225 0.01651) (xy 0.21971 0.02667)
						(xy 0.20828 0.05715) (xy 0.19812 0.07747) (xy 0.19177 0.08636) (xy 0.18669 0.09525) (xy 0.17907 0.10414)
						(xy 0.17272 0.11303) (xy 0.1651 0.12065) (xy 0.1651 0.7366) (xy 0.16256 0.76835) (xy 0.1524 0.8001)
						(xy 0.13716 0.82804) (xy 0.11684 0.85344) (xy 0.09144 0.87376) (xy 0.0635 0.889) (xy 0.03175 0.89916)
					)
					(width 0)
					(fill yes)
				)
			)
		)
		(pad "76" smd custom
			(at -6.75005 -4.106672 180)
			(size 0.1143 0.1143)
			(layers "F.Cu" "F.Mask" "F.Paste")
			(net "GND")
			(options
				(clearance outline)
				(anchor circle)
			)
			(primitives
				(gr_poly
					(pts
						(xy 0 0.9017) (xy -0.03175 0.89916) (xy -0.0635 0.889) (xy -0.09144 0.87376) (xy -0.11684 0.85344)
						(xy -0.13716 0.82804) (xy -0.1524 0.8001) (xy -0.16256 0.76835) (xy -0.1651 0.7366) (xy -0.1651 0.19685)
						(xy -0.17272 0.18923) (xy -0.17907 0.18034) (xy -0.18669 0.17145) (xy -0.19177 0.16256) (xy -0.19812 0.15367)
						(xy -0.20828 0.13335) (xy -0.21971 0.10287) (xy -0.22225 0.09271) (xy -0.22479 0.08128) (xy -0.22606 0.07112)
						(xy -0.2286 0.05969) (xy -0.2286 0.01651) (xy -0.22606 0.00508) (xy -0.22479 -0.00508) (xy -0.22225 -0.01651)
						(xy -0.21971 -0.02667) (xy -0.20828 -0.05715) (xy -0.19812 -0.07747) (xy -0.19177 -0.08636) (xy -0.18669 -0.09525)
						(xy -0.17907 -0.10414) (xy -0.17272 -0.11303) (xy -0.1651 -0.12065) (xy -0.1651 -0.7366) (xy -0.16256 -0.76835)
						(xy -0.1524 -0.8001) (xy -0.13716 -0.82804) (xy -0.11684 -0.85344) (xy -0.09144 -0.87376) (xy -0.0635 -0.889)
						(xy -0.03175 -0.89916) (xy 0 -0.9017) (xy 0.03175 -0.89916) (xy 0.0635 -0.889) (xy 0.09144 -0.87376)
						(xy 0.11684 -0.85344) (xy 0.13716 -0.82804) (xy 0.1524 -0.8001) (xy 0.16256 -0.76835) (xy 0.1651 -0.7366)
						(xy 0.1651 -0.11938) (xy 0.17272 -0.11176) (xy 0.19812 -0.0762) (xy 0.2032 -0.06604) (xy 0.20701 -0.05715)
						(xy 0.21209 -0.04699) (xy 0.2159 -0.03683) (xy 0.21844 -0.02667) (xy 0.22225 -0.01524) (xy 0.22352 -0.00508)
						(xy 0.22606 0.00508) (xy 0.22733 0.01651) (xy 0.22733 0.02667) (xy 0.2286 0.0381) (xy 0.22733 0.04953)
						(xy 0.22733 0.05969) (xy 0.22606 0.07112) (xy 0.22352 0.08128) (xy 0.22225 0.09144) (xy 0.21844 0.10287)
						(xy 0.2159 0.11303) (xy 0.21209 0.12319) (xy 0.20701 0.13335) (xy 0.2032 0.14224) (xy 0.19812 0.1524)
						(xy 0.17272 0.18796) (xy 0.1651 0.19558) (xy 0.1651 0.7366) (xy 0.16256 0.76835) (xy 0.1524 0.8001)
						(xy 0.13716 0.82804) (xy 0.11684 0.85344) (xy 0.09144 0.87376) (xy 0.0635 0.889) (xy 0.03175 0.89916)
					)
					(width 0)
					(fill yes)
				)
			)
		)
		(pad "77" smd custom
			(at -6.450076 4.106672 180)
			(size 0.1143 0.1143)
			(layers "F.Cu" "F.Mask" "F.Paste")
			(net "M_A_DQS_DP8")
			(options
				(clearance outline)
				(anchor circle)
			)
			(primitives
				(gr_poly
					(pts
						(xy 0 0.9017) (xy -0.03175 0.89916) (xy -0.0635 0.889) (xy -0.09144 0.87376) (xy -0.11684 0.85344)
						(xy -0.13716 0.82804) (xy -0.1524 0.8001) (xy -0.16256 0.76835) (xy -0.1651 0.7366) (xy -0.1651 -0.13462)
						(xy -0.17272 -0.14224) (xy -0.19812 -0.1778) (xy -0.2032 -0.18796) (xy -0.20701 -0.19685) (xy -0.21209 -0.20701)
						(xy -0.2159 -0.21717) (xy -0.21844 -0.22733) (xy -0.22225 -0.23876) (xy -0.22352 -0.24892) (xy -0.22606 -0.25908)
						(xy -0.22733 -0.27051) (xy -0.22733 -0.28067) (xy -0.2286 -0.2921) (xy -0.22733 -0.30353) (xy -0.22733 -0.31369)
						(xy -0.22606 -0.32512) (xy -0.22352 -0.33528) (xy -0.22225 -0.34544) (xy -0.21844 -0.35687) (xy -0.2159 -0.36703)
						(xy -0.21209 -0.37719) (xy -0.20701 -0.38735) (xy -0.2032 -0.39624) (xy -0.19812 -0.4064) (xy -0.17272 -0.44196)
						(xy -0.1651 -0.44958) (xy -0.1651 -0.7366) (xy -0.16256 -0.76835) (xy -0.1524 -0.8001) (xy -0.13716 -0.82804)
						(xy -0.11684 -0.85344) (xy -0.09144 -0.87376) (xy -0.0635 -0.889) (xy -0.03175 -0.89916) (xy 0 -0.9017)
						(xy 0.03175 -0.89916) (xy 0.0635 -0.889) (xy 0.09144 -0.87376) (xy 0.11684 -0.85344) (xy 0.13716 -0.82804)
						(xy 0.1524 -0.8001) (xy 0.16256 -0.76835) (xy 0.1651 -0.7366) (xy 0.1651 -0.44958) (xy 0.17272 -0.44196)
						(xy 0.19812 -0.4064) (xy 0.2032 -0.39624) (xy 0.20701 -0.38735) (xy 0.21209 -0.37719) (xy 0.2159 -0.36703)
						(xy 0.21844 -0.35687) (xy 0.22225 -0.34544) (xy 0.22352 -0.33528) (xy 0.22606 -0.32512) (xy 0.22733 -0.31369)
						(xy 0.22733 -0.30353) (xy 0.2286 -0.2921) (xy 0.22733 -0.28067) (xy 0.22733 -0.27051) (xy 0.22606 -0.25908)
						(xy 0.22352 -0.24892) (xy 0.22225 -0.23876) (xy 0.21844 -0.22733) (xy 0.2159 -0.21717) (xy 0.21209 -0.20701)
						(xy 0.20701 -0.19685) (xy 0.2032 -0.18796) (xy 0.19812 -0.1778) (xy 0.17272 -0.14224) (xy 0.1651 -0.13462)
						(xy 0.1651 0.7366) (xy 0.16256 0.76835) (xy 0.1524 0.8001) (xy 0.13716 0.82804) (xy 0.11684 0.85344)
						(xy 0.09144 0.87376) (xy 0.0635 0.889) (xy 0.03175 0.89916)
					)
					(width 0)
					(fill yes)
				)
			)
		)
		(pad "78" smd custom
			(at -6.150102 -4.106672 180)
			(size 0.1143 0.1143)
			(layers "F.Cu" "F.Mask" "F.Paste")
			(net "GND")
			(options
				(clearance outline)
				(anchor circle)
			)
			(primitives
				(gr_poly
					(pts
						(xy 0 0.9017) (xy -0.03175 0.89916) (xy -0.0635 0.889) (xy -0.09144 0.87376) (xy -0.11684 0.85344)
						(xy -0.13716 0.82804) (xy -0.1524 0.8001) (xy -0.16256 0.76835) (xy -0.1651 0.7366) (xy -0.1651 0.44958)
						(xy -0.17272 0.44196) (xy -0.19812 0.4064) (xy -0.2032 0.39624) (xy -0.20701 0.38735) (xy -0.21209 0.37719)
						(xy -0.2159 0.36703) (xy -0.21844 0.35687) (xy -0.22225 0.34544) (xy -0.22352 0.33528) (xy -0.22606 0.32512)
						(xy -0.22733 0.31369) (xy -0.22733 0.30353) (xy -0.2286 0.2921) (xy -0.22733 0.28067) (xy -0.22733 0.27051)
						(xy -0.22606 0.25908) (xy -0.22352 0.24892) (xy -0.22225 0.23876) (xy -0.21844 0.22733) (xy -0.2159 0.21717)
						(xy -0.21209 0.20701) (xy -0.20701 0.19685) (xy -0.2032 0.18796) (xy -0.19812 0.1778) (xy -0.17272 0.14224)
						(xy -0.1651 0.13462) (xy -0.1651 -0.7366) (xy -0.16256 -0.76835) (xy -0.1524 -0.8001) (xy -0.13716 -0.82804)
						(xy -0.11684 -0.85344) (xy -0.09144 -0.87376) (xy -0.0635 -0.889) (xy -0.03175 -0.89916) (xy 0 -0.9017)
						(xy 0.03175 -0.89916) (xy 0.0635 -0.889) (xy 0.09144 -0.87376) (xy 0.11684 -0.85344) (xy 0.13716 -0.82804)
						(xy 0.1524 -0.8001) (xy 0.16256 -0.76835) (xy 0.1651 -0.7366) (xy 0.1651 0.13462) (xy 0.17272 0.14224)
						(xy 0.19812 0.1778) (xy 0.2032 0.18796) (xy 0.20701 0.19685) (xy 0.21209 0.20701) (xy 0.2159 0.21717)
						(xy 0.21844 0.22733) (xy 0.22225 0.23876) (xy 0.22352 0.24892) (xy 0.22606 0.25908) (xy 0.22733 0.27051)
						(xy 0.22733 0.28067) (xy 0.2286 0.2921) (xy 0.22733 0.30353) (xy 0.22733 0.31369) (xy 0.22606 0.32512)
						(xy 0.22352 0.33528) (xy 0.22225 0.34544) (xy 0.21844 0.35687) (xy 0.2159 0.36703) (xy 0.21209 0.37719)
						(xy 0.20701 0.38735) (xy 0.2032 0.39624) (xy 0.19812 0.4064) (xy 0.17272 0.44196) (xy 0.1651 0.44958)
						(xy 0.1651 0.7366) (xy 0.16256 0.76835) (xy 0.1524 0.8001) (xy 0.13716 0.82804) (xy 0.11684 0.85344)
						(xy 0.09144 0.87376) (xy 0.0635 0.889) (xy 0.03175 0.89916)
					)
					(width 0)
					(fill yes)
				)
			)
		)
		(pad "79" smd custom
			(at -5.849874 4.106672 180)
			(size 0.1143 0.1143)
			(layers "F.Cu" "F.Mask" "F.Paste")
			(net "GND")
			(options
				(clearance outline)
				(anchor circle)
			)
			(primitives
				(gr_poly
					(pts
						(xy 0 0.9017) (xy -0.03175 0.89916) (xy -0.0635 0.889) (xy -0.09144 0.87376) (xy -0.11684 0.85344)
						(xy -0.13716 0.82804) (xy -0.1524 0.8001) (xy -0.16256 0.76835) (xy -0.1651 0.7366) (xy -0.1651 0.11938)
						(xy -0.17272 0.11176) (xy -0.19812 0.0762) (xy -0.2032 0.06604) (xy -0.20701 0.05715) (xy -0.21209 0.04699)
						(xy -0.2159 0.03683) (xy -0.21844 0.02667) (xy -0.22225 0.01524) (xy -0.22352 0.00508) (xy -0.22606 -0.00508)
						(xy -0.22733 -0.01651) (xy -0.22733 -0.02667) (xy -0.2286 -0.0381) (xy -0.22733 -0.04953) (xy -0.22733 -0.05969)
						(xy -0.22606 -0.07112) (xy -0.22352 -0.08128) (xy -0.22225 -0.09144) (xy -0.21844 -0.10287) (xy -0.2159 -0.11303)
						(xy -0.21209 -0.12319) (xy -0.20701 -0.13335) (xy -0.2032 -0.14224) (xy -0.19812 -0.1524) (xy -0.17272 -0.18796)
						(xy -0.1651 -0.19558) (xy -0.1651 -0.7366) (xy -0.16256 -0.76835) (xy -0.1524 -0.8001) (xy -0.13716 -0.82804)
						(xy -0.11684 -0.85344) (xy -0.09144 -0.87376) (xy -0.0635 -0.889) (xy -0.03175 -0.89916) (xy 0 -0.9017)
						(xy 0.03175 -0.89916) (xy 0.0635 -0.889) (xy 0.09144 -0.87376) (xy 0.11684 -0.85344) (xy 0.13716 -0.82804)
						(xy 0.1524 -0.8001) (xy 0.16256 -0.76835) (xy 0.1651 -0.7366) (xy 0.1651 -0.19685) (xy 0.17272 -0.18923)
						(xy 0.17907 -0.18034) (xy 0.18669 -0.17145) (xy 0.19177 -0.16256) (xy 0.19812 -0.15367) (xy 0.20828 -0.13335)
						(xy 0.21971 -0.10287) (xy 0.22225 -0.09271) (xy 0.22479 -0.08128) (xy 0.22606 -0.07112) (xy 0.2286 -0.05969)
						(xy 0.2286 -0.01651) (xy 0.22606 -0.00508) (xy 0.22479 0.00508) (xy 0.22225 0.01651) (xy 0.21971 0.02667)
						(xy 0.20828 0.05715) (xy 0.19812 0.07747) (xy 0.19177 0.08636) (xy 0.18669 0.09525) (xy 0.17907 0.10414)
						(xy 0.17272 0.11303) (xy 0.1651 0.12065) (xy 0.1651 0.7366) (xy 0.16256 0.76835) (xy 0.1524 0.8001)
						(xy 0.13716 0.82804) (xy 0.11684 0.85344) (xy 0.09144 0.87376) (xy 0.0635 0.889) (xy 0.03175 0.89916)
					)
					(width 0)
					(fill yes)
				)
			)
		)
		(pad "80" smd custom
			(at -5.5499 -4.106672 180)
			(size 0.1143 0.1143)
			(layers "F.Cu" "F.Mask" "F.Paste")
			(net "M_A_ECC2")
			(options
				(clearance outline)
				(anchor circle)
			)
			(primitives
				(gr_poly
					(pts
						(xy 0 0.9017) (xy -0.03175 0.89916) (xy -0.0635 0.889) (xy -0.09144 0.87376) (xy -0.11684 0.85344)
						(xy -0.13716 0.82804) (xy -0.1524 0.8001) (xy -0.16256 0.76835) (xy -0.1651 0.7366) (xy -0.1651 0.19685)
						(xy -0.17272 0.18923) (xy -0.17907 0.18034) (xy -0.18669 0.17145) (xy -0.19177 0.16256) (xy -0.19812 0.15367)
						(xy -0.20828 0.13335) (xy -0.21971 0.10287) (xy -0.22225 0.09271) (xy -0.22479 0.08128) (xy -0.22606 0.07112)
						(xy -0.2286 0.05969) (xy -0.2286 0.01651) (xy -0.22606 0.00508) (xy -0.22479 -0.00508) (xy -0.22225 -0.01651)
						(xy -0.21971 -0.02667) (xy -0.20828 -0.05715) (xy -0.19812 -0.07747) (xy -0.19177 -0.08636) (xy -0.18669 -0.09525)
						(xy -0.17907 -0.10414) (xy -0.17272 -0.11303) (xy -0.1651 -0.12065) (xy -0.1651 -0.7366) (xy -0.16256 -0.76835)
						(xy -0.1524 -0.8001) (xy -0.13716 -0.82804) (xy -0.11684 -0.85344) (xy -0.09144 -0.87376) (xy -0.0635 -0.889)
						(xy -0.03175 -0.89916) (xy 0 -0.9017) (xy 0.03175 -0.89916) (xy 0.0635 -0.889) (xy 0.09144 -0.87376)
						(xy 0.11684 -0.85344) (xy 0.13716 -0.82804) (xy 0.1524 -0.8001) (xy 0.16256 -0.76835) (xy 0.1651 -0.7366)
						(xy 0.1651 -0.11938) (xy 0.17272 -0.11176) (xy 0.19812 -0.0762) (xy 0.2032 -0.06604) (xy 0.20701 -0.05715)
						(xy 0.21209 -0.04699) (xy 0.2159 -0.03683) (xy 0.21844 -0.02667) (xy 0.22225 -0.01524) (xy 0.22352 -0.00508)
						(xy 0.22606 0.00508) (xy 0.22733 0.01651) (xy 0.22733 0.02667) (xy 0.2286 0.0381) (xy 0.22733 0.04953)
						(xy 0.22733 0.05969) (xy 0.22606 0.07112) (xy 0.22352 0.08128) (xy 0.22225 0.09144) (xy 0.21844 0.10287)
						(xy 0.2159 0.11303) (xy 0.21209 0.12319) (xy 0.20701 0.13335) (xy 0.2032 0.14224) (xy 0.19812 0.1524)
						(xy 0.17272 0.18796) (xy 0.1651 0.19558) (xy 0.1651 0.7366) (xy 0.16256 0.76835) (xy 0.1524 0.8001)
						(xy 0.13716 0.82804) (xy 0.11684 0.85344) (xy 0.09144 0.87376) (xy 0.0635 0.889) (xy 0.03175 0.89916)
					)
					(width 0)
					(fill yes)
				)
			)
		)
		(pad "81" smd custom
			(at -5.249926 4.106672 180)
			(size 0.1143 0.1143)
			(layers "F.Cu" "F.Mask" "F.Paste")
			(net "M_A_ECC6")
			(options
				(clearance outline)
				(anchor circle)
			)
			(primitives
				(gr_poly
					(pts
						(xy 0 0.9017) (xy -0.03175 0.89916) (xy -0.0635 0.889) (xy -0.09144 0.87376) (xy -0.11684 0.85344)
						(xy -0.13716 0.82804) (xy -0.1524 0.8001) (xy -0.16256 0.76835) (xy -0.1651 0.7366) (xy -0.1651 -0.13462)
						(xy -0.17272 -0.14224) (xy -0.19812 -0.1778) (xy -0.2032 -0.18796) (xy -0.20701 -0.19685) (xy -0.21209 -0.20701)
						(xy -0.2159 -0.21717) (xy -0.21844 -0.22733) (xy -0.22225 -0.23876) (xy -0.22352 -0.24892) (xy -0.22606 -0.25908)
						(xy -0.22733 -0.27051) (xy -0.22733 -0.28067) (xy -0.2286 -0.2921) (xy -0.22733 -0.30353) (xy -0.22733 -0.31369)
						(xy -0.22606 -0.32512) (xy -0.22352 -0.33528) (xy -0.22225 -0.34544) (xy -0.21844 -0.35687) (xy -0.2159 -0.36703)
						(xy -0.21209 -0.37719) (xy -0.20701 -0.38735) (xy -0.2032 -0.39624) (xy -0.19812 -0.4064) (xy -0.17272 -0.44196)
						(xy -0.1651 -0.44958) (xy -0.1651 -0.7366) (xy -0.16256 -0.76835) (xy -0.1524 -0.8001) (xy -0.13716 -0.82804)
						(xy -0.11684 -0.85344) (xy -0.09144 -0.87376) (xy -0.0635 -0.889) (xy -0.03175 -0.89916) (xy 0 -0.9017)
						(xy 0.03175 -0.89916) (xy 0.0635 -0.889) (xy 0.09144 -0.87376) (xy 0.11684 -0.85344) (xy 0.13716 -0.82804)
						(xy 0.1524 -0.8001) (xy 0.16256 -0.76835) (xy 0.1651 -0.7366) (xy 0.1651 -0.44958) (xy 0.17272 -0.44196)
						(xy 0.19812 -0.4064) (xy 0.2032 -0.39624) (xy 0.20701 -0.38735) (xy 0.21209 -0.37719) (xy 0.2159 -0.36703)
						(xy 0.21844 -0.35687) (xy 0.22225 -0.34544) (xy 0.22352 -0.33528) (xy 0.22606 -0.32512) (xy 0.22733 -0.31369)
						(xy 0.22733 -0.30353) (xy 0.2286 -0.2921) (xy 0.22733 -0.28067) (xy 0.22733 -0.27051) (xy 0.22606 -0.25908)
						(xy 0.22352 -0.24892) (xy 0.22225 -0.23876) (xy 0.21844 -0.22733) (xy 0.2159 -0.21717) (xy 0.21209 -0.20701)
						(xy 0.20701 -0.19685) (xy 0.2032 -0.18796) (xy 0.19812 -0.1778) (xy 0.17272 -0.14224) (xy 0.1651 -0.13462)
						(xy 0.1651 0.7366) (xy 0.16256 0.76835) (xy 0.1524 0.8001) (xy 0.13716 0.82804) (xy 0.11684 0.85344)
						(xy 0.09144 0.87376) (xy 0.0635 0.889) (xy 0.03175 0.89916)
					)
					(width 0)
					(fill yes)
				)
			)
		)
		(pad "82" smd custom
			(at -4.949952 -4.106672 180)
			(size 0.1143 0.1143)
			(layers "F.Cu" "F.Mask" "F.Paste")
			(net "M_A_ECC3")
			(options
				(clearance outline)
				(anchor circle)
			)
			(primitives
				(gr_poly
					(pts
						(xy 0 0.9017) (xy -0.03175 0.89916) (xy -0.0635 0.889) (xy -0.09144 0.87376) (xy -0.11684 0.85344)
						(xy -0.13716 0.82804) (xy -0.1524 0.8001) (xy -0.16256 0.76835) (xy -0.1651 0.7366) (xy -0.1651 0.44958)
						(xy -0.17272 0.44196) (xy -0.19812 0.4064) (xy -0.2032 0.39624) (xy -0.20701 0.38735) (xy -0.21209 0.37719)
						(xy -0.2159 0.36703) (xy -0.21844 0.35687) (xy -0.22225 0.34544) (xy -0.22352 0.33528) (xy -0.22606 0.32512)
						(xy -0.22733 0.31369) (xy -0.22733 0.30353) (xy -0.2286 0.2921) (xy -0.22733 0.28067) (xy -0.22733 0.27051)
						(xy -0.22606 0.25908) (xy -0.22352 0.24892) (xy -0.22225 0.23876) (xy -0.21844 0.22733) (xy -0.2159 0.21717)
						(xy -0.21209 0.20701) (xy -0.20701 0.19685) (xy -0.2032 0.18796) (xy -0.19812 0.1778) (xy -0.17272 0.14224)
						(xy -0.1651 0.13462) (xy -0.1651 -0.7366) (xy -0.16256 -0.76835) (xy -0.1524 -0.8001) (xy -0.13716 -0.82804)
						(xy -0.11684 -0.85344) (xy -0.09144 -0.87376) (xy -0.0635 -0.889) (xy -0.03175 -0.89916) (xy 0 -0.9017)
						(xy 0.03175 -0.89916) (xy 0.0635 -0.889) (xy 0.09144 -0.87376) (xy 0.11684 -0.85344) (xy 0.13716 -0.82804)
						(xy 0.1524 -0.8001) (xy 0.16256 -0.76835) (xy 0.1651 -0.7366) (xy 0.1651 0.13462) (xy 0.17272 0.14224)
						(xy 0.19812 0.1778) (xy 0.2032 0.18796) (xy 0.20701 0.19685) (xy 0.21209 0.20701) (xy 0.2159 0.21717)
						(xy 0.21844 0.22733) (xy 0.22225 0.23876) (xy 0.22352 0.24892) (xy 0.22606 0.25908) (xy 0.22733 0.27051)
						(xy 0.22733 0.28067) (xy 0.2286 0.2921) (xy 0.22733 0.30353) (xy 0.22733 0.31369) (xy 0.22606 0.32512)
						(xy 0.22352 0.33528) (xy 0.22225 0.34544) (xy 0.21844 0.35687) (xy 0.2159 0.36703) (xy 0.21209 0.37719)
						(xy 0.20701 0.38735) (xy 0.2032 0.39624) (xy 0.19812 0.4064) (xy 0.17272 0.44196) (xy 0.1651 0.44958)
						(xy 0.1651 0.7366) (xy 0.16256 0.76835) (xy 0.1524 0.8001) (xy 0.13716 0.82804) (xy 0.11684 0.85344)
						(xy 0.09144 0.87376) (xy 0.0635 0.889) (xy 0.03175 0.89916)
					)
					(width 0)
					(fill yes)
				)
			)
		)
		(pad "83" smd custom
			(at -4.649978 4.106672 180)
			(size 0.1143 0.1143)
			(layers "F.Cu" "F.Mask" "F.Paste")
			(net "M_A_ECC7")
			(options
				(clearance outline)
				(anchor circle)
			)
			(primitives
				(gr_poly
					(pts
						(xy 0 0.9017) (xy -0.03175 0.89916) (xy -0.0635 0.889) (xy -0.09144 0.87376) (xy -0.11684 0.85344)
						(xy -0.13716 0.82804) (xy -0.1524 0.8001) (xy -0.16256 0.76835) (xy -0.1651 0.7366) (xy -0.1651 0.11938)
						(xy -0.17272 0.11176) (xy -0.19812 0.0762) (xy -0.2032 0.06604) (xy -0.20701 0.05715) (xy -0.21209 0.04699)
						(xy -0.2159 0.03683) (xy -0.21844 0.02667) (xy -0.22225 0.01524) (xy -0.22352 0.00508) (xy -0.22606 -0.00508)
						(xy -0.22733 -0.01651) (xy -0.22733 -0.02667) (xy -0.2286 -0.0381) (xy -0.22733 -0.04953) (xy -0.22733 -0.05969)
						(xy -0.22606 -0.07112) (xy -0.22352 -0.08128) (xy -0.22225 -0.09144) (xy -0.21844 -0.10287) (xy -0.2159 -0.11303)
						(xy -0.21209 -0.12319) (xy -0.20701 -0.13335) (xy -0.2032 -0.14224) (xy -0.19812 -0.1524) (xy -0.17272 -0.18796)
						(xy -0.1651 -0.19558) (xy -0.1651 -0.7366) (xy -0.16256 -0.76835) (xy -0.1524 -0.8001) (xy -0.13716 -0.82804)
						(xy -0.11684 -0.85344) (xy -0.09144 -0.87376) (xy -0.0635 -0.889) (xy -0.03175 -0.89916) (xy 0 -0.9017)
						(xy 0.03175 -0.89916) (xy 0.0635 -0.889) (xy 0.09144 -0.87376) (xy 0.11684 -0.85344) (xy 0.13716 -0.82804)
						(xy 0.1524 -0.8001) (xy 0.16256 -0.76835) (xy 0.1651 -0.7366) (xy 0.1651 -0.19685) (xy 0.17272 -0.18923)
						(xy 0.17907 -0.18034) (xy 0.18669 -0.17145) (xy 0.19177 -0.16256) (xy 0.19812 -0.15367) (xy 0.20828 -0.13335)
						(xy 0.21971 -0.10287) (xy 0.22225 -0.09271) (xy 0.22479 -0.08128) (xy 0.22606 -0.07112) (xy 0.2286 -0.05969)
						(xy 0.2286 -0.01651) (xy 0.22606 -0.00508) (xy 0.22479 0.00508) (xy 0.22225 0.01651) (xy 0.21971 0.02667)
						(xy 0.20828 0.05715) (xy 0.19812 0.07747) (xy 0.19177 0.08636) (xy 0.18669 0.09525) (xy 0.17907 0.10414)
						(xy 0.17272 0.11303) (xy 0.1651 0.12065) (xy 0.1651 0.7366) (xy 0.16256 0.76835) (xy 0.1524 0.8001)
						(xy 0.13716 0.82804) (xy 0.11684 0.85344) (xy 0.09144 0.87376) (xy 0.0635 0.889) (xy 0.03175 0.89916)
					)
					(width 0)
					(fill yes)
				)
			)
		)
		(pad "84" smd custom
			(at -4.350004 -4.106672 180)
			(size 0.1143 0.1143)
			(layers "F.Cu" "F.Mask" "F.Paste")
			(net "DDR3_M_A_VREF_CA")
			(options
				(clearance outline)
				(anchor circle)
			)
			(primitives
				(gr_poly
					(pts
						(xy 0 0.9017) (xy -0.03175 0.89916) (xy -0.0635 0.889) (xy -0.09144 0.87376) (xy -0.11684 0.85344)
						(xy -0.13716 0.82804) (xy -0.1524 0.8001) (xy -0.16256 0.76835) (xy -0.1651 0.7366) (xy -0.1651 0.19685)
						(xy -0.17272 0.18923) (xy -0.17907 0.18034) (xy -0.18669 0.17145) (xy -0.19177 0.16256) (xy -0.19812 0.15367)
						(xy -0.20828 0.13335) (xy -0.21971 0.10287) (xy -0.22225 0.09271) (xy -0.22479 0.08128) (xy -0.22606 0.07112)
						(xy -0.2286 0.05969) (xy -0.2286 0.01651) (xy -0.22606 0.00508) (xy -0.22479 -0.00508) (xy -0.22225 -0.01651)
						(xy -0.21971 -0.02667) (xy -0.20828 -0.05715) (xy -0.19812 -0.07747) (xy -0.19177 -0.08636) (xy -0.18669 -0.09525)
						(xy -0.17907 -0.10414) (xy -0.17272 -0.11303) (xy -0.1651 -0.12065) (xy -0.1651 -0.7366) (xy -0.16256 -0.76835)
						(xy -0.1524 -0.8001) (xy -0.13716 -0.82804) (xy -0.11684 -0.85344) (xy -0.09144 -0.87376) (xy -0.0635 -0.889)
						(xy -0.03175 -0.89916) (xy 0 -0.9017) (xy 0.03175 -0.89916) (xy 0.0635 -0.889) (xy 0.09144 -0.87376)
						(xy 0.11684 -0.85344) (xy 0.13716 -0.82804) (xy 0.1524 -0.8001) (xy 0.16256 -0.76835) (xy 0.1651 -0.7366)
						(xy 0.1651 -0.11938) (xy 0.17272 -0.11176) (xy 0.19812 -0.0762) (xy 0.2032 -0.06604) (xy 0.20701 -0.05715)
						(xy 0.21209 -0.04699) (xy 0.2159 -0.03683) (xy 0.21844 -0.02667) (xy 0.22225 -0.01524) (xy 0.22352 -0.00508)
						(xy 0.22606 0.00508) (xy 0.22733 0.01651) (xy 0.22733 0.02667) (xy 0.2286 0.0381) (xy 0.22733 0.04953)
						(xy 0.22733 0.05969) (xy 0.22606 0.07112) (xy 0.22352 0.08128) (xy 0.22225 0.09144) (xy 0.21844 0.10287)
						(xy 0.2159 0.11303) (xy 0.21209 0.12319) (xy 0.20701 0.13335) (xy 0.2032 0.14224) (xy 0.19812 0.1524)
						(xy 0.17272 0.18796) (xy 0.1651 0.19558) (xy 0.1651 0.7366) (xy 0.16256 0.76835) (xy 0.1524 0.8001)
						(xy 0.13716 0.82804) (xy 0.11684 0.85344) (xy 0.09144 0.87376) (xy 0.0635 0.889) (xy 0.03175 0.89916)
					)
					(width 0)
					(fill yes)
				)
			)
		)
		(pad "85" smd custom
			(at -4.05003 4.106672 180)
			(size 0.1143 0.1143)
			(layers "F.Cu" "F.Mask" "F.Paste")
			(net "PV_VDDR")
			(options
				(clearance outline)
				(anchor circle)
			)
			(primitives
				(gr_poly
					(pts
						(xy 0 0.9017) (xy -0.03175 0.89916) (xy -0.0635 0.889) (xy -0.09144 0.87376) (xy -0.11684 0.85344)
						(xy -0.13716 0.82804) (xy -0.1524 0.8001) (xy -0.16256 0.76835) (xy -0.1651 0.7366) (xy -0.1651 -0.13462)
						(xy -0.17272 -0.14224) (xy -0.19812 -0.1778) (xy -0.2032 -0.18796) (xy -0.20701 -0.19685) (xy -0.21209 -0.20701)
						(xy -0.2159 -0.21717) (xy -0.21844 -0.22733) (xy -0.22225 -0.23876) (xy -0.22352 -0.24892) (xy -0.22606 -0.25908)
						(xy -0.22733 -0.27051) (xy -0.22733 -0.28067) (xy -0.2286 -0.2921) (xy -0.22733 -0.30353) (xy -0.22733 -0.31369)
						(xy -0.22606 -0.32512) (xy -0.22352 -0.33528) (xy -0.22225 -0.34544) (xy -0.21844 -0.35687) (xy -0.2159 -0.36703)
						(xy -0.21209 -0.37719) (xy -0.20701 -0.38735) (xy -0.2032 -0.39624) (xy -0.19812 -0.4064) (xy -0.17272 -0.44196)
						(xy -0.1651 -0.44958) (xy -0.1651 -0.7366) (xy -0.16256 -0.76835) (xy -0.1524 -0.8001) (xy -0.13716 -0.82804)
						(xy -0.11684 -0.85344) (xy -0.09144 -0.87376) (xy -0.0635 -0.889) (xy -0.03175 -0.89916) (xy 0 -0.9017)
						(xy 0.03175 -0.89916) (xy 0.0635 -0.889) (xy 0.09144 -0.87376) (xy 0.11684 -0.85344) (xy 0.13716 -0.82804)
						(xy 0.1524 -0.8001) (xy 0.16256 -0.76835) (xy 0.1651 -0.7366) (xy 0.1651 -0.44958) (xy 0.17272 -0.44196)
						(xy 0.19812 -0.4064) (xy 0.2032 -0.39624) (xy 0.20701 -0.38735) (xy 0.21209 -0.37719) (xy 0.2159 -0.36703)
						(xy 0.21844 -0.35687) (xy 0.22225 -0.34544) (xy 0.22352 -0.33528) (xy 0.22606 -0.32512) (xy 0.22733 -0.31369)
						(xy 0.22733 -0.30353) (xy 0.2286 -0.2921) (xy 0.22733 -0.28067) (xy 0.22733 -0.27051) (xy 0.22606 -0.25908)
						(xy 0.22352 -0.24892) (xy 0.22225 -0.23876) (xy 0.21844 -0.22733) (xy 0.2159 -0.21717) (xy 0.21209 -0.20701)
						(xy 0.20701 -0.19685) (xy 0.2032 -0.18796) (xy 0.19812 -0.1778) (xy 0.17272 -0.14224) (xy 0.1651 -0.13462)
						(xy 0.1651 0.7366) (xy 0.16256 0.76835) (xy 0.1524 0.8001) (xy 0.13716 0.82804) (xy 0.11684 0.85344)
						(xy 0.09144 0.87376) (xy 0.0635 0.889) (xy 0.03175 0.89916)
					)
					(width 0)
					(fill yes)
				)
			)
		)
		(pad "86" smd custom
			(at -3.750056 -4.106672 180)
			(size 0.1143 0.1143)
			(layers "F.Cu" "F.Mask" "F.Paste")
			(net "PV_VDDR")
			(options
				(clearance outline)
				(anchor circle)
			)
			(primitives
				(gr_poly
					(pts
						(xy 0 0.9017) (xy -0.03175 0.89916) (xy -0.0635 0.889) (xy -0.09144 0.87376) (xy -0.11684 0.85344)
						(xy -0.13716 0.82804) (xy -0.1524 0.8001) (xy -0.16256 0.76835) (xy -0.1651 0.7366) (xy -0.1651 0.44958)
						(xy -0.17272 0.44196) (xy -0.19812 0.4064) (xy -0.2032 0.39624) (xy -0.20701 0.38735) (xy -0.21209 0.37719)
						(xy -0.2159 0.36703) (xy -0.21844 0.35687) (xy -0.22225 0.34544) (xy -0.22352 0.33528) (xy -0.22606 0.32512)
						(xy -0.22733 0.31369) (xy -0.22733 0.30353) (xy -0.2286 0.2921) (xy -0.22733 0.28067) (xy -0.22733 0.27051)
						(xy -0.22606 0.25908) (xy -0.22352 0.24892) (xy -0.22225 0.23876) (xy -0.21844 0.22733) (xy -0.2159 0.21717)
						(xy -0.21209 0.20701) (xy -0.20701 0.19685) (xy -0.2032 0.18796) (xy -0.19812 0.1778) (xy -0.17272 0.14224)
						(xy -0.1651 0.13462) (xy -0.1651 -0.7366) (xy -0.16256 -0.76835) (xy -0.1524 -0.8001) (xy -0.13716 -0.82804)
						(xy -0.11684 -0.85344) (xy -0.09144 -0.87376) (xy -0.0635 -0.889) (xy -0.03175 -0.89916) (xy 0 -0.9017)
						(xy 0.03175 -0.89916) (xy 0.0635 -0.889) (xy 0.09144 -0.87376) (xy 0.11684 -0.85344) (xy 0.13716 -0.82804)
						(xy 0.1524 -0.8001) (xy 0.16256 -0.76835) (xy 0.1651 -0.7366) (xy 0.1651 0.13462) (xy 0.17272 0.14224)
						(xy 0.19812 0.1778) (xy 0.2032 0.18796) (xy 0.20701 0.19685) (xy 0.21209 0.20701) (xy 0.2159 0.21717)
						(xy 0.21844 0.22733) (xy 0.22225 0.23876) (xy 0.22352 0.24892) (xy 0.22606 0.25908) (xy 0.22733 0.27051)
						(xy 0.22733 0.28067) (xy 0.2286 0.2921) (xy 0.22733 0.30353) (xy 0.22733 0.31369) (xy 0.22606 0.32512)
						(xy 0.22352 0.33528) (xy 0.22225 0.34544) (xy 0.21844 0.35687) (xy 0.2159 0.36703) (xy 0.21209 0.37719)
						(xy 0.20701 0.38735) (xy 0.2032 0.39624) (xy 0.19812 0.4064) (xy 0.17272 0.44196) (xy 0.1651 0.44958)
						(xy 0.1651 0.7366) (xy 0.16256 0.76835) (xy 0.1524 0.8001) (xy 0.13716 0.82804) (xy 0.11684 0.85344)
						(xy 0.09144 0.87376) (xy 0.0635 0.889) (xy 0.03175 0.89916)
					)
					(width 0)
					(fill yes)
				)
			)
		)
		(pad "87" smd custom
			(at -3.450082 4.106672 180)
			(size 0.1143 0.1143)
			(layers "F.Cu" "F.Mask" "F.Paste")
			(net "M_A_CKE2")
			(options
				(clearance outline)
				(anchor circle)
			)
			(primitives
				(gr_poly
					(pts
						(xy 0 0.9017) (xy -0.03175 0.89916) (xy -0.0635 0.889) (xy -0.09144 0.87376) (xy -0.11684 0.85344)
						(xy -0.13716 0.82804) (xy -0.1524 0.8001) (xy -0.16256 0.76835) (xy -0.1651 0.7366) (xy -0.1651 0.11938)
						(xy -0.17272 0.11176) (xy -0.19812 0.0762) (xy -0.2032 0.06604) (xy -0.20701 0.05715) (xy -0.21209 0.04699)
						(xy -0.2159 0.03683) (xy -0.21844 0.02667) (xy -0.22225 0.01524) (xy -0.22352 0.00508) (xy -0.22606 -0.00508)
						(xy -0.22733 -0.01651) (xy -0.22733 -0.02667) (xy -0.2286 -0.0381) (xy -0.22733 -0.04953) (xy -0.22733 -0.05969)
						(xy -0.22606 -0.07112) (xy -0.22352 -0.08128) (xy -0.22225 -0.09144) (xy -0.21844 -0.10287) (xy -0.2159 -0.11303)
						(xy -0.21209 -0.12319) (xy -0.20701 -0.13335) (xy -0.2032 -0.14224) (xy -0.19812 -0.1524) (xy -0.17272 -0.18796)
						(xy -0.1651 -0.19558) (xy -0.1651 -0.7366) (xy -0.16256 -0.76835) (xy -0.1524 -0.8001) (xy -0.13716 -0.82804)
						(xy -0.11684 -0.85344) (xy -0.09144 -0.87376) (xy -0.0635 -0.889) (xy -0.03175 -0.89916) (xy 0 -0.9017)
						(xy 0.03175 -0.89916) (xy 0.0635 -0.889) (xy 0.09144 -0.87376) (xy 0.11684 -0.85344) (xy 0.13716 -0.82804)
						(xy 0.1524 -0.8001) (xy 0.16256 -0.76835) (xy 0.1651 -0.7366) (xy 0.1651 -0.19685) (xy 0.17272 -0.18923)
						(xy 0.17907 -0.18034) (xy 0.18669 -0.17145) (xy 0.19177 -0.16256) (xy 0.19812 -0.15367) (xy 0.20828 -0.13335)
						(xy 0.21971 -0.10287) (xy 0.22225 -0.09271) (xy 0.22479 -0.08128) (xy 0.22606 -0.07112) (xy 0.2286 -0.05969)
						(xy 0.2286 -0.01651) (xy 0.22606 -0.00508) (xy 0.22479 0.00508) (xy 0.22225 0.01651) (xy 0.21971 0.02667)
						(xy 0.20828 0.05715) (xy 0.19812 0.07747) (xy 0.19177 0.08636) (xy 0.18669 0.09525) (xy 0.17907 0.10414)
						(xy 0.17272 0.11303) (xy 0.1651 0.12065) (xy 0.1651 0.7366) (xy 0.16256 0.76835) (xy 0.1524 0.8001)
						(xy 0.13716 0.82804) (xy 0.11684 0.85344) (xy 0.09144 0.87376) (xy 0.0635 0.889) (xy 0.03175 0.89916)
					)
					(width 0)
					(fill yes)
				)
			)
		)
		(pad "88" smd custom
			(at -3.150108 -4.106672 180)
			(size 0.1143 0.1143)
			(layers "F.Cu" "F.Mask" "F.Paste")
			(net "M_A_MA15")
			(options
				(clearance outline)
				(anchor circle)
			)
			(primitives
				(gr_poly
					(pts
						(xy 0 0.9017) (xy -0.03175 0.89916) (xy -0.0635 0.889) (xy -0.09144 0.87376) (xy -0.11684 0.85344)
						(xy -0.13716 0.82804) (xy -0.1524 0.8001) (xy -0.16256 0.76835) (xy -0.1651 0.7366) (xy -0.1651 0.19685)
						(xy -0.17272 0.18923) (xy -0.17907 0.18034) (xy -0.18669 0.17145) (xy -0.19177 0.16256) (xy -0.19812 0.15367)
						(xy -0.20828 0.13335) (xy -0.21971 0.10287) (xy -0.22225 0.09271) (xy -0.22479 0.08128) (xy -0.22606 0.07112)
						(xy -0.2286 0.05969) (xy -0.2286 0.01651) (xy -0.22606 0.00508) (xy -0.22479 -0.00508) (xy -0.22225 -0.01651)
						(xy -0.21971 -0.02667) (xy -0.20828 -0.05715) (xy -0.19812 -0.07747) (xy -0.19177 -0.08636) (xy -0.18669 -0.09525)
						(xy -0.17907 -0.10414) (xy -0.17272 -0.11303) (xy -0.1651 -0.12065) (xy -0.1651 -0.7366) (xy -0.16256 -0.76835)
						(xy -0.1524 -0.8001) (xy -0.13716 -0.82804) (xy -0.11684 -0.85344) (xy -0.09144 -0.87376) (xy -0.0635 -0.889)
						(xy -0.03175 -0.89916) (xy 0 -0.9017) (xy 0.03175 -0.89916) (xy 0.0635 -0.889) (xy 0.09144 -0.87376)
						(xy 0.11684 -0.85344) (xy 0.13716 -0.82804) (xy 0.1524 -0.8001) (xy 0.16256 -0.76835) (xy 0.1651 -0.7366)
						(xy 0.1651 -0.11938) (xy 0.17272 -0.11176) (xy 0.19812 -0.0762) (xy 0.2032 -0.06604) (xy 0.20701 -0.05715)
						(xy 0.21209 -0.04699) (xy 0.2159 -0.03683) (xy 0.21844 -0.02667) (xy 0.22225 -0.01524) (xy 0.22352 -0.00508)
						(xy 0.22606 0.00508) (xy 0.22733 0.01651) (xy 0.22733 0.02667) (xy 0.2286 0.0381) (xy 0.22733 0.04953)
						(xy 0.22733 0.05969) (xy 0.22606 0.07112) (xy 0.22352 0.08128) (xy 0.22225 0.09144) (xy 0.21844 0.10287)
						(xy 0.2159 0.11303) (xy 0.21209 0.12319) (xy 0.20701 0.13335) (xy 0.2032 0.14224) (xy 0.19812 0.1524)
						(xy 0.17272 0.18796) (xy 0.1651 0.19558) (xy 0.1651 0.7366) (xy 0.16256 0.76835) (xy 0.1524 0.8001)
						(xy 0.13716 0.82804) (xy 0.11684 0.85344) (xy 0.09144 0.87376) (xy 0.0635 0.889) (xy 0.03175 0.89916)
					)
					(width 0)
					(fill yes)
				)
			)
		)
		(pad "89" smd custom
			(at -2.84988 4.106672 180)
			(size 0.1143 0.1143)
			(layers "F.Cu" "F.Mask" "F.Paste")
			(net "M_A_CKE3")
			(options
				(clearance outline)
				(anchor circle)
			)
			(primitives
				(gr_poly
					(pts
						(xy 0 0.9017) (xy -0.03175 0.89916) (xy -0.0635 0.889) (xy -0.09144 0.87376) (xy -0.11684 0.85344)
						(xy -0.13716 0.82804) (xy -0.1524 0.8001) (xy -0.16256 0.76835) (xy -0.1651 0.7366) (xy -0.1651 -0.13462)
						(xy -0.17272 -0.14224) (xy -0.19812 -0.1778) (xy -0.2032 -0.18796) (xy -0.20701 -0.19685) (xy -0.21209 -0.20701)
						(xy -0.2159 -0.21717) (xy -0.21844 -0.22733) (xy -0.22225 -0.23876) (xy -0.22352 -0.24892) (xy -0.22606 -0.25908)
						(xy -0.22733 -0.27051) (xy -0.22733 -0.28067) (xy -0.2286 -0.2921) (xy -0.22733 -0.30353) (xy -0.22733 -0.31369)
						(xy -0.22606 -0.32512) (xy -0.22352 -0.33528) (xy -0.22225 -0.34544) (xy -0.21844 -0.35687) (xy -0.2159 -0.36703)
						(xy -0.21209 -0.37719) (xy -0.20701 -0.38735) (xy -0.2032 -0.39624) (xy -0.19812 -0.4064) (xy -0.17272 -0.44196)
						(xy -0.1651 -0.44958) (xy -0.1651 -0.7366) (xy -0.16256 -0.76835) (xy -0.1524 -0.8001) (xy -0.13716 -0.82804)
						(xy -0.11684 -0.85344) (xy -0.09144 -0.87376) (xy -0.0635 -0.889) (xy -0.03175 -0.89916) (xy 0 -0.9017)
						(xy 0.03175 -0.89916) (xy 0.0635 -0.889) (xy 0.09144 -0.87376) (xy 0.11684 -0.85344) (xy 0.13716 -0.82804)
						(xy 0.1524 -0.8001) (xy 0.16256 -0.76835) (xy 0.1651 -0.7366) (xy 0.1651 -0.44958) (xy 0.17272 -0.44196)
						(xy 0.19812 -0.4064) (xy 0.2032 -0.39624) (xy 0.20701 -0.38735) (xy 0.21209 -0.37719) (xy 0.2159 -0.36703)
						(xy 0.21844 -0.35687) (xy 0.22225 -0.34544) (xy 0.22352 -0.33528) (xy 0.22606 -0.32512) (xy 0.22733 -0.31369)
						(xy 0.22733 -0.30353) (xy 0.2286 -0.2921) (xy 0.22733 -0.28067) (xy 0.22733 -0.27051) (xy 0.22606 -0.25908)
						(xy 0.22352 -0.24892) (xy 0.22225 -0.23876) (xy 0.21844 -0.22733) (xy 0.2159 -0.21717) (xy 0.21209 -0.20701)
						(xy 0.20701 -0.19685) (xy 0.2032 -0.18796) (xy 0.19812 -0.1778) (xy 0.17272 -0.14224) (xy 0.1651 -0.13462)
						(xy 0.1651 0.7366) (xy 0.16256 0.76835) (xy 0.1524 0.8001) (xy 0.13716 0.82804) (xy 0.11684 0.85344)
						(xy 0.09144 0.87376) (xy 0.0635 0.889) (xy 0.03175 0.89916)
					)
					(width 0)
					(fill yes)
				)
			)
		)
		(pad "90" smd custom
			(at -2.549906 -4.106672 180)
			(size 0.1143 0.1143)
			(layers "F.Cu" "F.Mask" "F.Paste")
			(net "M_A_MA14")
			(options
				(clearance outline)
				(anchor circle)
			)
			(primitives
				(gr_poly
					(pts
						(xy 0 0.9017) (xy -0.03175 0.89916) (xy -0.0635 0.889) (xy -0.09144 0.87376) (xy -0.11684 0.85344)
						(xy -0.13716 0.82804) (xy -0.1524 0.8001) (xy -0.16256 0.76835) (xy -0.1651 0.7366) (xy -0.1651 0.44958)
						(xy -0.17272 0.44196) (xy -0.19812 0.4064) (xy -0.2032 0.39624) (xy -0.20701 0.38735) (xy -0.21209 0.37719)
						(xy -0.2159 0.36703) (xy -0.21844 0.35687) (xy -0.22225 0.34544) (xy -0.22352 0.33528) (xy -0.22606 0.32512)
						(xy -0.22733 0.31369) (xy -0.22733 0.30353) (xy -0.2286 0.2921) (xy -0.22733 0.28067) (xy -0.22733 0.27051)
						(xy -0.22606 0.25908) (xy -0.22352 0.24892) (xy -0.22225 0.23876) (xy -0.21844 0.22733) (xy -0.2159 0.21717)
						(xy -0.21209 0.20701) (xy -0.20701 0.19685) (xy -0.2032 0.18796) (xy -0.19812 0.1778) (xy -0.17272 0.14224)
						(xy -0.1651 0.13462) (xy -0.1651 -0.7366) (xy -0.16256 -0.76835) (xy -0.1524 -0.8001) (xy -0.13716 -0.82804)
						(xy -0.11684 -0.85344) (xy -0.09144 -0.87376) (xy -0.0635 -0.889) (xy -0.03175 -0.89916) (xy 0 -0.9017)
						(xy 0.03175 -0.89916) (xy 0.0635 -0.889) (xy 0.09144 -0.87376) (xy 0.11684 -0.85344) (xy 0.13716 -0.82804)
						(xy 0.1524 -0.8001) (xy 0.16256 -0.76835) (xy 0.1651 -0.7366) (xy 0.1651 0.13462) (xy 0.17272 0.14224)
						(xy 0.19812 0.1778) (xy 0.2032 0.18796) (xy 0.20701 0.19685) (xy 0.21209 0.20701) (xy 0.2159 0.21717)
						(xy 0.21844 0.22733) (xy 0.22225 0.23876) (xy 0.22352 0.24892) (xy 0.22606 0.25908) (xy 0.22733 0.27051)
						(xy 0.22733 0.28067) (xy 0.2286 0.2921) (xy 0.22733 0.30353) (xy 0.22733 0.31369) (xy 0.22606 0.32512)
						(xy 0.22352 0.33528) (xy 0.22225 0.34544) (xy 0.21844 0.35687) (xy 0.2159 0.36703) (xy 0.21209 0.37719)
						(xy 0.20701 0.38735) (xy 0.2032 0.39624) (xy 0.19812 0.4064) (xy 0.17272 0.44196) (xy 0.1651 0.44958)
						(xy 0.1651 0.7366) (xy 0.16256 0.76835) (xy 0.1524 0.8001) (xy 0.13716 0.82804) (xy 0.11684 0.85344)
						(xy 0.09144 0.87376) (xy 0.0635 0.889) (xy 0.03175 0.89916)
					)
					(width 0)
					(fill yes)
				)
			)
		)
		(pad "91" smd custom
			(at -2.249932 4.106672 180)
			(size 0.1143 0.1143)
			(layers "F.Cu" "F.Mask" "F.Paste")
			(net "M_A_BS2")
			(options
				(clearance outline)
				(anchor circle)
			)
			(primitives
				(gr_poly
					(pts
						(xy 0 0.9017) (xy -0.03175 0.89916) (xy -0.0635 0.889) (xy -0.09144 0.87376) (xy -0.11684 0.85344)
						(xy -0.13716 0.82804) (xy -0.1524 0.8001) (xy -0.16256 0.76835) (xy -0.1651 0.7366) (xy -0.1651 0.11938)
						(xy -0.17272 0.11176) (xy -0.19812 0.0762) (xy -0.2032 0.06604) (xy -0.20701 0.05715) (xy -0.21209 0.04699)
						(xy -0.2159 0.03683) (xy -0.21844 0.02667) (xy -0.22225 0.01524) (xy -0.22352 0.00508) (xy -0.22606 -0.00508)
						(xy -0.22733 -0.01651) (xy -0.22733 -0.02667) (xy -0.2286 -0.0381) (xy -0.22733 -0.04953) (xy -0.22733 -0.05969)
						(xy -0.22606 -0.07112) (xy -0.22352 -0.08128) (xy -0.22225 -0.09144) (xy -0.21844 -0.10287) (xy -0.2159 -0.11303)
						(xy -0.21209 -0.12319) (xy -0.20701 -0.13335) (xy -0.2032 -0.14224) (xy -0.19812 -0.1524) (xy -0.17272 -0.18796)
						(xy -0.1651 -0.19558) (xy -0.1651 -0.7366) (xy -0.16256 -0.76835) (xy -0.1524 -0.8001) (xy -0.13716 -0.82804)
						(xy -0.11684 -0.85344) (xy -0.09144 -0.87376) (xy -0.0635 -0.889) (xy -0.03175 -0.89916) (xy 0 -0.9017)
						(xy 0.03175 -0.89916) (xy 0.0635 -0.889) (xy 0.09144 -0.87376) (xy 0.11684 -0.85344) (xy 0.13716 -0.82804)
						(xy 0.1524 -0.8001) (xy 0.16256 -0.76835) (xy 0.1651 -0.7366) (xy 0.1651 -0.19685) (xy 0.17272 -0.18923)
						(xy 0.17907 -0.18034) (xy 0.18669 -0.17145) (xy 0.19177 -0.16256) (xy 0.19812 -0.15367) (xy 0.20828 -0.13335)
						(xy 0.21971 -0.10287) (xy 0.22225 -0.09271) (xy 0.22479 -0.08128) (xy 0.22606 -0.07112) (xy 0.2286 -0.05969)
						(xy 0.2286 -0.01651) (xy 0.22606 -0.00508) (xy 0.22479 0.00508) (xy 0.22225 0.01651) (xy 0.21971 0.02667)
						(xy 0.20828 0.05715) (xy 0.19812 0.07747) (xy 0.19177 0.08636) (xy 0.18669 0.09525) (xy 0.17907 0.10414)
						(xy 0.17272 0.11303) (xy 0.1651 0.12065) (xy 0.1651 0.7366) (xy 0.16256 0.76835) (xy 0.1524 0.8001)
						(xy 0.13716 0.82804) (xy 0.11684 0.85344) (xy 0.09144 0.87376) (xy 0.0635 0.889) (xy 0.03175 0.89916)
					)
					(width 0)
					(fill yes)
				)
			)
		)
		(pad "92" smd custom
			(at -1.949958 -4.106672 180)
			(size 0.1143 0.1143)
			(layers "F.Cu" "F.Mask" "F.Paste")
			(net "M_A_MA9")
			(options
				(clearance outline)
				(anchor circle)
			)
			(primitives
				(gr_poly
					(pts
						(xy 0 0.9017) (xy -0.03175 0.89916) (xy -0.0635 0.889) (xy -0.09144 0.87376) (xy -0.11684 0.85344)
						(xy -0.13716 0.82804) (xy -0.1524 0.8001) (xy -0.16256 0.76835) (xy -0.1651 0.7366) (xy -0.1651 0.19685)
						(xy -0.17272 0.18923) (xy -0.17907 0.18034) (xy -0.18669 0.17145) (xy -0.19177 0.16256) (xy -0.19812 0.15367)
						(xy -0.20828 0.13335) (xy -0.21971 0.10287) (xy -0.22225 0.09271) (xy -0.22479 0.08128) (xy -0.22606 0.07112)
						(xy -0.2286 0.05969) (xy -0.2286 0.01651) (xy -0.22606 0.00508) (xy -0.22479 -0.00508) (xy -0.22225 -0.01651)
						(xy -0.21971 -0.02667) (xy -0.20828 -0.05715) (xy -0.19812 -0.07747) (xy -0.19177 -0.08636) (xy -0.18669 -0.09525)
						(xy -0.17907 -0.10414) (xy -0.17272 -0.11303) (xy -0.1651 -0.12065) (xy -0.1651 -0.7366) (xy -0.16256 -0.76835)
						(xy -0.1524 -0.8001) (xy -0.13716 -0.82804) (xy -0.11684 -0.85344) (xy -0.09144 -0.87376) (xy -0.0635 -0.889)
						(xy -0.03175 -0.89916) (xy 0 -0.9017) (xy 0.03175 -0.89916) (xy 0.0635 -0.889) (xy 0.09144 -0.87376)
						(xy 0.11684 -0.85344) (xy 0.13716 -0.82804) (xy 0.1524 -0.8001) (xy 0.16256 -0.76835) (xy 0.1651 -0.7366)
						(xy 0.1651 -0.11938) (xy 0.17272 -0.11176) (xy 0.19812 -0.0762) (xy 0.2032 -0.06604) (xy 0.20701 -0.05715)
						(xy 0.21209 -0.04699) (xy 0.2159 -0.03683) (xy 0.21844 -0.02667) (xy 0.22225 -0.01524) (xy 0.22352 -0.00508)
						(xy 0.22606 0.00508) (xy 0.22733 0.01651) (xy 0.22733 0.02667) (xy 0.2286 0.0381) (xy 0.22733 0.04953)
						(xy 0.22733 0.05969) (xy 0.22606 0.07112) (xy 0.22352 0.08128) (xy 0.22225 0.09144) (xy 0.21844 0.10287)
						(xy 0.2159 0.11303) (xy 0.21209 0.12319) (xy 0.20701 0.13335) (xy 0.2032 0.14224) (xy 0.19812 0.1524)
						(xy 0.17272 0.18796) (xy 0.1651 0.19558) (xy 0.1651 0.7366) (xy 0.16256 0.76835) (xy 0.1524 0.8001)
						(xy 0.13716 0.82804) (xy 0.11684 0.85344) (xy 0.09144 0.87376) (xy 0.0635 0.889) (xy 0.03175 0.89916)
					)
					(width 0)
					(fill yes)
				)
			)
		)
		(pad "93" smd custom
			(at -1.649984 4.106672 180)
			(size 0.1143 0.1143)
			(layers "F.Cu" "F.Mask" "F.Paste")
			(net "PV_VDDR")
			(options
				(clearance outline)
				(anchor circle)
			)
			(primitives
				(gr_poly
					(pts
						(xy 0 0.9017) (xy -0.03175 0.89916) (xy -0.0635 0.889) (xy -0.09144 0.87376) (xy -0.11684 0.85344)
						(xy -0.13716 0.82804) (xy -0.1524 0.8001) (xy -0.16256 0.76835) (xy -0.1651 0.7366) (xy -0.1651 -0.13462)
						(xy -0.17272 -0.14224) (xy -0.19812 -0.1778) (xy -0.2032 -0.18796) (xy -0.20701 -0.19685) (xy -0.21209 -0.20701)
						(xy -0.2159 -0.21717) (xy -0.21844 -0.22733) (xy -0.22225 -0.23876) (xy -0.22352 -0.24892) (xy -0.22606 -0.25908)
						(xy -0.22733 -0.27051) (xy -0.22733 -0.28067) (xy -0.2286 -0.2921) (xy -0.22733 -0.30353) (xy -0.22733 -0.31369)
						(xy -0.22606 -0.32512) (xy -0.22352 -0.33528) (xy -0.22225 -0.34544) (xy -0.21844 -0.35687) (xy -0.2159 -0.36703)
						(xy -0.21209 -0.37719) (xy -0.20701 -0.38735) (xy -0.2032 -0.39624) (xy -0.19812 -0.4064) (xy -0.17272 -0.44196)
						(xy -0.1651 -0.44958) (xy -0.1651 -0.7366) (xy -0.16256 -0.76835) (xy -0.1524 -0.8001) (xy -0.13716 -0.82804)
						(xy -0.11684 -0.85344) (xy -0.09144 -0.87376) (xy -0.0635 -0.889) (xy -0.03175 -0.89916) (xy 0 -0.9017)
						(xy 0.03175 -0.89916) (xy 0.0635 -0.889) (xy 0.09144 -0.87376) (xy 0.11684 -0.85344) (xy 0.13716 -0.82804)
						(xy 0.1524 -0.8001) (xy 0.16256 -0.76835) (xy 0.1651 -0.7366) (xy 0.1651 -0.44958) (xy 0.17272 -0.44196)
						(xy 0.19812 -0.4064) (xy 0.2032 -0.39624) (xy 0.20701 -0.38735) (xy 0.21209 -0.37719) (xy 0.2159 -0.36703)
						(xy 0.21844 -0.35687) (xy 0.22225 -0.34544) (xy 0.22352 -0.33528) (xy 0.22606 -0.32512) (xy 0.22733 -0.31369)
						(xy 0.22733 -0.30353) (xy 0.2286 -0.2921) (xy 0.22733 -0.28067) (xy 0.22733 -0.27051) (xy 0.22606 -0.25908)
						(xy 0.22352 -0.24892) (xy 0.22225 -0.23876) (xy 0.21844 -0.22733) (xy 0.2159 -0.21717) (xy 0.21209 -0.20701)
						(xy 0.20701 -0.19685) (xy 0.2032 -0.18796) (xy 0.19812 -0.1778) (xy 0.17272 -0.14224) (xy 0.1651 -0.13462)
						(xy 0.1651 0.7366) (xy 0.16256 0.76835) (xy 0.1524 0.8001) (xy 0.13716 0.82804) (xy 0.11684 0.85344)
						(xy 0.09144 0.87376) (xy 0.0635 0.889) (xy 0.03175 0.89916)
					)
					(width 0)
					(fill yes)
				)
			)
		)
		(pad "94" smd custom
			(at -1.35001 -4.106672 180)
			(size 0.1143 0.1143)
			(layers "F.Cu" "F.Mask" "F.Paste")
			(net "PV_VDDR")
			(options
				(clearance outline)
				(anchor circle)
			)
			(primitives
				(gr_poly
					(pts
						(xy 0 0.9017) (xy -0.03175 0.89916) (xy -0.0635 0.889) (xy -0.09144 0.87376) (xy -0.11684 0.85344)
						(xy -0.13716 0.82804) (xy -0.1524 0.8001) (xy -0.16256 0.76835) (xy -0.1651 0.7366) (xy -0.1651 0.44958)
						(xy -0.17272 0.44196) (xy -0.19812 0.4064) (xy -0.2032 0.39624) (xy -0.20701 0.38735) (xy -0.21209 0.37719)
						(xy -0.2159 0.36703) (xy -0.21844 0.35687) (xy -0.22225 0.34544) (xy -0.22352 0.33528) (xy -0.22606 0.32512)
						(xy -0.22733 0.31369) (xy -0.22733 0.30353) (xy -0.2286 0.2921) (xy -0.22733 0.28067) (xy -0.22733 0.27051)
						(xy -0.22606 0.25908) (xy -0.22352 0.24892) (xy -0.22225 0.23876) (xy -0.21844 0.22733) (xy -0.2159 0.21717)
						(xy -0.21209 0.20701) (xy -0.20701 0.19685) (xy -0.2032 0.18796) (xy -0.19812 0.1778) (xy -0.17272 0.14224)
						(xy -0.1651 0.13462) (xy -0.1651 -0.7366) (xy -0.16256 -0.76835) (xy -0.1524 -0.8001) (xy -0.13716 -0.82804)
						(xy -0.11684 -0.85344) (xy -0.09144 -0.87376) (xy -0.0635 -0.889) (xy -0.03175 -0.89916) (xy 0 -0.9017)
						(xy 0.03175 -0.89916) (xy 0.0635 -0.889) (xy 0.09144 -0.87376) (xy 0.11684 -0.85344) (xy 0.13716 -0.82804)
						(xy 0.1524 -0.8001) (xy 0.16256 -0.76835) (xy 0.1651 -0.7366) (xy 0.1651 0.13462) (xy 0.17272 0.14224)
						(xy 0.19812 0.1778) (xy 0.2032 0.18796) (xy 0.20701 0.19685) (xy 0.21209 0.20701) (xy 0.2159 0.21717)
						(xy 0.21844 0.22733) (xy 0.22225 0.23876) (xy 0.22352 0.24892) (xy 0.22606 0.25908) (xy 0.22733 0.27051)
						(xy 0.22733 0.28067) (xy 0.2286 0.2921) (xy 0.22733 0.30353) (xy 0.22733 0.31369) (xy 0.22606 0.32512)
						(xy 0.22352 0.33528) (xy 0.22225 0.34544) (xy 0.21844 0.35687) (xy 0.2159 0.36703) (xy 0.21209 0.37719)
						(xy 0.20701 0.38735) (xy 0.2032 0.39624) (xy 0.19812 0.4064) (xy 0.17272 0.44196) (xy 0.1651 0.44958)
						(xy 0.1651 0.7366) (xy 0.16256 0.76835) (xy 0.1524 0.8001) (xy 0.13716 0.82804) (xy 0.11684 0.85344)
						(xy 0.09144 0.87376) (xy 0.0635 0.889) (xy 0.03175 0.89916)
					)
					(width 0)
					(fill yes)
				)
			)
		)
		(pad "95" smd custom
			(at -1.050036 4.106672 180)
			(size 0.1143 0.1143)
			(layers "F.Cu" "F.Mask" "F.Paste")
			(net "M_A_MA12")
			(options
				(clearance outline)
				(anchor circle)
			)
			(primitives
				(gr_poly
					(pts
						(xy 0 0.9017) (xy -0.03175 0.89916) (xy -0.0635 0.889) (xy -0.09144 0.87376) (xy -0.11684 0.85344)
						(xy -0.13716 0.82804) (xy -0.1524 0.8001) (xy -0.16256 0.76835) (xy -0.1651 0.7366) (xy -0.1651 0.11938)
						(xy -0.17272 0.11176) (xy -0.19812 0.0762) (xy -0.2032 0.06604) (xy -0.20701 0.05715) (xy -0.21209 0.04699)
						(xy -0.2159 0.03683) (xy -0.21844 0.02667) (xy -0.22225 0.01524) (xy -0.22352 0.00508) (xy -0.22606 -0.00508)
						(xy -0.22733 -0.01651) (xy -0.22733 -0.02667) (xy -0.2286 -0.0381) (xy -0.22733 -0.04953) (xy -0.22733 -0.05969)
						(xy -0.22606 -0.07112) (xy -0.22352 -0.08128) (xy -0.22225 -0.09144) (xy -0.21844 -0.10287) (xy -0.2159 -0.11303)
						(xy -0.21209 -0.12319) (xy -0.20701 -0.13335) (xy -0.2032 -0.14224) (xy -0.19812 -0.1524) (xy -0.17272 -0.18796)
						(xy -0.1651 -0.19558) (xy -0.1651 -0.7366) (xy -0.16256 -0.76835) (xy -0.1524 -0.8001) (xy -0.13716 -0.82804)
						(xy -0.11684 -0.85344) (xy -0.09144 -0.87376) (xy -0.0635 -0.889) (xy -0.03175 -0.89916) (xy 0 -0.9017)
						(xy 0.03175 -0.89916) (xy 0.0635 -0.889) (xy 0.09144 -0.87376) (xy 0.11684 -0.85344) (xy 0.13716 -0.82804)
						(xy 0.1524 -0.8001) (xy 0.16256 -0.76835) (xy 0.1651 -0.7366) (xy 0.1651 -0.19685) (xy 0.17272 -0.18923)
						(xy 0.17907 -0.18034) (xy 0.18669 -0.17145) (xy 0.19177 -0.16256) (xy 0.19812 -0.15367) (xy 0.20828 -0.13335)
						(xy 0.21971 -0.10287) (xy 0.22225 -0.09271) (xy 0.22479 -0.08128) (xy 0.22606 -0.07112) (xy 0.2286 -0.05969)
						(xy 0.2286 -0.01651) (xy 0.22606 -0.00508) (xy 0.22479 0.00508) (xy 0.22225 0.01651) (xy 0.21971 0.02667)
						(xy 0.20828 0.05715) (xy 0.19812 0.07747) (xy 0.19177 0.08636) (xy 0.18669 0.09525) (xy 0.17907 0.10414)
						(xy 0.17272 0.11303) (xy 0.1651 0.12065) (xy 0.1651 0.7366) (xy 0.16256 0.76835) (xy 0.1524 0.8001)
						(xy 0.13716 0.82804) (xy 0.11684 0.85344) (xy 0.09144 0.87376) (xy 0.0635 0.889) (xy 0.03175 0.89916)
					)
					(width 0)
					(fill yes)
				)
			)
		)
		(pad "96" smd custom
			(at -0.750062 -4.106672 180)
			(size 0.1143 0.1143)
			(layers "F.Cu" "F.Mask" "F.Paste")
			(net "M_A_MA11")
			(options
				(clearance outline)
				(anchor circle)
			)
			(primitives
				(gr_poly
					(pts
						(xy 0 0.9017) (xy -0.03175 0.89916) (xy -0.0635 0.889) (xy -0.09144 0.87376) (xy -0.11684 0.85344)
						(xy -0.13716 0.82804) (xy -0.1524 0.8001) (xy -0.16256 0.76835) (xy -0.1651 0.7366) (xy -0.1651 0.19685)
						(xy -0.17272 0.18923) (xy -0.17907 0.18034) (xy -0.18669 0.17145) (xy -0.19177 0.16256) (xy -0.19812 0.15367)
						(xy -0.20828 0.13335) (xy -0.21971 0.10287) (xy -0.22225 0.09271) (xy -0.22479 0.08128) (xy -0.22606 0.07112)
						(xy -0.2286 0.05969) (xy -0.2286 0.01651) (xy -0.22606 0.00508) (xy -0.22479 -0.00508) (xy -0.22225 -0.01651)
						(xy -0.21971 -0.02667) (xy -0.20828 -0.05715) (xy -0.19812 -0.07747) (xy -0.19177 -0.08636) (xy -0.18669 -0.09525)
						(xy -0.17907 -0.10414) (xy -0.17272 -0.11303) (xy -0.1651 -0.12065) (xy -0.1651 -0.7366) (xy -0.16256 -0.76835)
						(xy -0.1524 -0.8001) (xy -0.13716 -0.82804) (xy -0.11684 -0.85344) (xy -0.09144 -0.87376) (xy -0.0635 -0.889)
						(xy -0.03175 -0.89916) (xy 0 -0.9017) (xy 0.03175 -0.89916) (xy 0.0635 -0.889) (xy 0.09144 -0.87376)
						(xy 0.11684 -0.85344) (xy 0.13716 -0.82804) (xy 0.1524 -0.8001) (xy 0.16256 -0.76835) (xy 0.1651 -0.7366)
						(xy 0.1651 -0.11938) (xy 0.17272 -0.11176) (xy 0.19812 -0.0762) (xy 0.2032 -0.06604) (xy 0.20701 -0.05715)
						(xy 0.21209 -0.04699) (xy 0.2159 -0.03683) (xy 0.21844 -0.02667) (xy 0.22225 -0.01524) (xy 0.22352 -0.00508)
						(xy 0.22606 0.00508) (xy 0.22733 0.01651) (xy 0.22733 0.02667) (xy 0.2286 0.0381) (xy 0.22733 0.04953)
						(xy 0.22733 0.05969) (xy 0.22606 0.07112) (xy 0.22352 0.08128) (xy 0.22225 0.09144) (xy 0.21844 0.10287)
						(xy 0.2159 0.11303) (xy 0.21209 0.12319) (xy 0.20701 0.13335) (xy 0.2032 0.14224) (xy 0.19812 0.1524)
						(xy 0.17272 0.18796) (xy 0.1651 0.19558) (xy 0.1651 0.7366) (xy 0.16256 0.76835) (xy 0.1524 0.8001)
						(xy 0.13716 0.82804) (xy 0.11684 0.85344) (xy 0.09144 0.87376) (xy 0.0635 0.889) (xy 0.03175 0.89916)
					)
					(width 0)
					(fill yes)
				)
			)
		)
		(pad "97" smd custom
			(at -0.450088 4.106672 180)
			(size 0.1143 0.1143)
			(layers "F.Cu" "F.Mask" "F.Paste")
			(net "M_A_MA8")
			(options
				(clearance outline)
				(anchor circle)
			)
			(primitives
				(gr_poly
					(pts
						(xy 0 0.9017) (xy -0.03175 0.89916) (xy -0.0635 0.889) (xy -0.09144 0.87376) (xy -0.11684 0.85344)
						(xy -0.13716 0.82804) (xy -0.1524 0.8001) (xy -0.16256 0.76835) (xy -0.1651 0.7366) (xy -0.1651 -0.13462)
						(xy -0.17272 -0.14224) (xy -0.19812 -0.1778) (xy -0.2032 -0.18796) (xy -0.20701 -0.19685) (xy -0.21209 -0.20701)
						(xy -0.2159 -0.21717) (xy -0.21844 -0.22733) (xy -0.22225 -0.23876) (xy -0.22352 -0.24892) (xy -0.22606 -0.25908)
						(xy -0.22733 -0.27051) (xy -0.22733 -0.28067) (xy -0.2286 -0.2921) (xy -0.22733 -0.30353) (xy -0.22733 -0.31369)
						(xy -0.22606 -0.32512) (xy -0.22352 -0.33528) (xy -0.22225 -0.34544) (xy -0.21844 -0.35687) (xy -0.2159 -0.36703)
						(xy -0.21209 -0.37719) (xy -0.20701 -0.38735) (xy -0.2032 -0.39624) (xy -0.19812 -0.4064) (xy -0.17272 -0.44196)
						(xy -0.1651 -0.44958) (xy -0.1651 -0.7366) (xy -0.16256 -0.76835) (xy -0.1524 -0.8001) (xy -0.13716 -0.82804)
						(xy -0.11684 -0.85344) (xy -0.09144 -0.87376) (xy -0.0635 -0.889) (xy -0.03175 -0.89916) (xy 0 -0.9017)
						(xy 0.03175 -0.89916) (xy 0.0635 -0.889) (xy 0.09144 -0.87376) (xy 0.11684 -0.85344) (xy 0.13716 -0.82804)
						(xy 0.1524 -0.8001) (xy 0.16256 -0.76835) (xy 0.1651 -0.7366) (xy 0.1651 -0.44958) (xy 0.17272 -0.44196)
						(xy 0.19812 -0.4064) (xy 0.2032 -0.39624) (xy 0.20701 -0.38735) (xy 0.21209 -0.37719) (xy 0.2159 -0.36703)
						(xy 0.21844 -0.35687) (xy 0.22225 -0.34544) (xy 0.22352 -0.33528) (xy 0.22606 -0.32512) (xy 0.22733 -0.31369)
						(xy 0.22733 -0.30353) (xy 0.2286 -0.2921) (xy 0.22733 -0.28067) (xy 0.22733 -0.27051) (xy 0.22606 -0.25908)
						(xy 0.22352 -0.24892) (xy 0.22225 -0.23876) (xy 0.21844 -0.22733) (xy 0.2159 -0.21717) (xy 0.21209 -0.20701)
						(xy 0.20701 -0.19685) (xy 0.2032 -0.18796) (xy 0.19812 -0.1778) (xy 0.17272 -0.14224) (xy 0.1651 -0.13462)
						(xy 0.1651 0.7366) (xy 0.16256 0.76835) (xy 0.1524 0.8001) (xy 0.13716 0.82804) (xy 0.11684 0.85344)
						(xy 0.09144 0.87376) (xy 0.0635 0.889) (xy 0.03175 0.89916)
					)
					(width 0)
					(fill yes)
				)
			)
		)
		(pad "98" smd custom
			(at -0.150114 -4.106672 180)
			(size 0.1143 0.1143)
			(layers "F.Cu" "F.Mask" "F.Paste")
			(net "M_A_MA7")
			(options
				(clearance outline)
				(anchor circle)
			)
			(primitives
				(gr_poly
					(pts
						(xy 0 0.9017) (xy -0.03175 0.89916) (xy -0.0635 0.889) (xy -0.09144 0.87376) (xy -0.11684 0.85344)
						(xy -0.13716 0.82804) (xy -0.1524 0.8001) (xy -0.16256 0.76835) (xy -0.1651 0.7366) (xy -0.1651 0.44958)
						(xy -0.17272 0.44196) (xy -0.19812 0.4064) (xy -0.2032 0.39624) (xy -0.20701 0.38735) (xy -0.21209 0.37719)
						(xy -0.2159 0.36703) (xy -0.21844 0.35687) (xy -0.22225 0.34544) (xy -0.22352 0.33528) (xy -0.22606 0.32512)
						(xy -0.22733 0.31369) (xy -0.22733 0.30353) (xy -0.2286 0.2921) (xy -0.22733 0.28067) (xy -0.22733 0.27051)
						(xy -0.22606 0.25908) (xy -0.22352 0.24892) (xy -0.22225 0.23876) (xy -0.21844 0.22733) (xy -0.2159 0.21717)
						(xy -0.21209 0.20701) (xy -0.20701 0.19685) (xy -0.2032 0.18796) (xy -0.19812 0.1778) (xy -0.17272 0.14224)
						(xy -0.1651 0.13462) (xy -0.1651 -0.7366) (xy -0.16256 -0.76835) (xy -0.1524 -0.8001) (xy -0.13716 -0.82804)
						(xy -0.11684 -0.85344) (xy -0.09144 -0.87376) (xy -0.0635 -0.889) (xy -0.03175 -0.89916) (xy 0 -0.9017)
						(xy 0.03175 -0.89916) (xy 0.0635 -0.889) (xy 0.09144 -0.87376) (xy 0.11684 -0.85344) (xy 0.13716 -0.82804)
						(xy 0.1524 -0.8001) (xy 0.16256 -0.76835) (xy 0.1651 -0.7366) (xy 0.1651 0.13462) (xy 0.17272 0.14224)
						(xy 0.19812 0.1778) (xy 0.2032 0.18796) (xy 0.20701 0.19685) (xy 0.21209 0.20701) (xy 0.2159 0.21717)
						(xy 0.21844 0.22733) (xy 0.22225 0.23876) (xy 0.22352 0.24892) (xy 0.22606 0.25908) (xy 0.22733 0.27051)
						(xy 0.22733 0.28067) (xy 0.2286 0.2921) (xy 0.22733 0.30353) (xy 0.22733 0.31369) (xy 0.22606 0.32512)
						(xy 0.22352 0.33528) (xy 0.22225 0.34544) (xy 0.21844 0.35687) (xy 0.2159 0.36703) (xy 0.21209 0.37719)
						(xy 0.20701 0.38735) (xy 0.2032 0.39624) (xy 0.19812 0.4064) (xy 0.17272 0.44196) (xy 0.1651 0.44958)
						(xy 0.1651 0.7366) (xy 0.16256 0.76835) (xy 0.1524 0.8001) (xy 0.13716 0.82804) (xy 0.11684 0.85344)
						(xy 0.09144 0.87376) (xy 0.0635 0.889) (xy 0.03175 0.89916)
					)
					(width 0)
					(fill yes)
				)
			)
		)
		(pad "99" smd custom
			(at 0.150114 4.106672 180)
			(size 0.1143 0.1143)
			(layers "F.Cu" "F.Mask" "F.Paste")
			(net "M_A_MA5")
			(options
				(clearance outline)
				(anchor circle)
			)
			(primitives
				(gr_poly
					(pts
						(xy 0 0.9017) (xy -0.03175 0.89916) (xy -0.0635 0.889) (xy -0.09144 0.87376) (xy -0.11684 0.85344)
						(xy -0.13716 0.82804) (xy -0.1524 0.8001) (xy -0.16256 0.76835) (xy -0.1651 0.7366) (xy -0.1651 0.11938)
						(xy -0.17272 0.11176) (xy -0.19812 0.0762) (xy -0.2032 0.06604) (xy -0.20701 0.05715) (xy -0.21209 0.04699)
						(xy -0.2159 0.03683) (xy -0.21844 0.02667) (xy -0.22225 0.01524) (xy -0.22352 0.00508) (xy -0.22606 -0.00508)
						(xy -0.22733 -0.01651) (xy -0.22733 -0.02667) (xy -0.2286 -0.0381) (xy -0.22733 -0.04953) (xy -0.22733 -0.05969)
						(xy -0.22606 -0.07112) (xy -0.22352 -0.08128) (xy -0.22225 -0.09144) (xy -0.21844 -0.10287) (xy -0.2159 -0.11303)
						(xy -0.21209 -0.12319) (xy -0.20701 -0.13335) (xy -0.2032 -0.14224) (xy -0.19812 -0.1524) (xy -0.17272 -0.18796)
						(xy -0.1651 -0.19558) (xy -0.1651 -0.7366) (xy -0.16256 -0.76835) (xy -0.1524 -0.8001) (xy -0.13716 -0.82804)
						(xy -0.11684 -0.85344) (xy -0.09144 -0.87376) (xy -0.0635 -0.889) (xy -0.03175 -0.89916) (xy 0 -0.9017)
						(xy 0.03175 -0.89916) (xy 0.0635 -0.889) (xy 0.09144 -0.87376) (xy 0.11684 -0.85344) (xy 0.13716 -0.82804)
						(xy 0.1524 -0.8001) (xy 0.16256 -0.76835) (xy 0.1651 -0.7366) (xy 0.1651 -0.19685) (xy 0.17272 -0.18923)
						(xy 0.17907 -0.18034) (xy 0.18669 -0.17145) (xy 0.19177 -0.16256) (xy 0.19812 -0.15367) (xy 0.20828 -0.13335)
						(xy 0.21971 -0.10287) (xy 0.22225 -0.09271) (xy 0.22479 -0.08128) (xy 0.22606 -0.07112) (xy 0.2286 -0.05969)
						(xy 0.2286 -0.01651) (xy 0.22606 -0.00508) (xy 0.22479 0.00508) (xy 0.22225 0.01651) (xy 0.21971 0.02667)
						(xy 0.20828 0.05715) (xy 0.19812 0.07747) (xy 0.19177 0.08636) (xy 0.18669 0.09525) (xy 0.17907 0.10414)
						(xy 0.17272 0.11303) (xy 0.1651 0.12065) (xy 0.1651 0.7366) (xy 0.16256 0.76835) (xy 0.1524 0.8001)
						(xy 0.13716 0.82804) (xy 0.11684 0.85344) (xy 0.09144 0.87376) (xy 0.0635 0.889) (xy 0.03175 0.89916)
					)
					(width 0)
					(fill yes)
				)
			)
		)
		(pad "100" smd custom
			(at 0.450088 -4.106672 180)
			(size 0.1143 0.1143)
			(layers "F.Cu" "F.Mask" "F.Paste")
			(net "M_A_MA6")
			(options
				(clearance outline)
				(anchor circle)
			)
			(primitives
				(gr_poly
					(pts
						(xy 0 0.9017) (xy -0.03175 0.89916) (xy -0.0635 0.889) (xy -0.09144 0.87376) (xy -0.11684 0.85344)
						(xy -0.13716 0.82804) (xy -0.1524 0.8001) (xy -0.16256 0.76835) (xy -0.1651 0.7366) (xy -0.1651 0.19685)
						(xy -0.17272 0.18923) (xy -0.17907 0.18034) (xy -0.18669 0.17145) (xy -0.19177 0.16256) (xy -0.19812 0.15367)
						(xy -0.20828 0.13335) (xy -0.21971 0.10287) (xy -0.22225 0.09271) (xy -0.22479 0.08128) (xy -0.22606 0.07112)
						(xy -0.2286 0.05969) (xy -0.2286 0.01651) (xy -0.22606 0.00508) (xy -0.22479 -0.00508) (xy -0.22225 -0.01651)
						(xy -0.21971 -0.02667) (xy -0.20828 -0.05715) (xy -0.19812 -0.07747) (xy -0.19177 -0.08636) (xy -0.18669 -0.09525)
						(xy -0.17907 -0.10414) (xy -0.17272 -0.11303) (xy -0.1651 -0.12065) (xy -0.1651 -0.7366) (xy -0.16256 -0.76835)
						(xy -0.1524 -0.8001) (xy -0.13716 -0.82804) (xy -0.11684 -0.85344) (xy -0.09144 -0.87376) (xy -0.0635 -0.889)
						(xy -0.03175 -0.89916) (xy 0 -0.9017) (xy 0.03175 -0.89916) (xy 0.0635 -0.889) (xy 0.09144 -0.87376)
						(xy 0.11684 -0.85344) (xy 0.13716 -0.82804) (xy 0.1524 -0.8001) (xy 0.16256 -0.76835) (xy 0.1651 -0.7366)
						(xy 0.1651 -0.11938) (xy 0.17272 -0.11176) (xy 0.19812 -0.0762) (xy 0.2032 -0.06604) (xy 0.20701 -0.05715)
						(xy 0.21209 -0.04699) (xy 0.2159 -0.03683) (xy 0.21844 -0.02667) (xy 0.22225 -0.01524) (xy 0.22352 -0.00508)
						(xy 0.22606 0.00508) (xy 0.22733 0.01651) (xy 0.22733 0.02667) (xy 0.2286 0.0381) (xy 0.22733 0.04953)
						(xy 0.22733 0.05969) (xy 0.22606 0.07112) (xy 0.22352 0.08128) (xy 0.22225 0.09144) (xy 0.21844 0.10287)
						(xy 0.2159 0.11303) (xy 0.21209 0.12319) (xy 0.20701 0.13335) (xy 0.2032 0.14224) (xy 0.19812 0.1524)
						(xy 0.17272 0.18796) (xy 0.1651 0.19558) (xy 0.1651 0.7366) (xy 0.16256 0.76835) (xy 0.1524 0.8001)
						(xy 0.13716 0.82804) (xy 0.11684 0.85344) (xy 0.09144 0.87376) (xy 0.0635 0.889) (xy 0.03175 0.89916)
					)
					(width 0)
					(fill yes)
				)
			)
		)
		(pad "101" smd custom
			(at 0.750062 4.106672 180)
			(size 0.1143 0.1143)
			(layers "F.Cu" "F.Mask" "F.Paste")
			(net "PV_VDDR")
			(options
				(clearance outline)
				(anchor circle)
			)
			(primitives
				(gr_poly
					(pts
						(xy 0 0.9017) (xy -0.03175 0.89916) (xy -0.0635 0.889) (xy -0.09144 0.87376) (xy -0.11684 0.85344)
						(xy -0.13716 0.82804) (xy -0.1524 0.8001) (xy -0.16256 0.76835) (xy -0.1651 0.7366) (xy -0.1651 -0.13462)
						(xy -0.17272 -0.14224) (xy -0.19812 -0.1778) (xy -0.2032 -0.18796) (xy -0.20701 -0.19685) (xy -0.21209 -0.20701)
						(xy -0.2159 -0.21717) (xy -0.21844 -0.22733) (xy -0.22225 -0.23876) (xy -0.22352 -0.24892) (xy -0.22606 -0.25908)
						(xy -0.22733 -0.27051) (xy -0.22733 -0.28067) (xy -0.2286 -0.2921) (xy -0.22733 -0.30353) (xy -0.22733 -0.31369)
						(xy -0.22606 -0.32512) (xy -0.22352 -0.33528) (xy -0.22225 -0.34544) (xy -0.21844 -0.35687) (xy -0.2159 -0.36703)
						(xy -0.21209 -0.37719) (xy -0.20701 -0.38735) (xy -0.2032 -0.39624) (xy -0.19812 -0.4064) (xy -0.17272 -0.44196)
						(xy -0.1651 -0.44958) (xy -0.1651 -0.7366) (xy -0.16256 -0.76835) (xy -0.1524 -0.8001) (xy -0.13716 -0.82804)
						(xy -0.11684 -0.85344) (xy -0.09144 -0.87376) (xy -0.0635 -0.889) (xy -0.03175 -0.89916) (xy 0 -0.9017)
						(xy 0.03175 -0.89916) (xy 0.0635 -0.889) (xy 0.09144 -0.87376) (xy 0.11684 -0.85344) (xy 0.13716 -0.82804)
						(xy 0.1524 -0.8001) (xy 0.16256 -0.76835) (xy 0.1651 -0.7366) (xy 0.1651 -0.44958) (xy 0.17272 -0.44196)
						(xy 0.19812 -0.4064) (xy 0.2032 -0.39624) (xy 0.20701 -0.38735) (xy 0.21209 -0.37719) (xy 0.2159 -0.36703)
						(xy 0.21844 -0.35687) (xy 0.22225 -0.34544) (xy 0.22352 -0.33528) (xy 0.22606 -0.32512) (xy 0.22733 -0.31369)
						(xy 0.22733 -0.30353) (xy 0.2286 -0.2921) (xy 0.22733 -0.28067) (xy 0.22733 -0.27051) (xy 0.22606 -0.25908)
						(xy 0.22352 -0.24892) (xy 0.22225 -0.23876) (xy 0.21844 -0.22733) (xy 0.2159 -0.21717) (xy 0.21209 -0.20701)
						(xy 0.20701 -0.19685) (xy 0.2032 -0.18796) (xy 0.19812 -0.1778) (xy 0.17272 -0.14224) (xy 0.1651 -0.13462)
						(xy 0.1651 0.7366) (xy 0.16256 0.76835) (xy 0.1524 0.8001) (xy 0.13716 0.82804) (xy 0.11684 0.85344)
						(xy 0.09144 0.87376) (xy 0.0635 0.889) (xy 0.03175 0.89916)
					)
					(width 0)
					(fill yes)
				)
			)
		)
		(pad "102" smd custom
			(at 1.050036 -4.106672 180)
			(size 0.1143 0.1143)
			(layers "F.Cu" "F.Mask" "F.Paste")
			(net "PV_VDDR")
			(options
				(clearance outline)
				(anchor circle)
			)
			(primitives
				(gr_poly
					(pts
						(xy 0 0.9017) (xy -0.03175 0.89916) (xy -0.0635 0.889) (xy -0.09144 0.87376) (xy -0.11684 0.85344)
						(xy -0.13716 0.82804) (xy -0.1524 0.8001) (xy -0.16256 0.76835) (xy -0.1651 0.7366) (xy -0.1651 0.44958)
						(xy -0.17272 0.44196) (xy -0.19812 0.4064) (xy -0.2032 0.39624) (xy -0.20701 0.38735) (xy -0.21209 0.37719)
						(xy -0.2159 0.36703) (xy -0.21844 0.35687) (xy -0.22225 0.34544) (xy -0.22352 0.33528) (xy -0.22606 0.32512)
						(xy -0.22733 0.31369) (xy -0.22733 0.30353) (xy -0.2286 0.2921) (xy -0.22733 0.28067) (xy -0.22733 0.27051)
						(xy -0.22606 0.25908) (xy -0.22352 0.24892) (xy -0.22225 0.23876) (xy -0.21844 0.22733) (xy -0.2159 0.21717)
						(xy -0.21209 0.20701) (xy -0.20701 0.19685) (xy -0.2032 0.18796) (xy -0.19812 0.1778) (xy -0.17272 0.14224)
						(xy -0.1651 0.13462) (xy -0.1651 -0.7366) (xy -0.16256 -0.76835) (xy -0.1524 -0.8001) (xy -0.13716 -0.82804)
						(xy -0.11684 -0.85344) (xy -0.09144 -0.87376) (xy -0.0635 -0.889) (xy -0.03175 -0.89916) (xy 0 -0.9017)
						(xy 0.03175 -0.89916) (xy 0.0635 -0.889) (xy 0.09144 -0.87376) (xy 0.11684 -0.85344) (xy 0.13716 -0.82804)
						(xy 0.1524 -0.8001) (xy 0.16256 -0.76835) (xy 0.1651 -0.7366) (xy 0.1651 0.13462) (xy 0.17272 0.14224)
						(xy 0.19812 0.1778) (xy 0.2032 0.18796) (xy 0.20701 0.19685) (xy 0.21209 0.20701) (xy 0.2159 0.21717)
						(xy 0.21844 0.22733) (xy 0.22225 0.23876) (xy 0.22352 0.24892) (xy 0.22606 0.25908) (xy 0.22733 0.27051)
						(xy 0.22733 0.28067) (xy 0.2286 0.2921) (xy 0.22733 0.30353) (xy 0.22733 0.31369) (xy 0.22606 0.32512)
						(xy 0.22352 0.33528) (xy 0.22225 0.34544) (xy 0.21844 0.35687) (xy 0.2159 0.36703) (xy 0.21209 0.37719)
						(xy 0.20701 0.38735) (xy 0.2032 0.39624) (xy 0.19812 0.4064) (xy 0.17272 0.44196) (xy 0.1651 0.44958)
						(xy 0.1651 0.7366) (xy 0.16256 0.76835) (xy 0.1524 0.8001) (xy 0.13716 0.82804) (xy 0.11684 0.85344)
						(xy 0.09144 0.87376) (xy 0.0635 0.889) (xy 0.03175 0.89916)
					)
					(width 0)
					(fill yes)
				)
			)
		)
		(pad "103" smd custom
			(at 1.35001 4.106672 180)
			(size 0.1143 0.1143)
			(layers "F.Cu" "F.Mask" "F.Paste")
			(net "M_A_MA3")
			(options
				(clearance outline)
				(anchor circle)
			)
			(primitives
				(gr_poly
					(pts
						(xy 0 0.9017) (xy -0.03175 0.89916) (xy -0.0635 0.889) (xy -0.09144 0.87376) (xy -0.11684 0.85344)
						(xy -0.13716 0.82804) (xy -0.1524 0.8001) (xy -0.16256 0.76835) (xy -0.1651 0.7366) (xy -0.1651 0.11938)
						(xy -0.17272 0.11176) (xy -0.19812 0.0762) (xy -0.2032 0.06604) (xy -0.20701 0.05715) (xy -0.21209 0.04699)
						(xy -0.2159 0.03683) (xy -0.21844 0.02667) (xy -0.22225 0.01524) (xy -0.22352 0.00508) (xy -0.22606 -0.00508)
						(xy -0.22733 -0.01651) (xy -0.22733 -0.02667) (xy -0.2286 -0.0381) (xy -0.22733 -0.04953) (xy -0.22733 -0.05969)
						(xy -0.22606 -0.07112) (xy -0.22352 -0.08128) (xy -0.22225 -0.09144) (xy -0.21844 -0.10287) (xy -0.2159 -0.11303)
						(xy -0.21209 -0.12319) (xy -0.20701 -0.13335) (xy -0.2032 -0.14224) (xy -0.19812 -0.1524) (xy -0.17272 -0.18796)
						(xy -0.1651 -0.19558) (xy -0.1651 -0.7366) (xy -0.16256 -0.76835) (xy -0.1524 -0.8001) (xy -0.13716 -0.82804)
						(xy -0.11684 -0.85344) (xy -0.09144 -0.87376) (xy -0.0635 -0.889) (xy -0.03175 -0.89916) (xy 0 -0.9017)
						(xy 0.03175 -0.89916) (xy 0.0635 -0.889) (xy 0.09144 -0.87376) (xy 0.11684 -0.85344) (xy 0.13716 -0.82804)
						(xy 0.1524 -0.8001) (xy 0.16256 -0.76835) (xy 0.1651 -0.7366) (xy 0.1651 -0.19685) (xy 0.17272 -0.18923)
						(xy 0.17907 -0.18034) (xy 0.18669 -0.17145) (xy 0.19177 -0.16256) (xy 0.19812 -0.15367) (xy 0.20828 -0.13335)
						(xy 0.21971 -0.10287) (xy 0.22225 -0.09271) (xy 0.22479 -0.08128) (xy 0.22606 -0.07112) (xy 0.2286 -0.05969)
						(xy 0.2286 -0.01651) (xy 0.22606 -0.00508) (xy 0.22479 0.00508) (xy 0.22225 0.01651) (xy 0.21971 0.02667)
						(xy 0.20828 0.05715) (xy 0.19812 0.07747) (xy 0.19177 0.08636) (xy 0.18669 0.09525) (xy 0.17907 0.10414)
						(xy 0.17272 0.11303) (xy 0.1651 0.12065) (xy 0.1651 0.7366) (xy 0.16256 0.76835) (xy 0.1524 0.8001)
						(xy 0.13716 0.82804) (xy 0.11684 0.85344) (xy 0.09144 0.87376) (xy 0.0635 0.889) (xy 0.03175 0.89916)
					)
					(width 0)
					(fill yes)
				)
			)
		)
		(pad "104" smd custom
			(at 1.649984 -4.106672 180)
			(size 0.1143 0.1143)
			(layers "F.Cu" "F.Mask" "F.Paste")
			(net "M_A_MA4")
			(options
				(clearance outline)
				(anchor circle)
			)
			(primitives
				(gr_poly
					(pts
						(xy 0 0.9017) (xy -0.03175 0.89916) (xy -0.0635 0.889) (xy -0.09144 0.87376) (xy -0.11684 0.85344)
						(xy -0.13716 0.82804) (xy -0.1524 0.8001) (xy -0.16256 0.76835) (xy -0.1651 0.7366) (xy -0.1651 0.19685)
						(xy -0.17272 0.18923) (xy -0.17907 0.18034) (xy -0.18669 0.17145) (xy -0.19177 0.16256) (xy -0.19812 0.15367)
						(xy -0.20828 0.13335) (xy -0.21971 0.10287) (xy -0.22225 0.09271) (xy -0.22479 0.08128) (xy -0.22606 0.07112)
						(xy -0.2286 0.05969) (xy -0.2286 0.01651) (xy -0.22606 0.00508) (xy -0.22479 -0.00508) (xy -0.22225 -0.01651)
						(xy -0.21971 -0.02667) (xy -0.20828 -0.05715) (xy -0.19812 -0.07747) (xy -0.19177 -0.08636) (xy -0.18669 -0.09525)
						(xy -0.17907 -0.10414) (xy -0.17272 -0.11303) (xy -0.1651 -0.12065) (xy -0.1651 -0.7366) (xy -0.16256 -0.76835)
						(xy -0.1524 -0.8001) (xy -0.13716 -0.82804) (xy -0.11684 -0.85344) (xy -0.09144 -0.87376) (xy -0.0635 -0.889)
						(xy -0.03175 -0.89916) (xy 0 -0.9017) (xy 0.03175 -0.89916) (xy 0.0635 -0.889) (xy 0.09144 -0.87376)
						(xy 0.11684 -0.85344) (xy 0.13716 -0.82804) (xy 0.1524 -0.8001) (xy 0.16256 -0.76835) (xy 0.1651 -0.7366)
						(xy 0.1651 -0.11938) (xy 0.17272 -0.11176) (xy 0.19812 -0.0762) (xy 0.2032 -0.06604) (xy 0.20701 -0.05715)
						(xy 0.21209 -0.04699) (xy 0.2159 -0.03683) (xy 0.21844 -0.02667) (xy 0.22225 -0.01524) (xy 0.22352 -0.00508)
						(xy 0.22606 0.00508) (xy 0.22733 0.01651) (xy 0.22733 0.02667) (xy 0.2286 0.0381) (xy 0.22733 0.04953)
						(xy 0.22733 0.05969) (xy 0.22606 0.07112) (xy 0.22352 0.08128) (xy 0.22225 0.09144) (xy 0.21844 0.10287)
						(xy 0.2159 0.11303) (xy 0.21209 0.12319) (xy 0.20701 0.13335) (xy 0.2032 0.14224) (xy 0.19812 0.1524)
						(xy 0.17272 0.18796) (xy 0.1651 0.19558) (xy 0.1651 0.7366) (xy 0.16256 0.76835) (xy 0.1524 0.8001)
						(xy 0.13716 0.82804) (xy 0.11684 0.85344) (xy 0.09144 0.87376) (xy 0.0635 0.889) (xy 0.03175 0.89916)
					)
					(width 0)
					(fill yes)
				)
			)
		)
		(pad "105" smd custom
			(at 1.949958 4.106672 180)
			(size 0.1143 0.1143)
			(layers "F.Cu" "F.Mask" "F.Paste")
			(net "M_A_MA1")
			(options
				(clearance outline)
				(anchor circle)
			)
			(primitives
				(gr_poly
					(pts
						(xy 0 0.9017) (xy -0.03175 0.89916) (xy -0.0635 0.889) (xy -0.09144 0.87376) (xy -0.11684 0.85344)
						(xy -0.13716 0.82804) (xy -0.1524 0.8001) (xy -0.16256 0.76835) (xy -0.1651 0.7366) (xy -0.1651 -0.13462)
						(xy -0.17272 -0.14224) (xy -0.19812 -0.1778) (xy -0.2032 -0.18796) (xy -0.20701 -0.19685) (xy -0.21209 -0.20701)
						(xy -0.2159 -0.21717) (xy -0.21844 -0.22733) (xy -0.22225 -0.23876) (xy -0.22352 -0.24892) (xy -0.22606 -0.25908)
						(xy -0.22733 -0.27051) (xy -0.22733 -0.28067) (xy -0.2286 -0.2921) (xy -0.22733 -0.30353) (xy -0.22733 -0.31369)
						(xy -0.22606 -0.32512) (xy -0.22352 -0.33528) (xy -0.22225 -0.34544) (xy -0.21844 -0.35687) (xy -0.2159 -0.36703)
						(xy -0.21209 -0.37719) (xy -0.20701 -0.38735) (xy -0.2032 -0.39624) (xy -0.19812 -0.4064) (xy -0.17272 -0.44196)
						(xy -0.1651 -0.44958) (xy -0.1651 -0.7366) (xy -0.16256 -0.76835) (xy -0.1524 -0.8001) (xy -0.13716 -0.82804)
						(xy -0.11684 -0.85344) (xy -0.09144 -0.87376) (xy -0.0635 -0.889) (xy -0.03175 -0.89916) (xy 0 -0.9017)
						(xy 0.03175 -0.89916) (xy 0.0635 -0.889) (xy 0.09144 -0.87376) (xy 0.11684 -0.85344) (xy 0.13716 -0.82804)
						(xy 0.1524 -0.8001) (xy 0.16256 -0.76835) (xy 0.1651 -0.7366) (xy 0.1651 -0.44958) (xy 0.17272 -0.44196)
						(xy 0.19812 -0.4064) (xy 0.2032 -0.39624) (xy 0.20701 -0.38735) (xy 0.21209 -0.37719) (xy 0.2159 -0.36703)
						(xy 0.21844 -0.35687) (xy 0.22225 -0.34544) (xy 0.22352 -0.33528) (xy 0.22606 -0.32512) (xy 0.22733 -0.31369)
						(xy 0.22733 -0.30353) (xy 0.2286 -0.2921) (xy 0.22733 -0.28067) (xy 0.22733 -0.27051) (xy 0.22606 -0.25908)
						(xy 0.22352 -0.24892) (xy 0.22225 -0.23876) (xy 0.21844 -0.22733) (xy 0.2159 -0.21717) (xy 0.21209 -0.20701)
						(xy 0.20701 -0.19685) (xy 0.2032 -0.18796) (xy 0.19812 -0.1778) (xy 0.17272 -0.14224) (xy 0.1651 -0.13462)
						(xy 0.1651 0.7366) (xy 0.16256 0.76835) (xy 0.1524 0.8001) (xy 0.13716 0.82804) (xy 0.11684 0.85344)
						(xy 0.09144 0.87376) (xy 0.0635 0.889) (xy 0.03175 0.89916)
					)
					(width 0)
					(fill yes)
				)
			)
		)
		(pad "106" smd custom
			(at 2.249932 -4.106672 180)
			(size 0.1143 0.1143)
			(layers "F.Cu" "F.Mask" "F.Paste")
			(net "M_A_MA2")
			(options
				(clearance outline)
				(anchor circle)
			)
			(primitives
				(gr_poly
					(pts
						(xy 0 0.9017) (xy -0.03175 0.89916) (xy -0.0635 0.889) (xy -0.09144 0.87376) (xy -0.11684 0.85344)
						(xy -0.13716 0.82804) (xy -0.1524 0.8001) (xy -0.16256 0.76835) (xy -0.1651 0.7366) (xy -0.1651 0.44958)
						(xy -0.17272 0.44196) (xy -0.19812 0.4064) (xy -0.2032 0.39624) (xy -0.20701 0.38735) (xy -0.21209 0.37719)
						(xy -0.2159 0.36703) (xy -0.21844 0.35687) (xy -0.22225 0.34544) (xy -0.22352 0.33528) (xy -0.22606 0.32512)
						(xy -0.22733 0.31369) (xy -0.22733 0.30353) (xy -0.2286 0.2921) (xy -0.22733 0.28067) (xy -0.22733 0.27051)
						(xy -0.22606 0.25908) (xy -0.22352 0.24892) (xy -0.22225 0.23876) (xy -0.21844 0.22733) (xy -0.2159 0.21717)
						(xy -0.21209 0.20701) (xy -0.20701 0.19685) (xy -0.2032 0.18796) (xy -0.19812 0.1778) (xy -0.17272 0.14224)
						(xy -0.1651 0.13462) (xy -0.1651 -0.7366) (xy -0.16256 -0.76835) (xy -0.1524 -0.8001) (xy -0.13716 -0.82804)
						(xy -0.11684 -0.85344) (xy -0.09144 -0.87376) (xy -0.0635 -0.889) (xy -0.03175 -0.89916) (xy 0 -0.9017)
						(xy 0.03175 -0.89916) (xy 0.0635 -0.889) (xy 0.09144 -0.87376) (xy 0.11684 -0.85344) (xy 0.13716 -0.82804)
						(xy 0.1524 -0.8001) (xy 0.16256 -0.76835) (xy 0.1651 -0.7366) (xy 0.1651 0.13462) (xy 0.17272 0.14224)
						(xy 0.19812 0.1778) (xy 0.2032 0.18796) (xy 0.20701 0.19685) (xy 0.21209 0.20701) (xy 0.2159 0.21717)
						(xy 0.21844 0.22733) (xy 0.22225 0.23876) (xy 0.22352 0.24892) (xy 0.22606 0.25908) (xy 0.22733 0.27051)
						(xy 0.22733 0.28067) (xy 0.2286 0.2921) (xy 0.22733 0.30353) (xy 0.22733 0.31369) (xy 0.22606 0.32512)
						(xy 0.22352 0.33528) (xy 0.22225 0.34544) (xy 0.21844 0.35687) (xy 0.2159 0.36703) (xy 0.21209 0.37719)
						(xy 0.20701 0.38735) (xy 0.2032 0.39624) (xy 0.19812 0.4064) (xy 0.17272 0.44196) (xy 0.1651 0.44958)
						(xy 0.1651 0.7366) (xy 0.16256 0.76835) (xy 0.1524 0.8001) (xy 0.13716 0.82804) (xy 0.11684 0.85344)
						(xy 0.09144 0.87376) (xy 0.0635 0.889) (xy 0.03175 0.89916)
					)
					(width 0)
					(fill yes)
				)
			)
		)
		(pad "107" smd custom
			(at 2.549906 4.106672 180)
			(size 0.1143 0.1143)
			(layers "F.Cu" "F.Mask" "F.Paste")
			(net "M_A_MA0")
			(options
				(clearance outline)
				(anchor circle)
			)
			(primitives
				(gr_poly
					(pts
						(xy 0 0.9017) (xy -0.03175 0.89916) (xy -0.0635 0.889) (xy -0.09144 0.87376) (xy -0.11684 0.85344)
						(xy -0.13716 0.82804) (xy -0.1524 0.8001) (xy -0.16256 0.76835) (xy -0.1651 0.7366) (xy -0.1651 0.11938)
						(xy -0.17272 0.11176) (xy -0.19812 0.0762) (xy -0.2032 0.06604) (xy -0.20701 0.05715) (xy -0.21209 0.04699)
						(xy -0.2159 0.03683) (xy -0.21844 0.02667) (xy -0.22225 0.01524) (xy -0.22352 0.00508) (xy -0.22606 -0.00508)
						(xy -0.22733 -0.01651) (xy -0.22733 -0.02667) (xy -0.2286 -0.0381) (xy -0.22733 -0.04953) (xy -0.22733 -0.05969)
						(xy -0.22606 -0.07112) (xy -0.22352 -0.08128) (xy -0.22225 -0.09144) (xy -0.21844 -0.10287) (xy -0.2159 -0.11303)
						(xy -0.21209 -0.12319) (xy -0.20701 -0.13335) (xy -0.2032 -0.14224) (xy -0.19812 -0.1524) (xy -0.17272 -0.18796)
						(xy -0.1651 -0.19558) (xy -0.1651 -0.7366) (xy -0.16256 -0.76835) (xy -0.1524 -0.8001) (xy -0.13716 -0.82804)
						(xy -0.11684 -0.85344) (xy -0.09144 -0.87376) (xy -0.0635 -0.889) (xy -0.03175 -0.89916) (xy 0 -0.9017)
						(xy 0.03175 -0.89916) (xy 0.0635 -0.889) (xy 0.09144 -0.87376) (xy 0.11684 -0.85344) (xy 0.13716 -0.82804)
						(xy 0.1524 -0.8001) (xy 0.16256 -0.76835) (xy 0.1651 -0.7366) (xy 0.1651 -0.19685) (xy 0.17272 -0.18923)
						(xy 0.17907 -0.18034) (xy 0.18669 -0.17145) (xy 0.19177 -0.16256) (xy 0.19812 -0.15367) (xy 0.20828 -0.13335)
						(xy 0.21971 -0.10287) (xy 0.22225 -0.09271) (xy 0.22479 -0.08128) (xy 0.22606 -0.07112) (xy 0.2286 -0.05969)
						(xy 0.2286 -0.01651) (xy 0.22606 -0.00508) (xy 0.22479 0.00508) (xy 0.22225 0.01651) (xy 0.21971 0.02667)
						(xy 0.20828 0.05715) (xy 0.19812 0.07747) (xy 0.19177 0.08636) (xy 0.18669 0.09525) (xy 0.17907 0.10414)
						(xy 0.17272 0.11303) (xy 0.1651 0.12065) (xy 0.1651 0.7366) (xy 0.16256 0.76835) (xy 0.1524 0.8001)
						(xy 0.13716 0.82804) (xy 0.11684 0.85344) (xy 0.09144 0.87376) (xy 0.0635 0.889) (xy 0.03175 0.89916)
					)
					(width 0)
					(fill yes)
				)
			)
		)
		(pad "108" smd custom
			(at 2.84988 -4.106672 180)
			(size 0.1143 0.1143)
			(layers "F.Cu" "F.Mask" "F.Paste")
			(net "M_A_BS1")
			(options
				(clearance outline)
				(anchor circle)
			)
			(primitives
				(gr_poly
					(pts
						(xy 0 0.9017) (xy -0.03175 0.89916) (xy -0.0635 0.889) (xy -0.09144 0.87376) (xy -0.11684 0.85344)
						(xy -0.13716 0.82804) (xy -0.1524 0.8001) (xy -0.16256 0.76835) (xy -0.1651 0.7366) (xy -0.1651 0.19685)
						(xy -0.17272 0.18923) (xy -0.17907 0.18034) (xy -0.18669 0.17145) (xy -0.19177 0.16256) (xy -0.19812 0.15367)
						(xy -0.20828 0.13335) (xy -0.21971 0.10287) (xy -0.22225 0.09271) (xy -0.22479 0.08128) (xy -0.22606 0.07112)
						(xy -0.2286 0.05969) (xy -0.2286 0.01651) (xy -0.22606 0.00508) (xy -0.22479 -0.00508) (xy -0.22225 -0.01651)
						(xy -0.21971 -0.02667) (xy -0.20828 -0.05715) (xy -0.19812 -0.07747) (xy -0.19177 -0.08636) (xy -0.18669 -0.09525)
						(xy -0.17907 -0.10414) (xy -0.17272 -0.11303) (xy -0.1651 -0.12065) (xy -0.1651 -0.7366) (xy -0.16256 -0.76835)
						(xy -0.1524 -0.8001) (xy -0.13716 -0.82804) (xy -0.11684 -0.85344) (xy -0.09144 -0.87376) (xy -0.0635 -0.889)
						(xy -0.03175 -0.89916) (xy 0 -0.9017) (xy 0.03175 -0.89916) (xy 0.0635 -0.889) (xy 0.09144 -0.87376)
						(xy 0.11684 -0.85344) (xy 0.13716 -0.82804) (xy 0.1524 -0.8001) (xy 0.16256 -0.76835) (xy 0.1651 -0.7366)
						(xy 0.1651 -0.11938) (xy 0.17272 -0.11176) (xy 0.19812 -0.0762) (xy 0.2032 -0.06604) (xy 0.20701 -0.05715)
						(xy 0.21209 -0.04699) (xy 0.2159 -0.03683) (xy 0.21844 -0.02667) (xy 0.22225 -0.01524) (xy 0.22352 -0.00508)
						(xy 0.22606 0.00508) (xy 0.22733 0.01651) (xy 0.22733 0.02667) (xy 0.2286 0.0381) (xy 0.22733 0.04953)
						(xy 0.22733 0.05969) (xy 0.22606 0.07112) (xy 0.22352 0.08128) (xy 0.22225 0.09144) (xy 0.21844 0.10287)
						(xy 0.2159 0.11303) (xy 0.21209 0.12319) (xy 0.20701 0.13335) (xy 0.2032 0.14224) (xy 0.19812 0.1524)
						(xy 0.17272 0.18796) (xy 0.1651 0.19558) (xy 0.1651 0.7366) (xy 0.16256 0.76835) (xy 0.1524 0.8001)
						(xy 0.13716 0.82804) (xy 0.11684 0.85344) (xy 0.09144 0.87376) (xy 0.0635 0.889) (xy 0.03175 0.89916)
					)
					(width 0)
					(fill yes)
				)
			)
		)
		(pad "109" smd custom
			(at 3.150108 4.106672 180)
			(size 0.1143 0.1143)
			(layers "F.Cu" "F.Mask" "F.Paste")
			(net "PV_VDDR")
			(options
				(clearance outline)
				(anchor circle)
			)
			(primitives
				(gr_poly
					(pts
						(xy 0 0.9017) (xy -0.03175 0.89916) (xy -0.0635 0.889) (xy -0.09144 0.87376) (xy -0.11684 0.85344)
						(xy -0.13716 0.82804) (xy -0.1524 0.8001) (xy -0.16256 0.76835) (xy -0.1651 0.7366) (xy -0.1651 -0.13462)
						(xy -0.17272 -0.14224) (xy -0.19812 -0.1778) (xy -0.2032 -0.18796) (xy -0.20701 -0.19685) (xy -0.21209 -0.20701)
						(xy -0.2159 -0.21717) (xy -0.21844 -0.22733) (xy -0.22225 -0.23876) (xy -0.22352 -0.24892) (xy -0.22606 -0.25908)
						(xy -0.22733 -0.27051) (xy -0.22733 -0.28067) (xy -0.2286 -0.2921) (xy -0.22733 -0.30353) (xy -0.22733 -0.31369)
						(xy -0.22606 -0.32512) (xy -0.22352 -0.33528) (xy -0.22225 -0.34544) (xy -0.21844 -0.35687) (xy -0.2159 -0.36703)
						(xy -0.21209 -0.37719) (xy -0.20701 -0.38735) (xy -0.2032 -0.39624) (xy -0.19812 -0.4064) (xy -0.17272 -0.44196)
						(xy -0.1651 -0.44958) (xy -0.1651 -0.7366) (xy -0.16256 -0.76835) (xy -0.1524 -0.8001) (xy -0.13716 -0.82804)
						(xy -0.11684 -0.85344) (xy -0.09144 -0.87376) (xy -0.0635 -0.889) (xy -0.03175 -0.89916) (xy 0 -0.9017)
						(xy 0.03175 -0.89916) (xy 0.0635 -0.889) (xy 0.09144 -0.87376) (xy 0.11684 -0.85344) (xy 0.13716 -0.82804)
						(xy 0.1524 -0.8001) (xy 0.16256 -0.76835) (xy 0.1651 -0.7366) (xy 0.1651 -0.44958) (xy 0.17272 -0.44196)
						(xy 0.19812 -0.4064) (xy 0.2032 -0.39624) (xy 0.20701 -0.38735) (xy 0.21209 -0.37719) (xy 0.2159 -0.36703)
						(xy 0.21844 -0.35687) (xy 0.22225 -0.34544) (xy 0.22352 -0.33528) (xy 0.22606 -0.32512) (xy 0.22733 -0.31369)
						(xy 0.22733 -0.30353) (xy 0.2286 -0.2921) (xy 0.22733 -0.28067) (xy 0.22733 -0.27051) (xy 0.22606 -0.25908)
						(xy 0.22352 -0.24892) (xy 0.22225 -0.23876) (xy 0.21844 -0.22733) (xy 0.2159 -0.21717) (xy 0.21209 -0.20701)
						(xy 0.20701 -0.19685) (xy 0.2032 -0.18796) (xy 0.19812 -0.1778) (xy 0.17272 -0.14224) (xy 0.1651 -0.13462)
						(xy 0.1651 0.7366) (xy 0.16256 0.76835) (xy 0.1524 0.8001) (xy 0.13716 0.82804) (xy 0.11684 0.85344)
						(xy 0.09144 0.87376) (xy 0.0635 0.889) (xy 0.03175 0.89916)
					)
					(width 0)
					(fill yes)
				)
			)
		)
		(pad "110" smd custom
			(at 3.450082 -4.106672 180)
			(size 0.1143 0.1143)
			(layers "F.Cu" "F.Mask" "F.Paste")
			(net "PV_VDDR")
			(options
				(clearance outline)
				(anchor circle)
			)
			(primitives
				(gr_poly
					(pts
						(xy 0 0.9017) (xy -0.03175 0.89916) (xy -0.0635 0.889) (xy -0.09144 0.87376) (xy -0.11684 0.85344)
						(xy -0.13716 0.82804) (xy -0.1524 0.8001) (xy -0.16256 0.76835) (xy -0.1651 0.7366) (xy -0.1651 0.44958)
						(xy -0.17272 0.44196) (xy -0.19812 0.4064) (xy -0.2032 0.39624) (xy -0.20701 0.38735) (xy -0.21209 0.37719)
						(xy -0.2159 0.36703) (xy -0.21844 0.35687) (xy -0.22225 0.34544) (xy -0.22352 0.33528) (xy -0.22606 0.32512)
						(xy -0.22733 0.31369) (xy -0.22733 0.30353) (xy -0.2286 0.2921) (xy -0.22733 0.28067) (xy -0.22733 0.27051)
						(xy -0.22606 0.25908) (xy -0.22352 0.24892) (xy -0.22225 0.23876) (xy -0.21844 0.22733) (xy -0.2159 0.21717)
						(xy -0.21209 0.20701) (xy -0.20701 0.19685) (xy -0.2032 0.18796) (xy -0.19812 0.1778) (xy -0.17272 0.14224)
						(xy -0.1651 0.13462) (xy -0.1651 -0.7366) (xy -0.16256 -0.76835) (xy -0.1524 -0.8001) (xy -0.13716 -0.82804)
						(xy -0.11684 -0.85344) (xy -0.09144 -0.87376) (xy -0.0635 -0.889) (xy -0.03175 -0.89916) (xy 0 -0.9017)
						(xy 0.03175 -0.89916) (xy 0.0635 -0.889) (xy 0.09144 -0.87376) (xy 0.11684 -0.85344) (xy 0.13716 -0.82804)
						(xy 0.1524 -0.8001) (xy 0.16256 -0.76835) (xy 0.1651 -0.7366) (xy 0.1651 0.13462) (xy 0.17272 0.14224)
						(xy 0.19812 0.1778) (xy 0.2032 0.18796) (xy 0.20701 0.19685) (xy 0.21209 0.20701) (xy 0.2159 0.21717)
						(xy 0.21844 0.22733) (xy 0.22225 0.23876) (xy 0.22352 0.24892) (xy 0.22606 0.25908) (xy 0.22733 0.27051)
						(xy 0.22733 0.28067) (xy 0.2286 0.2921) (xy 0.22733 0.30353) (xy 0.22733 0.31369) (xy 0.22606 0.32512)
						(xy 0.22352 0.33528) (xy 0.22225 0.34544) (xy 0.21844 0.35687) (xy 0.2159 0.36703) (xy 0.21209 0.37719)
						(xy 0.20701 0.38735) (xy 0.2032 0.39624) (xy 0.19812 0.4064) (xy 0.17272 0.44196) (xy 0.1651 0.44958)
						(xy 0.1651 0.7366) (xy 0.16256 0.76835) (xy 0.1524 0.8001) (xy 0.13716 0.82804) (xy 0.11684 0.85344)
						(xy 0.09144 0.87376) (xy 0.0635 0.889) (xy 0.03175 0.89916)
					)
					(width 0)
					(fill yes)
				)
			)
		)
		(pad "111" smd custom
			(at 3.750056 4.106672 180)
			(size 0.1143 0.1143)
			(layers "F.Cu" "F.Mask" "F.Paste")
			(net "M_A_CK_DP2")
			(options
				(clearance outline)
				(anchor circle)
			)
			(primitives
				(gr_poly
					(pts
						(xy 0 0.9017) (xy -0.03175 0.89916) (xy -0.0635 0.889) (xy -0.09144 0.87376) (xy -0.11684 0.85344)
						(xy -0.13716 0.82804) (xy -0.1524 0.8001) (xy -0.16256 0.76835) (xy -0.1651 0.7366) (xy -0.1651 0.11938)
						(xy -0.17272 0.11176) (xy -0.19812 0.0762) (xy -0.2032 0.06604) (xy -0.20701 0.05715) (xy -0.21209 0.04699)
						(xy -0.2159 0.03683) (xy -0.21844 0.02667) (xy -0.22225 0.01524) (xy -0.22352 0.00508) (xy -0.22606 -0.00508)
						(xy -0.22733 -0.01651) (xy -0.22733 -0.02667) (xy -0.2286 -0.0381) (xy -0.22733 -0.04953) (xy -0.22733 -0.05969)
						(xy -0.22606 -0.07112) (xy -0.22352 -0.08128) (xy -0.22225 -0.09144) (xy -0.21844 -0.10287) (xy -0.2159 -0.11303)
						(xy -0.21209 -0.12319) (xy -0.20701 -0.13335) (xy -0.2032 -0.14224) (xy -0.19812 -0.1524) (xy -0.17272 -0.18796)
						(xy -0.1651 -0.19558) (xy -0.1651 -0.7366) (xy -0.16256 -0.76835) (xy -0.1524 -0.8001) (xy -0.13716 -0.82804)
						(xy -0.11684 -0.85344) (xy -0.09144 -0.87376) (xy -0.0635 -0.889) (xy -0.03175 -0.89916) (xy 0 -0.9017)
						(xy 0.03175 -0.89916) (xy 0.0635 -0.889) (xy 0.09144 -0.87376) (xy 0.11684 -0.85344) (xy 0.13716 -0.82804)
						(xy 0.1524 -0.8001) (xy 0.16256 -0.76835) (xy 0.1651 -0.7366) (xy 0.1651 -0.19685) (xy 0.17272 -0.18923)
						(xy 0.17907 -0.18034) (xy 0.18669 -0.17145) (xy 0.19177 -0.16256) (xy 0.19812 -0.15367) (xy 0.20828 -0.13335)
						(xy 0.21971 -0.10287) (xy 0.22225 -0.09271) (xy 0.22479 -0.08128) (xy 0.22606 -0.07112) (xy 0.2286 -0.05969)
						(xy 0.2286 -0.01651) (xy 0.22606 -0.00508) (xy 0.22479 0.00508) (xy 0.22225 0.01651) (xy 0.21971 0.02667)
						(xy 0.20828 0.05715) (xy 0.19812 0.07747) (xy 0.19177 0.08636) (xy 0.18669 0.09525) (xy 0.17907 0.10414)
						(xy 0.17272 0.11303) (xy 0.1651 0.12065) (xy 0.1651 0.7366) (xy 0.16256 0.76835) (xy 0.1524 0.8001)
						(xy 0.13716 0.82804) (xy 0.11684 0.85344) (xy 0.09144 0.87376) (xy 0.0635 0.889) (xy 0.03175 0.89916)
					)
					(width 0)
					(fill yes)
				)
			)
		)
		(pad "112" smd custom
			(at 4.05003 -4.106672 180)
			(size 0.1143 0.1143)
			(layers "F.Cu" "F.Mask" "F.Paste")
			(net "M_A_CK_DP3")
			(options
				(clearance outline)
				(anchor circle)
			)
			(primitives
				(gr_poly
					(pts
						(xy 0 0.9017) (xy -0.03175 0.89916) (xy -0.0635 0.889) (xy -0.09144 0.87376) (xy -0.11684 0.85344)
						(xy -0.13716 0.82804) (xy -0.1524 0.8001) (xy -0.16256 0.76835) (xy -0.1651 0.7366) (xy -0.1651 0.19685)
						(xy -0.17272 0.18923) (xy -0.17907 0.18034) (xy -0.18669 0.17145) (xy -0.19177 0.16256) (xy -0.19812 0.15367)
						(xy -0.20828 0.13335) (xy -0.21971 0.10287) (xy -0.22225 0.09271) (xy -0.22479 0.08128) (xy -0.22606 0.07112)
						(xy -0.2286 0.05969) (xy -0.2286 0.01651) (xy -0.22606 0.00508) (xy -0.22479 -0.00508) (xy -0.22225 -0.01651)
						(xy -0.21971 -0.02667) (xy -0.20828 -0.05715) (xy -0.19812 -0.07747) (xy -0.19177 -0.08636) (xy -0.18669 -0.09525)
						(xy -0.17907 -0.10414) (xy -0.17272 -0.11303) (xy -0.1651 -0.12065) (xy -0.1651 -0.7366) (xy -0.16256 -0.76835)
						(xy -0.1524 -0.8001) (xy -0.13716 -0.82804) (xy -0.11684 -0.85344) (xy -0.09144 -0.87376) (xy -0.0635 -0.889)
						(xy -0.03175 -0.89916) (xy 0 -0.9017) (xy 0.03175 -0.89916) (xy 0.0635 -0.889) (xy 0.09144 -0.87376)
						(xy 0.11684 -0.85344) (xy 0.13716 -0.82804) (xy 0.1524 -0.8001) (xy 0.16256 -0.76835) (xy 0.1651 -0.7366)
						(xy 0.1651 -0.11938) (xy 0.17272 -0.11176) (xy 0.19812 -0.0762) (xy 0.2032 -0.06604) (xy 0.20701 -0.05715)
						(xy 0.21209 -0.04699) (xy 0.2159 -0.03683) (xy 0.21844 -0.02667) (xy 0.22225 -0.01524) (xy 0.22352 -0.00508)
						(xy 0.22606 0.00508) (xy 0.22733 0.01651) (xy 0.22733 0.02667) (xy 0.2286 0.0381) (xy 0.22733 0.04953)
						(xy 0.22733 0.05969) (xy 0.22606 0.07112) (xy 0.22352 0.08128) (xy 0.22225 0.09144) (xy 0.21844 0.10287)
						(xy 0.2159 0.11303) (xy 0.21209 0.12319) (xy 0.20701 0.13335) (xy 0.2032 0.14224) (xy 0.19812 0.1524)
						(xy 0.17272 0.18796) (xy 0.1651 0.19558) (xy 0.1651 0.7366) (xy 0.16256 0.76835) (xy 0.1524 0.8001)
						(xy 0.13716 0.82804) (xy 0.11684 0.85344) (xy 0.09144 0.87376) (xy 0.0635 0.889) (xy 0.03175 0.89916)
					)
					(width 0)
					(fill yes)
				)
			)
		)
		(pad "113" smd custom
			(at 4.350004 4.106672 180)
			(size 0.1143 0.1143)
			(layers "F.Cu" "F.Mask" "F.Paste")
			(net "M_A_CK_DN2")
			(options
				(clearance outline)
				(anchor circle)
			)
			(primitives
				(gr_poly
					(pts
						(xy 0 0.9017) (xy -0.03175 0.89916) (xy -0.0635 0.889) (xy -0.09144 0.87376) (xy -0.11684 0.85344)
						(xy -0.13716 0.82804) (xy -0.1524 0.8001) (xy -0.16256 0.76835) (xy -0.1651 0.7366) (xy -0.1651 -0.13462)
						(xy -0.17272 -0.14224) (xy -0.19812 -0.1778) (xy -0.2032 -0.18796) (xy -0.20701 -0.19685) (xy -0.21209 -0.20701)
						(xy -0.2159 -0.21717) (xy -0.21844 -0.22733) (xy -0.22225 -0.23876) (xy -0.22352 -0.24892) (xy -0.22606 -0.25908)
						(xy -0.22733 -0.27051) (xy -0.22733 -0.28067) (xy -0.2286 -0.2921) (xy -0.22733 -0.30353) (xy -0.22733 -0.31369)
						(xy -0.22606 -0.32512) (xy -0.22352 -0.33528) (xy -0.22225 -0.34544) (xy -0.21844 -0.35687) (xy -0.2159 -0.36703)
						(xy -0.21209 -0.37719) (xy -0.20701 -0.38735) (xy -0.2032 -0.39624) (xy -0.19812 -0.4064) (xy -0.17272 -0.44196)
						(xy -0.1651 -0.44958) (xy -0.1651 -0.7366) (xy -0.16256 -0.76835) (xy -0.1524 -0.8001) (xy -0.13716 -0.82804)
						(xy -0.11684 -0.85344) (xy -0.09144 -0.87376) (xy -0.0635 -0.889) (xy -0.03175 -0.89916) (xy 0 -0.9017)
						(xy 0.03175 -0.89916) (xy 0.0635 -0.889) (xy 0.09144 -0.87376) (xy 0.11684 -0.85344) (xy 0.13716 -0.82804)
						(xy 0.1524 -0.8001) (xy 0.16256 -0.76835) (xy 0.1651 -0.7366) (xy 0.1651 -0.44958) (xy 0.17272 -0.44196)
						(xy 0.19812 -0.4064) (xy 0.2032 -0.39624) (xy 0.20701 -0.38735) (xy 0.21209 -0.37719) (xy 0.2159 -0.36703)
						(xy 0.21844 -0.35687) (xy 0.22225 -0.34544) (xy 0.22352 -0.33528) (xy 0.22606 -0.32512) (xy 0.22733 -0.31369)
						(xy 0.22733 -0.30353) (xy 0.2286 -0.2921) (xy 0.22733 -0.28067) (xy 0.22733 -0.27051) (xy 0.22606 -0.25908)
						(xy 0.22352 -0.24892) (xy 0.22225 -0.23876) (xy 0.21844 -0.22733) (xy 0.2159 -0.21717) (xy 0.21209 -0.20701)
						(xy 0.20701 -0.19685) (xy 0.2032 -0.18796) (xy 0.19812 -0.1778) (xy 0.17272 -0.14224) (xy 0.1651 -0.13462)
						(xy 0.1651 0.7366) (xy 0.16256 0.76835) (xy 0.1524 0.8001) (xy 0.13716 0.82804) (xy 0.11684 0.85344)
						(xy 0.09144 0.87376) (xy 0.0635 0.889) (xy 0.03175 0.89916)
					)
					(width 0)
					(fill yes)
				)
			)
		)
		(pad "114" smd custom
			(at 4.649978 -4.106672 180)
			(size 0.1143 0.1143)
			(layers "F.Cu" "F.Mask" "F.Paste")
			(net "M_A_CK_DN3")
			(options
				(clearance outline)
				(anchor circle)
			)
			(primitives
				(gr_poly
					(pts
						(xy 0 0.9017) (xy -0.03175 0.89916) (xy -0.0635 0.889) (xy -0.09144 0.87376) (xy -0.11684 0.85344)
						(xy -0.13716 0.82804) (xy -0.1524 0.8001) (xy -0.16256 0.76835) (xy -0.1651 0.7366) (xy -0.1651 0.44958)
						(xy -0.17272 0.44196) (xy -0.19812 0.4064) (xy -0.2032 0.39624) (xy -0.20701 0.38735) (xy -0.21209 0.37719)
						(xy -0.2159 0.36703) (xy -0.21844 0.35687) (xy -0.22225 0.34544) (xy -0.22352 0.33528) (xy -0.22606 0.32512)
						(xy -0.22733 0.31369) (xy -0.22733 0.30353) (xy -0.2286 0.2921) (xy -0.22733 0.28067) (xy -0.22733 0.27051)
						(xy -0.22606 0.25908) (xy -0.22352 0.24892) (xy -0.22225 0.23876) (xy -0.21844 0.22733) (xy -0.2159 0.21717)
						(xy -0.21209 0.20701) (xy -0.20701 0.19685) (xy -0.2032 0.18796) (xy -0.19812 0.1778) (xy -0.17272 0.14224)
						(xy -0.1651 0.13462) (xy -0.1651 -0.7366) (xy -0.16256 -0.76835) (xy -0.1524 -0.8001) (xy -0.13716 -0.82804)
						(xy -0.11684 -0.85344) (xy -0.09144 -0.87376) (xy -0.0635 -0.889) (xy -0.03175 -0.89916) (xy 0 -0.9017)
						(xy 0.03175 -0.89916) (xy 0.0635 -0.889) (xy 0.09144 -0.87376) (xy 0.11684 -0.85344) (xy 0.13716 -0.82804)
						(xy 0.1524 -0.8001) (xy 0.16256 -0.76835) (xy 0.1651 -0.7366) (xy 0.1651 0.13462) (xy 0.17272 0.14224)
						(xy 0.19812 0.1778) (xy 0.2032 0.18796) (xy 0.20701 0.19685) (xy 0.21209 0.20701) (xy 0.2159 0.21717)
						(xy 0.21844 0.22733) (xy 0.22225 0.23876) (xy 0.22352 0.24892) (xy 0.22606 0.25908) (xy 0.22733 0.27051)
						(xy 0.22733 0.28067) (xy 0.2286 0.2921) (xy 0.22733 0.30353) (xy 0.22733 0.31369) (xy 0.22606 0.32512)
						(xy 0.22352 0.33528) (xy 0.22225 0.34544) (xy 0.21844 0.35687) (xy 0.2159 0.36703) (xy 0.21209 0.37719)
						(xy 0.20701 0.38735) (xy 0.2032 0.39624) (xy 0.19812 0.4064) (xy 0.17272 0.44196) (xy 0.1651 0.44958)
						(xy 0.1651 0.7366) (xy 0.16256 0.76835) (xy 0.1524 0.8001) (xy 0.13716 0.82804) (xy 0.11684 0.85344)
						(xy 0.09144 0.87376) (xy 0.0635 0.889) (xy 0.03175 0.89916)
					)
					(width 0)
					(fill yes)
				)
			)
		)
		(pad "115" smd custom
			(at 4.949952 4.106672 180)
			(size 0.1143 0.1143)
			(layers "F.Cu" "F.Mask" "F.Paste")
			(net "PV_VDDR")
			(options
				(clearance outline)
				(anchor circle)
			)
			(primitives
				(gr_poly
					(pts
						(xy 0 0.9017) (xy -0.03175 0.89916) (xy -0.0635 0.889) (xy -0.09144 0.87376) (xy -0.11684 0.85344)
						(xy -0.13716 0.82804) (xy -0.1524 0.8001) (xy -0.16256 0.76835) (xy -0.1651 0.7366) (xy -0.1651 0.11938)
						(xy -0.17272 0.11176) (xy -0.19812 0.0762) (xy -0.2032 0.06604) (xy -0.20701 0.05715) (xy -0.21209 0.04699)
						(xy -0.2159 0.03683) (xy -0.21844 0.02667) (xy -0.22225 0.01524) (xy -0.22352 0.00508) (xy -0.22606 -0.00508)
						(xy -0.22733 -0.01651) (xy -0.22733 -0.02667) (xy -0.2286 -0.0381) (xy -0.22733 -0.04953) (xy -0.22733 -0.05969)
						(xy -0.22606 -0.07112) (xy -0.22352 -0.08128) (xy -0.22225 -0.09144) (xy -0.21844 -0.10287) (xy -0.2159 -0.11303)
						(xy -0.21209 -0.12319) (xy -0.20701 -0.13335) (xy -0.2032 -0.14224) (xy -0.19812 -0.1524) (xy -0.17272 -0.18796)
						(xy -0.1651 -0.19558) (xy -0.1651 -0.7366) (xy -0.16256 -0.76835) (xy -0.1524 -0.8001) (xy -0.13716 -0.82804)
						(xy -0.11684 -0.85344) (xy -0.09144 -0.87376) (xy -0.0635 -0.889) (xy -0.03175 -0.89916) (xy 0 -0.9017)
						(xy 0.03175 -0.89916) (xy 0.0635 -0.889) (xy 0.09144 -0.87376) (xy 0.11684 -0.85344) (xy 0.13716 -0.82804)
						(xy 0.1524 -0.8001) (xy 0.16256 -0.76835) (xy 0.1651 -0.7366) (xy 0.1651 -0.19685) (xy 0.17272 -0.18923)
						(xy 0.17907 -0.18034) (xy 0.18669 -0.17145) (xy 0.19177 -0.16256) (xy 0.19812 -0.15367) (xy 0.20828 -0.13335)
						(xy 0.21971 -0.10287) (xy 0.22225 -0.09271) (xy 0.22479 -0.08128) (xy 0.22606 -0.07112) (xy 0.2286 -0.05969)
						(xy 0.2286 -0.01651) (xy 0.22606 -0.00508) (xy 0.22479 0.00508) (xy 0.22225 0.01651) (xy 0.21971 0.02667)
						(xy 0.20828 0.05715) (xy 0.19812 0.07747) (xy 0.19177 0.08636) (xy 0.18669 0.09525) (xy 0.17907 0.10414)
						(xy 0.17272 0.11303) (xy 0.1651 0.12065) (xy 0.1651 0.7366) (xy 0.16256 0.76835) (xy 0.1524 0.8001)
						(xy 0.13716 0.82804) (xy 0.11684 0.85344) (xy 0.09144 0.87376) (xy 0.0635 0.889) (xy 0.03175 0.89916)
					)
					(width 0)
					(fill yes)
				)
			)
		)
		(pad "116" smd custom
			(at 5.249926 -4.106672 180)
			(size 0.1143 0.1143)
			(layers "F.Cu" "F.Mask" "F.Paste")
			(net "PV_VDDR")
			(options
				(clearance outline)
				(anchor circle)
			)
			(primitives
				(gr_poly
					(pts
						(xy 0 0.9017) (xy -0.03175 0.89916) (xy -0.0635 0.889) (xy -0.09144 0.87376) (xy -0.11684 0.85344)
						(xy -0.13716 0.82804) (xy -0.1524 0.8001) (xy -0.16256 0.76835) (xy -0.1651 0.7366) (xy -0.1651 0.19685)
						(xy -0.17272 0.18923) (xy -0.17907 0.18034) (xy -0.18669 0.17145) (xy -0.19177 0.16256) (xy -0.19812 0.15367)
						(xy -0.20828 0.13335) (xy -0.21971 0.10287) (xy -0.22225 0.09271) (xy -0.22479 0.08128) (xy -0.22606 0.07112)
						(xy -0.2286 0.05969) (xy -0.2286 0.01651) (xy -0.22606 0.00508) (xy -0.22479 -0.00508) (xy -0.22225 -0.01651)
						(xy -0.21971 -0.02667) (xy -0.20828 -0.05715) (xy -0.19812 -0.07747) (xy -0.19177 -0.08636) (xy -0.18669 -0.09525)
						(xy -0.17907 -0.10414) (xy -0.17272 -0.11303) (xy -0.1651 -0.12065) (xy -0.1651 -0.7366) (xy -0.16256 -0.76835)
						(xy -0.1524 -0.8001) (xy -0.13716 -0.82804) (xy -0.11684 -0.85344) (xy -0.09144 -0.87376) (xy -0.0635 -0.889)
						(xy -0.03175 -0.89916) (xy 0 -0.9017) (xy 0.03175 -0.89916) (xy 0.0635 -0.889) (xy 0.09144 -0.87376)
						(xy 0.11684 -0.85344) (xy 0.13716 -0.82804) (xy 0.1524 -0.8001) (xy 0.16256 -0.76835) (xy 0.1651 -0.7366)
						(xy 0.1651 -0.11938) (xy 0.17272 -0.11176) (xy 0.19812 -0.0762) (xy 0.2032 -0.06604) (xy 0.20701 -0.05715)
						(xy 0.21209 -0.04699) (xy 0.2159 -0.03683) (xy 0.21844 -0.02667) (xy 0.22225 -0.01524) (xy 0.22352 -0.00508)
						(xy 0.22606 0.00508) (xy 0.22733 0.01651) (xy 0.22733 0.02667) (xy 0.2286 0.0381) (xy 0.22733 0.04953)
						(xy 0.22733 0.05969) (xy 0.22606 0.07112) (xy 0.22352 0.08128) (xy 0.22225 0.09144) (xy 0.21844 0.10287)
						(xy 0.2159 0.11303) (xy 0.21209 0.12319) (xy 0.20701 0.13335) (xy 0.2032 0.14224) (xy 0.19812 0.1524)
						(xy 0.17272 0.18796) (xy 0.1651 0.19558) (xy 0.1651 0.7366) (xy 0.16256 0.76835) (xy 0.1524 0.8001)
						(xy 0.13716 0.82804) (xy 0.11684 0.85344) (xy 0.09144 0.87376) (xy 0.0635 0.889) (xy 0.03175 0.89916)
					)
					(width 0)
					(fill yes)
				)
			)
		)
		(pad "117" smd custom
			(at 5.5499 4.106672 180)
			(size 0.1143 0.1143)
			(layers "F.Cu" "F.Mask" "F.Paste")
			(net "M_A_MA10")
			(options
				(clearance outline)
				(anchor circle)
			)
			(primitives
				(gr_poly
					(pts
						(xy 0 0.9017) (xy -0.03175 0.89916) (xy -0.0635 0.889) (xy -0.09144 0.87376) (xy -0.11684 0.85344)
						(xy -0.13716 0.82804) (xy -0.1524 0.8001) (xy -0.16256 0.76835) (xy -0.1651 0.7366) (xy -0.1651 -0.13462)
						(xy -0.17272 -0.14224) (xy -0.19812 -0.1778) (xy -0.2032 -0.18796) (xy -0.20701 -0.19685) (xy -0.21209 -0.20701)
						(xy -0.2159 -0.21717) (xy -0.21844 -0.22733) (xy -0.22225 -0.23876) (xy -0.22352 -0.24892) (xy -0.22606 -0.25908)
						(xy -0.22733 -0.27051) (xy -0.22733 -0.28067) (xy -0.2286 -0.2921) (xy -0.22733 -0.30353) (xy -0.22733 -0.31369)
						(xy -0.22606 -0.32512) (xy -0.22352 -0.33528) (xy -0.22225 -0.34544) (xy -0.21844 -0.35687) (xy -0.2159 -0.36703)
						(xy -0.21209 -0.37719) (xy -0.20701 -0.38735) (xy -0.2032 -0.39624) (xy -0.19812 -0.4064) (xy -0.17272 -0.44196)
						(xy -0.1651 -0.44958) (xy -0.1651 -0.7366) (xy -0.16256 -0.76835) (xy -0.1524 -0.8001) (xy -0.13716 -0.82804)
						(xy -0.11684 -0.85344) (xy -0.09144 -0.87376) (xy -0.0635 -0.889) (xy -0.03175 -0.89916) (xy 0 -0.9017)
						(xy 0.03175 -0.89916) (xy 0.0635 -0.889) (xy 0.09144 -0.87376) (xy 0.11684 -0.85344) (xy 0.13716 -0.82804)
						(xy 0.1524 -0.8001) (xy 0.16256 -0.76835) (xy 0.1651 -0.7366) (xy 0.1651 -0.44958) (xy 0.17272 -0.44196)
						(xy 0.19812 -0.4064) (xy 0.2032 -0.39624) (xy 0.20701 -0.38735) (xy 0.21209 -0.37719) (xy 0.2159 -0.36703)
						(xy 0.21844 -0.35687) (xy 0.22225 -0.34544) (xy 0.22352 -0.33528) (xy 0.22606 -0.32512) (xy 0.22733 -0.31369)
						(xy 0.22733 -0.30353) (xy 0.2286 -0.2921) (xy 0.22733 -0.28067) (xy 0.22733 -0.27051) (xy 0.22606 -0.25908)
						(xy 0.22352 -0.24892) (xy 0.22225 -0.23876) (xy 0.21844 -0.22733) (xy 0.2159 -0.21717) (xy 0.21209 -0.20701)
						(xy 0.20701 -0.19685) (xy 0.2032 -0.18796) (xy 0.19812 -0.1778) (xy 0.17272 -0.14224) (xy 0.1651 -0.13462)
						(xy 0.1651 0.7366) (xy 0.16256 0.76835) (xy 0.1524 0.8001) (xy 0.13716 0.82804) (xy 0.11684 0.85344)
						(xy 0.09144 0.87376) (xy 0.0635 0.889) (xy 0.03175 0.89916)
					)
					(width 0)
					(fill yes)
				)
			)
		)
		(pad "118" smd custom
			(at 5.849874 -4.106672 180)
			(size 0.1143 0.1143)
			(layers "F.Cu" "F.Mask" "F.Paste")
			(net "Net_12")
			(options
				(clearance outline)
				(anchor circle)
			)
			(primitives
				(gr_poly
					(pts
						(xy 0 0.9017) (xy -0.03175 0.89916) (xy -0.0635 0.889) (xy -0.09144 0.87376) (xy -0.11684 0.85344)
						(xy -0.13716 0.82804) (xy -0.1524 0.8001) (xy -0.16256 0.76835) (xy -0.1651 0.7366) (xy -0.1651 0.44958)
						(xy -0.17272 0.44196) (xy -0.19812 0.4064) (xy -0.2032 0.39624) (xy -0.20701 0.38735) (xy -0.21209 0.37719)
						(xy -0.2159 0.36703) (xy -0.21844 0.35687) (xy -0.22225 0.34544) (xy -0.22352 0.33528) (xy -0.22606 0.32512)
						(xy -0.22733 0.31369) (xy -0.22733 0.30353) (xy -0.2286 0.2921) (xy -0.22733 0.28067) (xy -0.22733 0.27051)
						(xy -0.22606 0.25908) (xy -0.22352 0.24892) (xy -0.22225 0.23876) (xy -0.21844 0.22733) (xy -0.2159 0.21717)
						(xy -0.21209 0.20701) (xy -0.20701 0.19685) (xy -0.2032 0.18796) (xy -0.19812 0.1778) (xy -0.17272 0.14224)
						(xy -0.1651 0.13462) (xy -0.1651 -0.7366) (xy -0.16256 -0.76835) (xy -0.1524 -0.8001) (xy -0.13716 -0.82804)
						(xy -0.11684 -0.85344) (xy -0.09144 -0.87376) (xy -0.0635 -0.889) (xy -0.03175 -0.89916) (xy 0 -0.9017)
						(xy 0.03175 -0.89916) (xy 0.0635 -0.889) (xy 0.09144 -0.87376) (xy 0.11684 -0.85344) (xy 0.13716 -0.82804)
						(xy 0.1524 -0.8001) (xy 0.16256 -0.76835) (xy 0.1651 -0.7366) (xy 0.1651 0.13462) (xy 0.17272 0.14224)
						(xy 0.19812 0.1778) (xy 0.2032 0.18796) (xy 0.20701 0.19685) (xy 0.21209 0.20701) (xy 0.2159 0.21717)
						(xy 0.21844 0.22733) (xy 0.22225 0.23876) (xy 0.22352 0.24892) (xy 0.22606 0.25908) (xy 0.22733 0.27051)
						(xy 0.22733 0.28067) (xy 0.2286 0.2921) (xy 0.22733 0.30353) (xy 0.22733 0.31369) (xy 0.22606 0.32512)
						(xy 0.22352 0.33528) (xy 0.22225 0.34544) (xy 0.21844 0.35687) (xy 0.2159 0.36703) (xy 0.21209 0.37719)
						(xy 0.20701 0.38735) (xy 0.2032 0.39624) (xy 0.19812 0.4064) (xy 0.17272 0.44196) (xy 0.1651 0.44958)
						(xy 0.1651 0.7366) (xy 0.16256 0.76835) (xy 0.1524 0.8001) (xy 0.13716 0.82804) (xy 0.11684 0.85344)
						(xy 0.09144 0.87376) (xy 0.0635 0.889) (xy 0.03175 0.89916)
					)
					(width 0)
					(fill yes)
				)
			)
		)
		(pad "119" smd custom
			(at 6.150102 4.106672 180)
			(size 0.1143 0.1143)
			(layers "F.Cu" "F.Mask" "F.Paste")
			(net "M_A_BS0")
			(options
				(clearance outline)
				(anchor circle)
			)
			(primitives
				(gr_poly
					(pts
						(xy 0 0.9017) (xy -0.03175 0.89916) (xy -0.0635 0.889) (xy -0.09144 0.87376) (xy -0.11684 0.85344)
						(xy -0.13716 0.82804) (xy -0.1524 0.8001) (xy -0.16256 0.76835) (xy -0.1651 0.7366) (xy -0.1651 0.11938)
						(xy -0.17272 0.11176) (xy -0.19812 0.0762) (xy -0.2032 0.06604) (xy -0.20701 0.05715) (xy -0.21209 0.04699)
						(xy -0.2159 0.03683) (xy -0.21844 0.02667) (xy -0.22225 0.01524) (xy -0.22352 0.00508) (xy -0.22606 -0.00508)
						(xy -0.22733 -0.01651) (xy -0.22733 -0.02667) (xy -0.2286 -0.0381) (xy -0.22733 -0.04953) (xy -0.22733 -0.05969)
						(xy -0.22606 -0.07112) (xy -0.22352 -0.08128) (xy -0.22225 -0.09144) (xy -0.21844 -0.10287) (xy -0.2159 -0.11303)
						(xy -0.21209 -0.12319) (xy -0.20701 -0.13335) (xy -0.2032 -0.14224) (xy -0.19812 -0.1524) (xy -0.17272 -0.18796)
						(xy -0.1651 -0.19558) (xy -0.1651 -0.7366) (xy -0.16256 -0.76835) (xy -0.1524 -0.8001) (xy -0.13716 -0.82804)
						(xy -0.11684 -0.85344) (xy -0.09144 -0.87376) (xy -0.0635 -0.889) (xy -0.03175 -0.89916) (xy 0 -0.9017)
						(xy 0.03175 -0.89916) (xy 0.0635 -0.889) (xy 0.09144 -0.87376) (xy 0.11684 -0.85344) (xy 0.13716 -0.82804)
						(xy 0.1524 -0.8001) (xy 0.16256 -0.76835) (xy 0.1651 -0.7366) (xy 0.1651 -0.19685) (xy 0.17272 -0.18923)
						(xy 0.17907 -0.18034) (xy 0.18669 -0.17145) (xy 0.19177 -0.16256) (xy 0.19812 -0.15367) (xy 0.20828 -0.13335)
						(xy 0.21971 -0.10287) (xy 0.22225 -0.09271) (xy 0.22479 -0.08128) (xy 0.22606 -0.07112) (xy 0.2286 -0.05969)
						(xy 0.2286 -0.01651) (xy 0.22606 -0.00508) (xy 0.22479 0.00508) (xy 0.22225 0.01651) (xy 0.21971 0.02667)
						(xy 0.20828 0.05715) (xy 0.19812 0.07747) (xy 0.19177 0.08636) (xy 0.18669 0.09525) (xy 0.17907 0.10414)
						(xy 0.17272 0.11303) (xy 0.1651 0.12065) (xy 0.1651 0.7366) (xy 0.16256 0.76835) (xy 0.1524 0.8001)
						(xy 0.13716 0.82804) (xy 0.11684 0.85344) (xy 0.09144 0.87376) (xy 0.0635 0.889) (xy 0.03175 0.89916)
					)
					(width 0)
					(fill yes)
				)
			)
		)
		(pad "120" smd custom
			(at 6.450076 -4.106672 180)
			(size 0.1143 0.1143)
			(layers "F.Cu" "F.Mask" "F.Paste")
			(net "Net_11")
			(options
				(clearance outline)
				(anchor circle)
			)
			(primitives
				(gr_poly
					(pts
						(xy 0 0.9017) (xy -0.03175 0.89916) (xy -0.0635 0.889) (xy -0.09144 0.87376) (xy -0.11684 0.85344)
						(xy -0.13716 0.82804) (xy -0.1524 0.8001) (xy -0.16256 0.76835) (xy -0.1651 0.7366) (xy -0.1651 0.19685)
						(xy -0.17272 0.18923) (xy -0.17907 0.18034) (xy -0.18669 0.17145) (xy -0.19177 0.16256) (xy -0.19812 0.15367)
						(xy -0.20828 0.13335) (xy -0.21971 0.10287) (xy -0.22225 0.09271) (xy -0.22479 0.08128) (xy -0.22606 0.07112)
						(xy -0.2286 0.05969) (xy -0.2286 0.01651) (xy -0.22606 0.00508) (xy -0.22479 -0.00508) (xy -0.22225 -0.01651)
						(xy -0.21971 -0.02667) (xy -0.20828 -0.05715) (xy -0.19812 -0.07747) (xy -0.19177 -0.08636) (xy -0.18669 -0.09525)
						(xy -0.17907 -0.10414) (xy -0.17272 -0.11303) (xy -0.1651 -0.12065) (xy -0.1651 -0.7366) (xy -0.16256 -0.76835)
						(xy -0.1524 -0.8001) (xy -0.13716 -0.82804) (xy -0.11684 -0.85344) (xy -0.09144 -0.87376) (xy -0.0635 -0.889)
						(xy -0.03175 -0.89916) (xy 0 -0.9017) (xy 0.03175 -0.89916) (xy 0.0635 -0.889) (xy 0.09144 -0.87376)
						(xy 0.11684 -0.85344) (xy 0.13716 -0.82804) (xy 0.1524 -0.8001) (xy 0.16256 -0.76835) (xy 0.1651 -0.7366)
						(xy 0.1651 -0.11938) (xy 0.17272 -0.11176) (xy 0.19812 -0.0762) (xy 0.2032 -0.06604) (xy 0.20701 -0.05715)
						(xy 0.21209 -0.04699) (xy 0.2159 -0.03683) (xy 0.21844 -0.02667) (xy 0.22225 -0.01524) (xy 0.22352 -0.00508)
						(xy 0.22606 0.00508) (xy 0.22733 0.01651) (xy 0.22733 0.02667) (xy 0.2286 0.0381) (xy 0.22733 0.04953)
						(xy 0.22733 0.05969) (xy 0.22606 0.07112) (xy 0.22352 0.08128) (xy 0.22225 0.09144) (xy 0.21844 0.10287)
						(xy 0.2159 0.11303) (xy 0.21209 0.12319) (xy 0.20701 0.13335) (xy 0.2032 0.14224) (xy 0.19812 0.1524)
						(xy 0.17272 0.18796) (xy 0.1651 0.19558) (xy 0.1651 0.7366) (xy 0.16256 0.76835) (xy 0.1524 0.8001)
						(xy 0.13716 0.82804) (xy 0.11684 0.85344) (xy 0.09144 0.87376) (xy 0.0635 0.889) (xy 0.03175 0.89916)
					)
					(width 0)
					(fill yes)
				)
			)
		)
		(pad "121" smd custom
			(at 6.75005 4.106672 180)
			(size 0.1143 0.1143)
			(layers "F.Cu" "F.Mask" "F.Paste")
			(net "M_A_WE#")
			(options
				(clearance outline)
				(anchor circle)
			)
			(primitives
				(gr_poly
					(pts
						(xy 0 0.9017) (xy -0.03175 0.89916) (xy -0.0635 0.889) (xy -0.09144 0.87376) (xy -0.11684 0.85344)
						(xy -0.13716 0.82804) (xy -0.1524 0.8001) (xy -0.16256 0.76835) (xy -0.1651 0.7366) (xy -0.1651 -0.13462)
						(xy -0.17272 -0.14224) (xy -0.19812 -0.1778) (xy -0.2032 -0.18796) (xy -0.20701 -0.19685) (xy -0.21209 -0.20701)
						(xy -0.2159 -0.21717) (xy -0.21844 -0.22733) (xy -0.22225 -0.23876) (xy -0.22352 -0.24892) (xy -0.22606 -0.25908)
						(xy -0.22733 -0.27051) (xy -0.22733 -0.28067) (xy -0.2286 -0.2921) (xy -0.22733 -0.30353) (xy -0.22733 -0.31369)
						(xy -0.22606 -0.32512) (xy -0.22352 -0.33528) (xy -0.22225 -0.34544) (xy -0.21844 -0.35687) (xy -0.2159 -0.36703)
						(xy -0.21209 -0.37719) (xy -0.20701 -0.38735) (xy -0.2032 -0.39624) (xy -0.19812 -0.4064) (xy -0.17272 -0.44196)
						(xy -0.1651 -0.44958) (xy -0.1651 -0.7366) (xy -0.16256 -0.76835) (xy -0.1524 -0.8001) (xy -0.13716 -0.82804)
						(xy -0.11684 -0.85344) (xy -0.09144 -0.87376) (xy -0.0635 -0.889) (xy -0.03175 -0.89916) (xy 0 -0.9017)
						(xy 0.03175 -0.89916) (xy 0.0635 -0.889) (xy 0.09144 -0.87376) (xy 0.11684 -0.85344) (xy 0.13716 -0.82804)
						(xy 0.1524 -0.8001) (xy 0.16256 -0.76835) (xy 0.1651 -0.7366) (xy 0.1651 -0.44958) (xy 0.17272 -0.44196)
						(xy 0.19812 -0.4064) (xy 0.2032 -0.39624) (xy 0.20701 -0.38735) (xy 0.21209 -0.37719) (xy 0.2159 -0.36703)
						(xy 0.21844 -0.35687) (xy 0.22225 -0.34544) (xy 0.22352 -0.33528) (xy 0.22606 -0.32512) (xy 0.22733 -0.31369)
						(xy 0.22733 -0.30353) (xy 0.2286 -0.2921) (xy 0.22733 -0.28067) (xy 0.22733 -0.27051) (xy 0.22606 -0.25908)
						(xy 0.22352 -0.24892) (xy 0.22225 -0.23876) (xy 0.21844 -0.22733) (xy 0.2159 -0.21717) (xy 0.21209 -0.20701)
						(xy 0.20701 -0.19685) (xy 0.2032 -0.18796) (xy 0.19812 -0.1778) (xy 0.17272 -0.14224) (xy 0.1651 -0.13462)
						(xy 0.1651 0.7366) (xy 0.16256 0.76835) (xy 0.1524 0.8001) (xy 0.13716 0.82804) (xy 0.11684 0.85344)
						(xy 0.09144 0.87376) (xy 0.0635 0.889) (xy 0.03175 0.89916)
					)
					(width 0)
					(fill yes)
				)
			)
		)
		(pad "122" smd custom
			(at 7.050024 -4.106672 180)
			(size 0.1143 0.1143)
			(layers "F.Cu" "F.Mask" "F.Paste")
			(net "M_A_RAS#")
			(options
				(clearance outline)
				(anchor circle)
			)
			(primitives
				(gr_poly
					(pts
						(xy 0 0.9017) (xy -0.03175 0.89916) (xy -0.0635 0.889) (xy -0.09144 0.87376) (xy -0.11684 0.85344)
						(xy -0.13716 0.82804) (xy -0.1524 0.8001) (xy -0.16256 0.76835) (xy -0.1651 0.7366) (xy -0.1651 0.44958)
						(xy -0.17272 0.44196) (xy -0.19812 0.4064) (xy -0.2032 0.39624) (xy -0.20701 0.38735) (xy -0.21209 0.37719)
						(xy -0.2159 0.36703) (xy -0.21844 0.35687) (xy -0.22225 0.34544) (xy -0.22352 0.33528) (xy -0.22606 0.32512)
						(xy -0.22733 0.31369) (xy -0.22733 0.30353) (xy -0.2286 0.2921) (xy -0.22733 0.28067) (xy -0.22733 0.27051)
						(xy -0.22606 0.25908) (xy -0.22352 0.24892) (xy -0.22225 0.23876) (xy -0.21844 0.22733) (xy -0.2159 0.21717)
						(xy -0.21209 0.20701) (xy -0.20701 0.19685) (xy -0.2032 0.18796) (xy -0.19812 0.1778) (xy -0.17272 0.14224)
						(xy -0.1651 0.13462) (xy -0.1651 -0.7366) (xy -0.16256 -0.76835) (xy -0.1524 -0.8001) (xy -0.13716 -0.82804)
						(xy -0.11684 -0.85344) (xy -0.09144 -0.87376) (xy -0.0635 -0.889) (xy -0.03175 -0.89916) (xy 0 -0.9017)
						(xy 0.03175 -0.89916) (xy 0.0635 -0.889) (xy 0.09144 -0.87376) (xy 0.11684 -0.85344) (xy 0.13716 -0.82804)
						(xy 0.1524 -0.8001) (xy 0.16256 -0.76835) (xy 0.1651 -0.7366) (xy 0.1651 0.13462) (xy 0.17272 0.14224)
						(xy 0.19812 0.1778) (xy 0.2032 0.18796) (xy 0.20701 0.19685) (xy 0.21209 0.20701) (xy 0.2159 0.21717)
						(xy 0.21844 0.22733) (xy 0.22225 0.23876) (xy 0.22352 0.24892) (xy 0.22606 0.25908) (xy 0.22733 0.27051)
						(xy 0.22733 0.28067) (xy 0.2286 0.2921) (xy 0.22733 0.30353) (xy 0.22733 0.31369) (xy 0.22606 0.32512)
						(xy 0.22352 0.33528) (xy 0.22225 0.34544) (xy 0.21844 0.35687) (xy 0.2159 0.36703) (xy 0.21209 0.37719)
						(xy 0.20701 0.38735) (xy 0.2032 0.39624) (xy 0.19812 0.4064) (xy 0.17272 0.44196) (xy 0.1651 0.44958)
						(xy 0.1651 0.7366) (xy 0.16256 0.76835) (xy 0.1524 0.8001) (xy 0.13716 0.82804) (xy 0.11684 0.85344)
						(xy 0.09144 0.87376) (xy 0.0635 0.889) (xy 0.03175 0.89916)
					)
					(width 0)
					(fill yes)
				)
			)
		)
		(pad "123" smd custom
			(at 7.349998 4.106672 180)
			(size 0.1143 0.1143)
			(layers "F.Cu" "F.Mask" "F.Paste")
			(net "PV_VDDR")
			(options
				(clearance outline)
				(anchor circle)
			)
			(primitives
				(gr_poly
					(pts
						(xy 0 0.9017) (xy -0.03175 0.89916) (xy -0.0635 0.889) (xy -0.09144 0.87376) (xy -0.11684 0.85344)
						(xy -0.13716 0.82804) (xy -0.1524 0.8001) (xy -0.16256 0.76835) (xy -0.1651 0.7366) (xy -0.1651 0.11938)
						(xy -0.17272 0.11176) (xy -0.19812 0.0762) (xy -0.2032 0.06604) (xy -0.20701 0.05715) (xy -0.21209 0.04699)
						(xy -0.2159 0.03683) (xy -0.21844 0.02667) (xy -0.22225 0.01524) (xy -0.22352 0.00508) (xy -0.22606 -0.00508)
						(xy -0.22733 -0.01651) (xy -0.22733 -0.02667) (xy -0.2286 -0.0381) (xy -0.22733 -0.04953) (xy -0.22733 -0.05969)
						(xy -0.22606 -0.07112) (xy -0.22352 -0.08128) (xy -0.22225 -0.09144) (xy -0.21844 -0.10287) (xy -0.2159 -0.11303)
						(xy -0.21209 -0.12319) (xy -0.20701 -0.13335) (xy -0.2032 -0.14224) (xy -0.19812 -0.1524) (xy -0.17272 -0.18796)
						(xy -0.1651 -0.19558) (xy -0.1651 -0.7366) (xy -0.16256 -0.76835) (xy -0.1524 -0.8001) (xy -0.13716 -0.82804)
						(xy -0.11684 -0.85344) (xy -0.09144 -0.87376) (xy -0.0635 -0.889) (xy -0.03175 -0.89916) (xy 0 -0.9017)
						(xy 0.03175 -0.89916) (xy 0.0635 -0.889) (xy 0.09144 -0.87376) (xy 0.11684 -0.85344) (xy 0.13716 -0.82804)
						(xy 0.1524 -0.8001) (xy 0.16256 -0.76835) (xy 0.1651 -0.7366) (xy 0.1651 -0.19685) (xy 0.17272 -0.18923)
						(xy 0.17907 -0.18034) (xy 0.18669 -0.17145) (xy 0.19177 -0.16256) (xy 0.19812 -0.15367) (xy 0.20828 -0.13335)
						(xy 0.21971 -0.10287) (xy 0.22225 -0.09271) (xy 0.22479 -0.08128) (xy 0.22606 -0.07112) (xy 0.2286 -0.05969)
						(xy 0.2286 -0.01651) (xy 0.22606 -0.00508) (xy 0.22479 0.00508) (xy 0.22225 0.01651) (xy 0.21971 0.02667)
						(xy 0.20828 0.05715) (xy 0.19812 0.07747) (xy 0.19177 0.08636) (xy 0.18669 0.09525) (xy 0.17907 0.10414)
						(xy 0.17272 0.11303) (xy 0.1651 0.12065) (xy 0.1651 0.7366) (xy 0.16256 0.76835) (xy 0.1524 0.8001)
						(xy 0.13716 0.82804) (xy 0.11684 0.85344) (xy 0.09144 0.87376) (xy 0.0635 0.889) (xy 0.03175 0.89916)
					)
					(width 0)
					(fill yes)
				)
			)
		)
		(pad "124" smd custom
			(at 7.649972 -4.106672 180)
			(size 0.1143 0.1143)
			(layers "F.Cu" "F.Mask" "F.Paste")
			(net "PV_VDDR")
			(options
				(clearance outline)
				(anchor circle)
			)
			(primitives
				(gr_poly
					(pts
						(xy 0 0.9017) (xy -0.03175 0.89916) (xy -0.0635 0.889) (xy -0.09144 0.87376) (xy -0.11684 0.85344)
						(xy -0.13716 0.82804) (xy -0.1524 0.8001) (xy -0.16256 0.76835) (xy -0.1651 0.7366) (xy -0.1651 0.19685)
						(xy -0.17272 0.18923) (xy -0.17907 0.18034) (xy -0.18669 0.17145) (xy -0.19177 0.16256) (xy -0.19812 0.15367)
						(xy -0.20828 0.13335) (xy -0.21971 0.10287) (xy -0.22225 0.09271) (xy -0.22479 0.08128) (xy -0.22606 0.07112)
						(xy -0.2286 0.05969) (xy -0.2286 0.01651) (xy -0.22606 0.00508) (xy -0.22479 -0.00508) (xy -0.22225 -0.01651)
						(xy -0.21971 -0.02667) (xy -0.20828 -0.05715) (xy -0.19812 -0.07747) (xy -0.19177 -0.08636) (xy -0.18669 -0.09525)
						(xy -0.17907 -0.10414) (xy -0.17272 -0.11303) (xy -0.1651 -0.12065) (xy -0.1651 -0.7366) (xy -0.16256 -0.76835)
						(xy -0.1524 -0.8001) (xy -0.13716 -0.82804) (xy -0.11684 -0.85344) (xy -0.09144 -0.87376) (xy -0.0635 -0.889)
						(xy -0.03175 -0.89916) (xy 0 -0.9017) (xy 0.03175 -0.89916) (xy 0.0635 -0.889) (xy 0.09144 -0.87376)
						(xy 0.11684 -0.85344) (xy 0.13716 -0.82804) (xy 0.1524 -0.8001) (xy 0.16256 -0.76835) (xy 0.1651 -0.7366)
						(xy 0.1651 -0.11938) (xy 0.17272 -0.11176) (xy 0.19812 -0.0762) (xy 0.2032 -0.06604) (xy 0.20701 -0.05715)
						(xy 0.21209 -0.04699) (xy 0.2159 -0.03683) (xy 0.21844 -0.02667) (xy 0.22225 -0.01524) (xy 0.22352 -0.00508)
						(xy 0.22606 0.00508) (xy 0.22733 0.01651) (xy 0.22733 0.02667) (xy 0.2286 0.0381) (xy 0.22733 0.04953)
						(xy 0.22733 0.05969) (xy 0.22606 0.07112) (xy 0.22352 0.08128) (xy 0.22225 0.09144) (xy 0.21844 0.10287)
						(xy 0.2159 0.11303) (xy 0.21209 0.12319) (xy 0.20701 0.13335) (xy 0.2032 0.14224) (xy 0.19812 0.1524)
						(xy 0.17272 0.18796) (xy 0.1651 0.19558) (xy 0.1651 0.7366) (xy 0.16256 0.76835) (xy 0.1524 0.8001)
						(xy 0.13716 0.82804) (xy 0.11684 0.85344) (xy 0.09144 0.87376) (xy 0.0635 0.889) (xy 0.03175 0.89916)
					)
					(width 0)
					(fill yes)
				)
			)
		)
		(pad "125" smd custom
			(at 7.949946 4.106672 180)
			(size 0.1143 0.1143)
			(layers "F.Cu" "F.Mask" "F.Paste")
			(net "M_A_CAS#")
			(options
				(clearance outline)
				(anchor circle)
			)
			(primitives
				(gr_poly
					(pts
						(xy 0 0.9017) (xy -0.03175 0.89916) (xy -0.0635 0.889) (xy -0.09144 0.87376) (xy -0.11684 0.85344)
						(xy -0.13716 0.82804) (xy -0.1524 0.8001) (xy -0.16256 0.76835) (xy -0.1651 0.7366) (xy -0.1651 -0.13462)
						(xy -0.17272 -0.14224) (xy -0.19812 -0.1778) (xy -0.2032 -0.18796) (xy -0.20701 -0.19685) (xy -0.21209 -0.20701)
						(xy -0.2159 -0.21717) (xy -0.21844 -0.22733) (xy -0.22225 -0.23876) (xy -0.22352 -0.24892) (xy -0.22606 -0.25908)
						(xy -0.22733 -0.27051) (xy -0.22733 -0.28067) (xy -0.2286 -0.2921) (xy -0.22733 -0.30353) (xy -0.22733 -0.31369)
						(xy -0.22606 -0.32512) (xy -0.22352 -0.33528) (xy -0.22225 -0.34544) (xy -0.21844 -0.35687) (xy -0.2159 -0.36703)
						(xy -0.21209 -0.37719) (xy -0.20701 -0.38735) (xy -0.2032 -0.39624) (xy -0.19812 -0.4064) (xy -0.17272 -0.44196)
						(xy -0.1651 -0.44958) (xy -0.1651 -0.7366) (xy -0.16256 -0.76835) (xy -0.1524 -0.8001) (xy -0.13716 -0.82804)
						(xy -0.11684 -0.85344) (xy -0.09144 -0.87376) (xy -0.0635 -0.889) (xy -0.03175 -0.89916) (xy 0 -0.9017)
						(xy 0.03175 -0.89916) (xy 0.0635 -0.889) (xy 0.09144 -0.87376) (xy 0.11684 -0.85344) (xy 0.13716 -0.82804)
						(xy 0.1524 -0.8001) (xy 0.16256 -0.76835) (xy 0.1651 -0.7366) (xy 0.1651 -0.44958) (xy 0.17272 -0.44196)
						(xy 0.19812 -0.4064) (xy 0.2032 -0.39624) (xy 0.20701 -0.38735) (xy 0.21209 -0.37719) (xy 0.2159 -0.36703)
						(xy 0.21844 -0.35687) (xy 0.22225 -0.34544) (xy 0.22352 -0.33528) (xy 0.22606 -0.32512) (xy 0.22733 -0.31369)
						(xy 0.22733 -0.30353) (xy 0.2286 -0.2921) (xy 0.22733 -0.28067) (xy 0.22733 -0.27051) (xy 0.22606 -0.25908)
						(xy 0.22352 -0.24892) (xy 0.22225 -0.23876) (xy 0.21844 -0.22733) (xy 0.2159 -0.21717) (xy 0.21209 -0.20701)
						(xy 0.20701 -0.19685) (xy 0.2032 -0.18796) (xy 0.19812 -0.1778) (xy 0.17272 -0.14224) (xy 0.1651 -0.13462)
						(xy 0.1651 0.7366) (xy 0.16256 0.76835) (xy 0.1524 0.8001) (xy 0.13716 0.82804) (xy 0.11684 0.85344)
						(xy 0.09144 0.87376) (xy 0.0635 0.889) (xy 0.03175 0.89916)
					)
					(width 0)
					(fill yes)
				)
			)
		)
		(pad "126" smd custom
			(at 8.24992 -4.106672 180)
			(size 0.1143 0.1143)
			(layers "F.Cu" "F.Mask" "F.Paste")
			(net "M_A_ODT2")
			(options
				(clearance outline)
				(anchor circle)
			)
			(primitives
				(gr_poly
					(pts
						(xy 0 0.9017) (xy -0.03175 0.89916) (xy -0.0635 0.889) (xy -0.09144 0.87376) (xy -0.11684 0.85344)
						(xy -0.13716 0.82804) (xy -0.1524 0.8001) (xy -0.16256 0.76835) (xy -0.1651 0.7366) (xy -0.1651 0.44958)
						(xy -0.17272 0.44196) (xy -0.19812 0.4064) (xy -0.2032 0.39624) (xy -0.20701 0.38735) (xy -0.21209 0.37719)
						(xy -0.2159 0.36703) (xy -0.21844 0.35687) (xy -0.22225 0.34544) (xy -0.22352 0.33528) (xy -0.22606 0.32512)
						(xy -0.22733 0.31369) (xy -0.22733 0.30353) (xy -0.2286 0.2921) (xy -0.22733 0.28067) (xy -0.22733 0.27051)
						(xy -0.22606 0.25908) (xy -0.22352 0.24892) (xy -0.22225 0.23876) (xy -0.21844 0.22733) (xy -0.2159 0.21717)
						(xy -0.21209 0.20701) (xy -0.20701 0.19685) (xy -0.2032 0.18796) (xy -0.19812 0.1778) (xy -0.17272 0.14224)
						(xy -0.1651 0.13462) (xy -0.1651 -0.7366) (xy -0.16256 -0.76835) (xy -0.1524 -0.8001) (xy -0.13716 -0.82804)
						(xy -0.11684 -0.85344) (xy -0.09144 -0.87376) (xy -0.0635 -0.889) (xy -0.03175 -0.89916) (xy 0 -0.9017)
						(xy 0.03175 -0.89916) (xy 0.0635 -0.889) (xy 0.09144 -0.87376) (xy 0.11684 -0.85344) (xy 0.13716 -0.82804)
						(xy 0.1524 -0.8001) (xy 0.16256 -0.76835) (xy 0.1651 -0.7366) (xy 0.1651 0.13462) (xy 0.17272 0.14224)
						(xy 0.19812 0.1778) (xy 0.2032 0.18796) (xy 0.20701 0.19685) (xy 0.21209 0.20701) (xy 0.2159 0.21717)
						(xy 0.21844 0.22733) (xy 0.22225 0.23876) (xy 0.22352 0.24892) (xy 0.22606 0.25908) (xy 0.22733 0.27051)
						(xy 0.22733 0.28067) (xy 0.2286 0.2921) (xy 0.22733 0.30353) (xy 0.22733 0.31369) (xy 0.22606 0.32512)
						(xy 0.22352 0.33528) (xy 0.22225 0.34544) (xy 0.21844 0.35687) (xy 0.2159 0.36703) (xy 0.21209 0.37719)
						(xy 0.20701 0.38735) (xy 0.2032 0.39624) (xy 0.19812 0.4064) (xy 0.17272 0.44196) (xy 0.1651 0.44958)
						(xy 0.1651 0.7366) (xy 0.16256 0.76835) (xy 0.1524 0.8001) (xy 0.13716 0.82804) (xy 0.11684 0.85344)
						(xy 0.09144 0.87376) (xy 0.0635 0.889) (xy 0.03175 0.89916)
					)
					(width 0)
					(fill yes)
				)
			)
		)
		(pad "127" smd custom
			(at 8.549894 4.106672 180)
			(size 0.1143 0.1143)
			(layers "F.Cu" "F.Mask" "F.Paste")
			(net "M_A_CS_N2")
			(options
				(clearance outline)
				(anchor circle)
			)
			(primitives
				(gr_poly
					(pts
						(xy 0 0.9017) (xy -0.03175 0.89916) (xy -0.0635 0.889) (xy -0.09144 0.87376) (xy -0.11684 0.85344)
						(xy -0.13716 0.82804) (xy -0.1524 0.8001) (xy -0.16256 0.76835) (xy -0.1651 0.7366) (xy -0.1651 0.11938)
						(xy -0.17272 0.11176) (xy -0.19812 0.0762) (xy -0.2032 0.06604) (xy -0.20701 0.05715) (xy -0.21209 0.04699)
						(xy -0.2159 0.03683) (xy -0.21844 0.02667) (xy -0.22225 0.01524) (xy -0.22352 0.00508) (xy -0.22606 -0.00508)
						(xy -0.22733 -0.01651) (xy -0.22733 -0.02667) (xy -0.2286 -0.0381) (xy -0.22733 -0.04953) (xy -0.22733 -0.05969)
						(xy -0.22606 -0.07112) (xy -0.22352 -0.08128) (xy -0.22225 -0.09144) (xy -0.21844 -0.10287) (xy -0.2159 -0.11303)
						(xy -0.21209 -0.12319) (xy -0.20701 -0.13335) (xy -0.2032 -0.14224) (xy -0.19812 -0.1524) (xy -0.17272 -0.18796)
						(xy -0.1651 -0.19558) (xy -0.1651 -0.7366) (xy -0.16256 -0.76835) (xy -0.1524 -0.8001) (xy -0.13716 -0.82804)
						(xy -0.11684 -0.85344) (xy -0.09144 -0.87376) (xy -0.0635 -0.889) (xy -0.03175 -0.89916) (xy 0 -0.9017)
						(xy 0.03175 -0.89916) (xy 0.0635 -0.889) (xy 0.09144 -0.87376) (xy 0.11684 -0.85344) (xy 0.13716 -0.82804)
						(xy 0.1524 -0.8001) (xy 0.16256 -0.76835) (xy 0.1651 -0.7366) (xy 0.1651 -0.19685) (xy 0.17272 -0.18923)
						(xy 0.17907 -0.18034) (xy 0.18669 -0.17145) (xy 0.19177 -0.16256) (xy 0.19812 -0.15367) (xy 0.20828 -0.13335)
						(xy 0.21971 -0.10287) (xy 0.22225 -0.09271) (xy 0.22479 -0.08128) (xy 0.22606 -0.07112) (xy 0.2286 -0.05969)
						(xy 0.2286 -0.01651) (xy 0.22606 -0.00508) (xy 0.22479 0.00508) (xy 0.22225 0.01651) (xy 0.21971 0.02667)
						(xy 0.20828 0.05715) (xy 0.19812 0.07747) (xy 0.19177 0.08636) (xy 0.18669 0.09525) (xy 0.17907 0.10414)
						(xy 0.17272 0.11303) (xy 0.1651 0.12065) (xy 0.1651 0.7366) (xy 0.16256 0.76835) (xy 0.1524 0.8001)
						(xy 0.13716 0.82804) (xy 0.11684 0.85344) (xy 0.09144 0.87376) (xy 0.0635 0.889) (xy 0.03175 0.89916)
					)
					(width 0)
					(fill yes)
				)
			)
		)
		(pad "128" smd custom
			(at 8.850122 -4.106672 180)
			(size 0.1143 0.1143)
			(layers "F.Cu" "F.Mask" "F.Paste")
			(net "M_A_ODT3")
			(options
				(clearance outline)
				(anchor circle)
			)
			(primitives
				(gr_poly
					(pts
						(xy 0 0.9017) (xy -0.03175 0.89916) (xy -0.0635 0.889) (xy -0.09144 0.87376) (xy -0.11684 0.85344)
						(xy -0.13716 0.82804) (xy -0.1524 0.8001) (xy -0.16256 0.76835) (xy -0.1651 0.7366) (xy -0.1651 0.19685)
						(xy -0.17272 0.18923) (xy -0.17907 0.18034) (xy -0.18669 0.17145) (xy -0.19177 0.16256) (xy -0.19812 0.15367)
						(xy -0.20828 0.13335) (xy -0.21971 0.10287) (xy -0.22225 0.09271) (xy -0.22479 0.08128) (xy -0.22606 0.07112)
						(xy -0.2286 0.05969) (xy -0.2286 0.01651) (xy -0.22606 0.00508) (xy -0.22479 -0.00508) (xy -0.22225 -0.01651)
						(xy -0.21971 -0.02667) (xy -0.20828 -0.05715) (xy -0.19812 -0.07747) (xy -0.19177 -0.08636) (xy -0.18669 -0.09525)
						(xy -0.17907 -0.10414) (xy -0.17272 -0.11303) (xy -0.1651 -0.12065) (xy -0.1651 -0.7366) (xy -0.16256 -0.76835)
						(xy -0.1524 -0.8001) (xy -0.13716 -0.82804) (xy -0.11684 -0.85344) (xy -0.09144 -0.87376) (xy -0.0635 -0.889)
						(xy -0.03175 -0.89916) (xy 0 -0.9017) (xy 0.03175 -0.89916) (xy 0.0635 -0.889) (xy 0.09144 -0.87376)
						(xy 0.11684 -0.85344) (xy 0.13716 -0.82804) (xy 0.1524 -0.8001) (xy 0.16256 -0.76835) (xy 0.1651 -0.7366)
						(xy 0.1651 -0.11938) (xy 0.17272 -0.11176) (xy 0.19812 -0.0762) (xy 0.2032 -0.06604) (xy 0.20701 -0.05715)
						(xy 0.21209 -0.04699) (xy 0.2159 -0.03683) (xy 0.21844 -0.02667) (xy 0.22225 -0.01524) (xy 0.22352 -0.00508)
						(xy 0.22606 0.00508) (xy 0.22733 0.01651) (xy 0.22733 0.02667) (xy 0.2286 0.0381) (xy 0.22733 0.04953)
						(xy 0.22733 0.05969) (xy 0.22606 0.07112) (xy 0.22352 0.08128) (xy 0.22225 0.09144) (xy 0.21844 0.10287)
						(xy 0.2159 0.11303) (xy 0.21209 0.12319) (xy 0.20701 0.13335) (xy 0.2032 0.14224) (xy 0.19812 0.1524)
						(xy 0.17272 0.18796) (xy 0.1651 0.19558) (xy 0.1651 0.7366) (xy 0.16256 0.76835) (xy 0.1524 0.8001)
						(xy 0.13716 0.82804) (xy 0.11684 0.85344) (xy 0.09144 0.87376) (xy 0.0635 0.889) (xy 0.03175 0.89916)
					)
					(width 0)
					(fill yes)
				)
			)
		)
		(pad "129" smd custom
			(at 9.150096 4.106672 180)
			(size 0.1143 0.1143)
			(layers "F.Cu" "F.Mask" "F.Paste")
			(net "M_A_CS_N3")
			(options
				(clearance outline)
				(anchor circle)
			)
			(primitives
				(gr_poly
					(pts
						(xy 0 0.9017) (xy -0.03175 0.89916) (xy -0.0635 0.889) (xy -0.09144 0.87376) (xy -0.11684 0.85344)
						(xy -0.13716 0.82804) (xy -0.1524 0.8001) (xy -0.16256 0.76835) (xy -0.1651 0.7366) (xy -0.1651 -0.13462)
						(xy -0.17272 -0.14224) (xy -0.19812 -0.1778) (xy -0.2032 -0.18796) (xy -0.20701 -0.19685) (xy -0.21209 -0.20701)
						(xy -0.2159 -0.21717) (xy -0.21844 -0.22733) (xy -0.22225 -0.23876) (xy -0.22352 -0.24892) (xy -0.22606 -0.25908)
						(xy -0.22733 -0.27051) (xy -0.22733 -0.28067) (xy -0.2286 -0.2921) (xy -0.22733 -0.30353) (xy -0.22733 -0.31369)
						(xy -0.22606 -0.32512) (xy -0.22352 -0.33528) (xy -0.22225 -0.34544) (xy -0.21844 -0.35687) (xy -0.2159 -0.36703)
						(xy -0.21209 -0.37719) (xy -0.20701 -0.38735) (xy -0.2032 -0.39624) (xy -0.19812 -0.4064) (xy -0.17272 -0.44196)
						(xy -0.1651 -0.44958) (xy -0.1651 -0.7366) (xy -0.16256 -0.76835) (xy -0.1524 -0.8001) (xy -0.13716 -0.82804)
						(xy -0.11684 -0.85344) (xy -0.09144 -0.87376) (xy -0.0635 -0.889) (xy -0.03175 -0.89916) (xy 0 -0.9017)
						(xy 0.03175 -0.89916) (xy 0.0635 -0.889) (xy 0.09144 -0.87376) (xy 0.11684 -0.85344) (xy 0.13716 -0.82804)
						(xy 0.1524 -0.8001) (xy 0.16256 -0.76835) (xy 0.1651 -0.7366) (xy 0.1651 -0.44958) (xy 0.17272 -0.44196)
						(xy 0.19812 -0.4064) (xy 0.2032 -0.39624) (xy 0.20701 -0.38735) (xy 0.21209 -0.37719) (xy 0.2159 -0.36703)
						(xy 0.21844 -0.35687) (xy 0.22225 -0.34544) (xy 0.22352 -0.33528) (xy 0.22606 -0.32512) (xy 0.22733 -0.31369)
						(xy 0.22733 -0.30353) (xy 0.2286 -0.2921) (xy 0.22733 -0.28067) (xy 0.22733 -0.27051) (xy 0.22606 -0.25908)
						(xy 0.22352 -0.24892) (xy 0.22225 -0.23876) (xy 0.21844 -0.22733) (xy 0.2159 -0.21717) (xy 0.21209 -0.20701)
						(xy 0.20701 -0.19685) (xy 0.2032 -0.18796) (xy 0.19812 -0.1778) (xy 0.17272 -0.14224) (xy 0.1651 -0.13462)
						(xy 0.1651 0.7366) (xy 0.16256 0.76835) (xy 0.1524 0.8001) (xy 0.13716 0.82804) (xy 0.11684 0.85344)
						(xy 0.09144 0.87376) (xy 0.0635 0.889) (xy 0.03175 0.89916)
					)
					(width 0)
					(fill yes)
				)
			)
		)
		(pad "130" smd custom
			(at 9.45007 -4.106672 180)
			(size 0.1143 0.1143)
			(layers "F.Cu" "F.Mask" "F.Paste")
			(net "M_A_MA13")
			(options
				(clearance outline)
				(anchor circle)
			)
			(primitives
				(gr_poly
					(pts
						(xy 0 0.9017) (xy -0.03175 0.89916) (xy -0.0635 0.889) (xy -0.09144 0.87376) (xy -0.11684 0.85344)
						(xy -0.13716 0.82804) (xy -0.1524 0.8001) (xy -0.16256 0.76835) (xy -0.1651 0.7366) (xy -0.1651 0.44958)
						(xy -0.17272 0.44196) (xy -0.19812 0.4064) (xy -0.2032 0.39624) (xy -0.20701 0.38735) (xy -0.21209 0.37719)
						(xy -0.2159 0.36703) (xy -0.21844 0.35687) (xy -0.22225 0.34544) (xy -0.22352 0.33528) (xy -0.22606 0.32512)
						(xy -0.22733 0.31369) (xy -0.22733 0.30353) (xy -0.2286 0.2921) (xy -0.22733 0.28067) (xy -0.22733 0.27051)
						(xy -0.22606 0.25908) (xy -0.22352 0.24892) (xy -0.22225 0.23876) (xy -0.21844 0.22733) (xy -0.2159 0.21717)
						(xy -0.21209 0.20701) (xy -0.20701 0.19685) (xy -0.2032 0.18796) (xy -0.19812 0.1778) (xy -0.17272 0.14224)
						(xy -0.1651 0.13462) (xy -0.1651 -0.7366) (xy -0.16256 -0.76835) (xy -0.1524 -0.8001) (xy -0.13716 -0.82804)
						(xy -0.11684 -0.85344) (xy -0.09144 -0.87376) (xy -0.0635 -0.889) (xy -0.03175 -0.89916) (xy 0 -0.9017)
						(xy 0.03175 -0.89916) (xy 0.0635 -0.889) (xy 0.09144 -0.87376) (xy 0.11684 -0.85344) (xy 0.13716 -0.82804)
						(xy 0.1524 -0.8001) (xy 0.16256 -0.76835) (xy 0.1651 -0.7366) (xy 0.1651 0.13462) (xy 0.17272 0.14224)
						(xy 0.19812 0.1778) (xy 0.2032 0.18796) (xy 0.20701 0.19685) (xy 0.21209 0.20701) (xy 0.2159 0.21717)
						(xy 0.21844 0.22733) (xy 0.22225 0.23876) (xy 0.22352 0.24892) (xy 0.22606 0.25908) (xy 0.22733 0.27051)
						(xy 0.22733 0.28067) (xy 0.2286 0.2921) (xy 0.22733 0.30353) (xy 0.22733 0.31369) (xy 0.22606 0.32512)
						(xy 0.22352 0.33528) (xy 0.22225 0.34544) (xy 0.21844 0.35687) (xy 0.2159 0.36703) (xy 0.21209 0.37719)
						(xy 0.20701 0.38735) (xy 0.2032 0.39624) (xy 0.19812 0.4064) (xy 0.17272 0.44196) (xy 0.1651 0.44958)
						(xy 0.1651 0.7366) (xy 0.16256 0.76835) (xy 0.1524 0.8001) (xy 0.13716 0.82804) (xy 0.11684 0.85344)
						(xy 0.09144 0.87376) (xy 0.0635 0.889) (xy 0.03175 0.89916)
					)
					(width 0)
					(fill yes)
				)
			)
		)
		(pad "131" smd custom
			(at 9.750044 4.106672 180)
			(size 0.1143 0.1143)
			(layers "F.Cu" "F.Mask" "F.Paste")
			(net "PV_VDDR")
			(options
				(clearance outline)
				(anchor circle)
			)
			(primitives
				(gr_poly
					(pts
						(xy 0 0.9017) (xy -0.03175 0.89916) (xy -0.0635 0.889) (xy -0.09144 0.87376) (xy -0.11684 0.85344)
						(xy -0.13716 0.82804) (xy -0.1524 0.8001) (xy -0.16256 0.76835) (xy -0.1651 0.7366) (xy -0.1651 0.11938)
						(xy -0.17272 0.11176) (xy -0.19812 0.0762) (xy -0.2032 0.06604) (xy -0.20701 0.05715) (xy -0.21209 0.04699)
						(xy -0.2159 0.03683) (xy -0.21844 0.02667) (xy -0.22225 0.01524) (xy -0.22352 0.00508) (xy -0.22606 -0.00508)
						(xy -0.22733 -0.01651) (xy -0.22733 -0.02667) (xy -0.2286 -0.0381) (xy -0.22733 -0.04953) (xy -0.22733 -0.05969)
						(xy -0.22606 -0.07112) (xy -0.22352 -0.08128) (xy -0.22225 -0.09144) (xy -0.21844 -0.10287) (xy -0.2159 -0.11303)
						(xy -0.21209 -0.12319) (xy -0.20701 -0.13335) (xy -0.2032 -0.14224) (xy -0.19812 -0.1524) (xy -0.17272 -0.18796)
						(xy -0.1651 -0.19558) (xy -0.1651 -0.7366) (xy -0.16256 -0.76835) (xy -0.1524 -0.8001) (xy -0.13716 -0.82804)
						(xy -0.11684 -0.85344) (xy -0.09144 -0.87376) (xy -0.0635 -0.889) (xy -0.03175 -0.89916) (xy 0 -0.9017)
						(xy 0.03175 -0.89916) (xy 0.0635 -0.889) (xy 0.09144 -0.87376) (xy 0.11684 -0.85344) (xy 0.13716 -0.82804)
						(xy 0.1524 -0.8001) (xy 0.16256 -0.76835) (xy 0.1651 -0.7366) (xy 0.1651 -0.19685) (xy 0.17272 -0.18923)
						(xy 0.17907 -0.18034) (xy 0.18669 -0.17145) (xy 0.19177 -0.16256) (xy 0.19812 -0.15367) (xy 0.20828 -0.13335)
						(xy 0.21971 -0.10287) (xy 0.22225 -0.09271) (xy 0.22479 -0.08128) (xy 0.22606 -0.07112) (xy 0.2286 -0.05969)
						(xy 0.2286 -0.01651) (xy 0.22606 -0.00508) (xy 0.22479 0.00508) (xy 0.22225 0.01651) (xy 0.21971 0.02667)
						(xy 0.20828 0.05715) (xy 0.19812 0.07747) (xy 0.19177 0.08636) (xy 0.18669 0.09525) (xy 0.17907 0.10414)
						(xy 0.17272 0.11303) (xy 0.1651 0.12065) (xy 0.1651 0.7366) (xy 0.16256 0.76835) (xy 0.1524 0.8001)
						(xy 0.13716 0.82804) (xy 0.11684 0.85344) (xy 0.09144 0.87376) (xy 0.0635 0.889) (xy 0.03175 0.89916)
					)
					(width 0)
					(fill yes)
				)
			)
		)
		(pad "132" smd custom
			(at 10.050018 -4.106672 180)
			(size 0.1143 0.1143)
			(layers "F.Cu" "F.Mask" "F.Paste")
			(net "PV_VDDR")
			(options
				(clearance outline)
				(anchor circle)
			)
			(primitives
				(gr_poly
					(pts
						(xy 0 0.9017) (xy -0.03175 0.89916) (xy -0.0635 0.889) (xy -0.09144 0.87376) (xy -0.11684 0.85344)
						(xy -0.13716 0.82804) (xy -0.1524 0.8001) (xy -0.16256 0.76835) (xy -0.1651 0.7366) (xy -0.1651 0.19685)
						(xy -0.17272 0.18923) (xy -0.17907 0.18034) (xy -0.18669 0.17145) (xy -0.19177 0.16256) (xy -0.19812 0.15367)
						(xy -0.20828 0.13335) (xy -0.21971 0.10287) (xy -0.22225 0.09271) (xy -0.22479 0.08128) (xy -0.22606 0.07112)
						(xy -0.2286 0.05969) (xy -0.2286 0.01651) (xy -0.22606 0.00508) (xy -0.22479 -0.00508) (xy -0.22225 -0.01651)
						(xy -0.21971 -0.02667) (xy -0.20828 -0.05715) (xy -0.19812 -0.07747) (xy -0.19177 -0.08636) (xy -0.18669 -0.09525)
						(xy -0.17907 -0.10414) (xy -0.17272 -0.11303) (xy -0.1651 -0.12065) (xy -0.1651 -0.7366) (xy -0.16256 -0.76835)
						(xy -0.1524 -0.8001) (xy -0.13716 -0.82804) (xy -0.11684 -0.85344) (xy -0.09144 -0.87376) (xy -0.0635 -0.889)
						(xy -0.03175 -0.89916) (xy 0 -0.9017) (xy 0.03175 -0.89916) (xy 0.0635 -0.889) (xy 0.09144 -0.87376)
						(xy 0.11684 -0.85344) (xy 0.13716 -0.82804) (xy 0.1524 -0.8001) (xy 0.16256 -0.76835) (xy 0.1651 -0.7366)
						(xy 0.1651 -0.11938) (xy 0.17272 -0.11176) (xy 0.19812 -0.0762) (xy 0.2032 -0.06604) (xy 0.20701 -0.05715)
						(xy 0.21209 -0.04699) (xy 0.2159 -0.03683) (xy 0.21844 -0.02667) (xy 0.22225 -0.01524) (xy 0.22352 -0.00508)
						(xy 0.22606 0.00508) (xy 0.22733 0.01651) (xy 0.22733 0.02667) (xy 0.2286 0.0381) (xy 0.22733 0.04953)
						(xy 0.22733 0.05969) (xy 0.22606 0.07112) (xy 0.22352 0.08128) (xy 0.22225 0.09144) (xy 0.21844 0.10287)
						(xy 0.2159 0.11303) (xy 0.21209 0.12319) (xy 0.20701 0.13335) (xy 0.2032 0.14224) (xy 0.19812 0.1524)
						(xy 0.17272 0.18796) (xy 0.1651 0.19558) (xy 0.1651 0.7366) (xy 0.16256 0.76835) (xy 0.1524 0.8001)
						(xy 0.13716 0.82804) (xy 0.11684 0.85344) (xy 0.09144 0.87376) (xy 0.0635 0.889) (xy 0.03175 0.89916)
					)
					(width 0)
					(fill yes)
				)
			)
		)
		(pad "133" smd custom
			(at 10.349992 4.106672 180)
			(size 0.1143 0.1143)
			(layers "F.Cu" "F.Mask" "F.Paste")
			(net "M_A_DQ36")
			(options
				(clearance outline)
				(anchor circle)
			)
			(primitives
				(gr_poly
					(pts
						(xy 0 0.9017) (xy -0.03175 0.89916) (xy -0.0635 0.889) (xy -0.09144 0.87376) (xy -0.11684 0.85344)
						(xy -0.13716 0.82804) (xy -0.1524 0.8001) (xy -0.16256 0.76835) (xy -0.1651 0.7366) (xy -0.1651 -0.13462)
						(xy -0.17272 -0.14224) (xy -0.19812 -0.1778) (xy -0.2032 -0.18796) (xy -0.20701 -0.19685) (xy -0.21209 -0.20701)
						(xy -0.2159 -0.21717) (xy -0.21844 -0.22733) (xy -0.22225 -0.23876) (xy -0.22352 -0.24892) (xy -0.22606 -0.25908)
						(xy -0.22733 -0.27051) (xy -0.22733 -0.28067) (xy -0.2286 -0.2921) (xy -0.22733 -0.30353) (xy -0.22733 -0.31369)
						(xy -0.22606 -0.32512) (xy -0.22352 -0.33528) (xy -0.22225 -0.34544) (xy -0.21844 -0.35687) (xy -0.2159 -0.36703)
						(xy -0.21209 -0.37719) (xy -0.20701 -0.38735) (xy -0.2032 -0.39624) (xy -0.19812 -0.4064) (xy -0.17272 -0.44196)
						(xy -0.1651 -0.44958) (xy -0.1651 -0.7366) (xy -0.16256 -0.76835) (xy -0.1524 -0.8001) (xy -0.13716 -0.82804)
						(xy -0.11684 -0.85344) (xy -0.09144 -0.87376) (xy -0.0635 -0.889) (xy -0.03175 -0.89916) (xy 0 -0.9017)
						(xy 0.03175 -0.89916) (xy 0.0635 -0.889) (xy 0.09144 -0.87376) (xy 0.11684 -0.85344) (xy 0.13716 -0.82804)
						(xy 0.1524 -0.8001) (xy 0.16256 -0.76835) (xy 0.1651 -0.7366) (xy 0.1651 -0.44958) (xy 0.17272 -0.44196)
						(xy 0.19812 -0.4064) (xy 0.2032 -0.39624) (xy 0.20701 -0.38735) (xy 0.21209 -0.37719) (xy 0.2159 -0.36703)
						(xy 0.21844 -0.35687) (xy 0.22225 -0.34544) (xy 0.22352 -0.33528) (xy 0.22606 -0.32512) (xy 0.22733 -0.31369)
						(xy 0.22733 -0.30353) (xy 0.2286 -0.2921) (xy 0.22733 -0.28067) (xy 0.22733 -0.27051) (xy 0.22606 -0.25908)
						(xy 0.22352 -0.24892) (xy 0.22225 -0.23876) (xy 0.21844 -0.22733) (xy 0.2159 -0.21717) (xy 0.21209 -0.20701)
						(xy 0.20701 -0.19685) (xy 0.2032 -0.18796) (xy 0.19812 -0.1778) (xy 0.17272 -0.14224) (xy 0.1651 -0.13462)
						(xy 0.1651 0.7366) (xy 0.16256 0.76835) (xy 0.1524 0.8001) (xy 0.13716 0.82804) (xy 0.11684 0.85344)
						(xy 0.09144 0.87376) (xy 0.0635 0.889) (xy 0.03175 0.89916)
					)
					(width 0)
					(fill yes)
				)
			)
		)
		(pad "134" smd custom
			(at 10.649966 -4.106672 180)
			(size 0.1143 0.1143)
			(layers "F.Cu" "F.Mask" "F.Paste")
			(net "M_A_DQ32")
			(options
				(clearance outline)
				(anchor circle)
			)
			(primitives
				(gr_poly
					(pts
						(xy 0 0.9017) (xy -0.03175 0.89916) (xy -0.0635 0.889) (xy -0.09144 0.87376) (xy -0.11684 0.85344)
						(xy -0.13716 0.82804) (xy -0.1524 0.8001) (xy -0.16256 0.76835) (xy -0.1651 0.7366) (xy -0.1651 0.44958)
						(xy -0.17272 0.44196) (xy -0.19812 0.4064) (xy -0.2032 0.39624) (xy -0.20701 0.38735) (xy -0.21209 0.37719)
						(xy -0.2159 0.36703) (xy -0.21844 0.35687) (xy -0.22225 0.34544) (xy -0.22352 0.33528) (xy -0.22606 0.32512)
						(xy -0.22733 0.31369) (xy -0.22733 0.30353) (xy -0.2286 0.2921) (xy -0.22733 0.28067) (xy -0.22733 0.27051)
						(xy -0.22606 0.25908) (xy -0.22352 0.24892) (xy -0.22225 0.23876) (xy -0.21844 0.22733) (xy -0.2159 0.21717)
						(xy -0.21209 0.20701) (xy -0.20701 0.19685) (xy -0.2032 0.18796) (xy -0.19812 0.1778) (xy -0.17272 0.14224)
						(xy -0.1651 0.13462) (xy -0.1651 -0.7366) (xy -0.16256 -0.76835) (xy -0.1524 -0.8001) (xy -0.13716 -0.82804)
						(xy -0.11684 -0.85344) (xy -0.09144 -0.87376) (xy -0.0635 -0.889) (xy -0.03175 -0.89916) (xy 0 -0.9017)
						(xy 0.03175 -0.89916) (xy 0.0635 -0.889) (xy 0.09144 -0.87376) (xy 0.11684 -0.85344) (xy 0.13716 -0.82804)
						(xy 0.1524 -0.8001) (xy 0.16256 -0.76835) (xy 0.1651 -0.7366) (xy 0.1651 0.13462) (xy 0.17272 0.14224)
						(xy 0.19812 0.1778) (xy 0.2032 0.18796) (xy 0.20701 0.19685) (xy 0.21209 0.20701) (xy 0.2159 0.21717)
						(xy 0.21844 0.22733) (xy 0.22225 0.23876) (xy 0.22352 0.24892) (xy 0.22606 0.25908) (xy 0.22733 0.27051)
						(xy 0.22733 0.28067) (xy 0.2286 0.2921) (xy 0.22733 0.30353) (xy 0.22733 0.31369) (xy 0.22606 0.32512)
						(xy 0.22352 0.33528) (xy 0.22225 0.34544) (xy 0.21844 0.35687) (xy 0.2159 0.36703) (xy 0.21209 0.37719)
						(xy 0.20701 0.38735) (xy 0.2032 0.39624) (xy 0.19812 0.4064) (xy 0.17272 0.44196) (xy 0.1651 0.44958)
						(xy 0.1651 0.7366) (xy 0.16256 0.76835) (xy 0.1524 0.8001) (xy 0.13716 0.82804) (xy 0.11684 0.85344)
						(xy 0.09144 0.87376) (xy 0.0635 0.889) (xy 0.03175 0.89916)
					)
					(width 0)
					(fill yes)
				)
			)
		)
		(pad "135" smd custom
			(at 10.94994 4.106672 180)
			(size 0.1143 0.1143)
			(layers "F.Cu" "F.Mask" "F.Paste")
			(net "M_A_DQ37")
			(options
				(clearance outline)
				(anchor circle)
			)
			(primitives
				(gr_poly
					(pts
						(xy 0 0.9017) (xy -0.03175 0.89916) (xy -0.0635 0.889) (xy -0.09144 0.87376) (xy -0.11684 0.85344)
						(xy -0.13716 0.82804) (xy -0.1524 0.8001) (xy -0.16256 0.76835) (xy -0.1651 0.7366) (xy -0.1651 0.11938)
						(xy -0.17272 0.11176) (xy -0.19812 0.0762) (xy -0.2032 0.06604) (xy -0.20701 0.05715) (xy -0.21209 0.04699)
						(xy -0.2159 0.03683) (xy -0.21844 0.02667) (xy -0.22225 0.01524) (xy -0.22352 0.00508) (xy -0.22606 -0.00508)
						(xy -0.22733 -0.01651) (xy -0.22733 -0.02667) (xy -0.2286 -0.0381) (xy -0.22733 -0.04953) (xy -0.22733 -0.05969)
						(xy -0.22606 -0.07112) (xy -0.22352 -0.08128) (xy -0.22225 -0.09144) (xy -0.21844 -0.10287) (xy -0.2159 -0.11303)
						(xy -0.21209 -0.12319) (xy -0.20701 -0.13335) (xy -0.2032 -0.14224) (xy -0.19812 -0.1524) (xy -0.17272 -0.18796)
						(xy -0.1651 -0.19558) (xy -0.1651 -0.7366) (xy -0.16256 -0.76835) (xy -0.1524 -0.8001) (xy -0.13716 -0.82804)
						(xy -0.11684 -0.85344) (xy -0.09144 -0.87376) (xy -0.0635 -0.889) (xy -0.03175 -0.89916) (xy 0 -0.9017)
						(xy 0.03175 -0.89916) (xy 0.0635 -0.889) (xy 0.09144 -0.87376) (xy 0.11684 -0.85344) (xy 0.13716 -0.82804)
						(xy 0.1524 -0.8001) (xy 0.16256 -0.76835) (xy 0.1651 -0.7366) (xy 0.1651 -0.19685) (xy 0.17272 -0.18923)
						(xy 0.17907 -0.18034) (xy 0.18669 -0.17145) (xy 0.19177 -0.16256) (xy 0.19812 -0.15367) (xy 0.20828 -0.13335)
						(xy 0.21971 -0.10287) (xy 0.22225 -0.09271) (xy 0.22479 -0.08128) (xy 0.22606 -0.07112) (xy 0.2286 -0.05969)
						(xy 0.2286 -0.01651) (xy 0.22606 -0.00508) (xy 0.22479 0.00508) (xy 0.22225 0.01651) (xy 0.21971 0.02667)
						(xy 0.20828 0.05715) (xy 0.19812 0.07747) (xy 0.19177 0.08636) (xy 0.18669 0.09525) (xy 0.17907 0.10414)
						(xy 0.17272 0.11303) (xy 0.1651 0.12065) (xy 0.1651 0.7366) (xy 0.16256 0.76835) (xy 0.1524 0.8001)
						(xy 0.13716 0.82804) (xy 0.11684 0.85344) (xy 0.09144 0.87376) (xy 0.0635 0.889) (xy 0.03175 0.89916)
					)
					(width 0)
					(fill yes)
				)
			)
		)
		(pad "136" smd custom
			(at 11.249914 -4.106672 180)
			(size 0.1143 0.1143)
			(layers "F.Cu" "F.Mask" "F.Paste")
			(net "M_A_DQ33")
			(options
				(clearance outline)
				(anchor circle)
			)
			(primitives
				(gr_poly
					(pts
						(xy 0 0.9017) (xy -0.03175 0.89916) (xy -0.0635 0.889) (xy -0.09144 0.87376) (xy -0.11684 0.85344)
						(xy -0.13716 0.82804) (xy -0.1524 0.8001) (xy -0.16256 0.76835) (xy -0.1651 0.7366) (xy -0.1651 0.19685)
						(xy -0.17272 0.18923) (xy -0.17907 0.18034) (xy -0.18669 0.17145) (xy -0.19177 0.16256) (xy -0.19812 0.15367)
						(xy -0.20828 0.13335) (xy -0.21971 0.10287) (xy -0.22225 0.09271) (xy -0.22479 0.08128) (xy -0.22606 0.07112)
						(xy -0.2286 0.05969) (xy -0.2286 0.01651) (xy -0.22606 0.00508) (xy -0.22479 -0.00508) (xy -0.22225 -0.01651)
						(xy -0.21971 -0.02667) (xy -0.20828 -0.05715) (xy -0.19812 -0.07747) (xy -0.19177 -0.08636) (xy -0.18669 -0.09525)
						(xy -0.17907 -0.10414) (xy -0.17272 -0.11303) (xy -0.1651 -0.12065) (xy -0.1651 -0.7366) (xy -0.16256 -0.76835)
						(xy -0.1524 -0.8001) (xy -0.13716 -0.82804) (xy -0.11684 -0.85344) (xy -0.09144 -0.87376) (xy -0.0635 -0.889)
						(xy -0.03175 -0.89916) (xy 0 -0.9017) (xy 0.03175 -0.89916) (xy 0.0635 -0.889) (xy 0.09144 -0.87376)
						(xy 0.11684 -0.85344) (xy 0.13716 -0.82804) (xy 0.1524 -0.8001) (xy 0.16256 -0.76835) (xy 0.1651 -0.7366)
						(xy 0.1651 -0.11938) (xy 0.17272 -0.11176) (xy 0.19812 -0.0762) (xy 0.2032 -0.06604) (xy 0.20701 -0.05715)
						(xy 0.21209 -0.04699) (xy 0.2159 -0.03683) (xy 0.21844 -0.02667) (xy 0.22225 -0.01524) (xy 0.22352 -0.00508)
						(xy 0.22606 0.00508) (xy 0.22733 0.01651) (xy 0.22733 0.02667) (xy 0.2286 0.0381) (xy 0.22733 0.04953)
						(xy 0.22733 0.05969) (xy 0.22606 0.07112) (xy 0.22352 0.08128) (xy 0.22225 0.09144) (xy 0.21844 0.10287)
						(xy 0.2159 0.11303) (xy 0.21209 0.12319) (xy 0.20701 0.13335) (xy 0.2032 0.14224) (xy 0.19812 0.1524)
						(xy 0.17272 0.18796) (xy 0.1651 0.19558) (xy 0.1651 0.7366) (xy 0.16256 0.76835) (xy 0.1524 0.8001)
						(xy 0.13716 0.82804) (xy 0.11684 0.85344) (xy 0.09144 0.87376) (xy 0.0635 0.889) (xy 0.03175 0.89916)
					)
					(width 0)
					(fill yes)
				)
			)
		)
		(pad "137" smd custom
			(at 11.549888 4.106672 180)
			(size 0.1143 0.1143)
			(layers "F.Cu" "F.Mask" "F.Paste")
			(net "GND")
			(options
				(clearance outline)
				(anchor circle)
			)
			(primitives
				(gr_poly
					(pts
						(xy 0 0.9017) (xy -0.03175 0.89916) (xy -0.0635 0.889) (xy -0.09144 0.87376) (xy -0.11684 0.85344)
						(xy -0.13716 0.82804) (xy -0.1524 0.8001) (xy -0.16256 0.76835) (xy -0.1651 0.7366) (xy -0.1651 -0.13462)
						(xy -0.17272 -0.14224) (xy -0.19812 -0.1778) (xy -0.2032 -0.18796) (xy -0.20701 -0.19685) (xy -0.21209 -0.20701)
						(xy -0.2159 -0.21717) (xy -0.21844 -0.22733) (xy -0.22225 -0.23876) (xy -0.22352 -0.24892) (xy -0.22606 -0.25908)
						(xy -0.22733 -0.27051) (xy -0.22733 -0.28067) (xy -0.2286 -0.2921) (xy -0.22733 -0.30353) (xy -0.22733 -0.31369)
						(xy -0.22606 -0.32512) (xy -0.22352 -0.33528) (xy -0.22225 -0.34544) (xy -0.21844 -0.35687) (xy -0.2159 -0.36703)
						(xy -0.21209 -0.37719) (xy -0.20701 -0.38735) (xy -0.2032 -0.39624) (xy -0.19812 -0.4064) (xy -0.17272 -0.44196)
						(xy -0.1651 -0.44958) (xy -0.1651 -0.7366) (xy -0.16256 -0.76835) (xy -0.1524 -0.8001) (xy -0.13716 -0.82804)
						(xy -0.11684 -0.85344) (xy -0.09144 -0.87376) (xy -0.0635 -0.889) (xy -0.03175 -0.89916) (xy 0 -0.9017)
						(xy 0.03175 -0.89916) (xy 0.0635 -0.889) (xy 0.09144 -0.87376) (xy 0.11684 -0.85344) (xy 0.13716 -0.82804)
						(xy 0.1524 -0.8001) (xy 0.16256 -0.76835) (xy 0.1651 -0.7366) (xy 0.1651 -0.44958) (xy 0.17272 -0.44196)
						(xy 0.19812 -0.4064) (xy 0.2032 -0.39624) (xy 0.20701 -0.38735) (xy 0.21209 -0.37719) (xy 0.2159 -0.36703)
						(xy 0.21844 -0.35687) (xy 0.22225 -0.34544) (xy 0.22352 -0.33528) (xy 0.22606 -0.32512) (xy 0.22733 -0.31369)
						(xy 0.22733 -0.30353) (xy 0.2286 -0.2921) (xy 0.22733 -0.28067) (xy 0.22733 -0.27051) (xy 0.22606 -0.25908)
						(xy 0.22352 -0.24892) (xy 0.22225 -0.23876) (xy 0.21844 -0.22733) (xy 0.2159 -0.21717) (xy 0.21209 -0.20701)
						(xy 0.20701 -0.19685) (xy 0.2032 -0.18796) (xy 0.19812 -0.1778) (xy 0.17272 -0.14224) (xy 0.1651 -0.13462)
						(xy 0.1651 0.7366) (xy 0.16256 0.76835) (xy 0.1524 0.8001) (xy 0.13716 0.82804) (xy 0.11684 0.85344)
						(xy 0.09144 0.87376) (xy 0.0635 0.889) (xy 0.03175 0.89916)
					)
					(width 0)
					(fill yes)
				)
			)
		)
		(pad "138" smd custom
			(at 11.850116 -4.106672 180)
			(size 0.1143 0.1143)
			(layers "F.Cu" "F.Mask" "F.Paste")
			(net "GND")
			(options
				(clearance outline)
				(anchor circle)
			)
			(primitives
				(gr_poly
					(pts
						(xy 0 0.9017) (xy -0.03175 0.89916) (xy -0.0635 0.889) (xy -0.09144 0.87376) (xy -0.11684 0.85344)
						(xy -0.13716 0.82804) (xy -0.1524 0.8001) (xy -0.16256 0.76835) (xy -0.1651 0.7366) (xy -0.1651 0.44958)
						(xy -0.17272 0.44196) (xy -0.19812 0.4064) (xy -0.2032 0.39624) (xy -0.20701 0.38735) (xy -0.21209 0.37719)
						(xy -0.2159 0.36703) (xy -0.21844 0.35687) (xy -0.22225 0.34544) (xy -0.22352 0.33528) (xy -0.22606 0.32512)
						(xy -0.22733 0.31369) (xy -0.22733 0.30353) (xy -0.2286 0.2921) (xy -0.22733 0.28067) (xy -0.22733 0.27051)
						(xy -0.22606 0.25908) (xy -0.22352 0.24892) (xy -0.22225 0.23876) (xy -0.21844 0.22733) (xy -0.2159 0.21717)
						(xy -0.21209 0.20701) (xy -0.20701 0.19685) (xy -0.2032 0.18796) (xy -0.19812 0.1778) (xy -0.17272 0.14224)
						(xy -0.1651 0.13462) (xy -0.1651 -0.7366) (xy -0.16256 -0.76835) (xy -0.1524 -0.8001) (xy -0.13716 -0.82804)
						(xy -0.11684 -0.85344) (xy -0.09144 -0.87376) (xy -0.0635 -0.889) (xy -0.03175 -0.89916) (xy 0 -0.9017)
						(xy 0.03175 -0.89916) (xy 0.0635 -0.889) (xy 0.09144 -0.87376) (xy 0.11684 -0.85344) (xy 0.13716 -0.82804)
						(xy 0.1524 -0.8001) (xy 0.16256 -0.76835) (xy 0.1651 -0.7366) (xy 0.1651 0.13462) (xy 0.17272 0.14224)
						(xy 0.19812 0.1778) (xy 0.2032 0.18796) (xy 0.20701 0.19685) (xy 0.21209 0.20701) (xy 0.2159 0.21717)
						(xy 0.21844 0.22733) (xy 0.22225 0.23876) (xy 0.22352 0.24892) (xy 0.22606 0.25908) (xy 0.22733 0.27051)
						(xy 0.22733 0.28067) (xy 0.2286 0.2921) (xy 0.22733 0.30353) (xy 0.22733 0.31369) (xy 0.22606 0.32512)
						(xy 0.22352 0.33528) (xy 0.22225 0.34544) (xy 0.21844 0.35687) (xy 0.2159 0.36703) (xy 0.21209 0.37719)
						(xy 0.20701 0.38735) (xy 0.2032 0.39624) (xy 0.19812 0.4064) (xy 0.17272 0.44196) (xy 0.1651 0.44958)
						(xy 0.1651 0.7366) (xy 0.16256 0.76835) (xy 0.1524 0.8001) (xy 0.13716 0.82804) (xy 0.11684 0.85344)
						(xy 0.09144 0.87376) (xy 0.0635 0.889) (xy 0.03175 0.89916)
					)
					(width 0)
					(fill yes)
				)
			)
		)
		(pad "139" smd custom
			(at 12.15009 4.106672 180)
			(size 0.1143 0.1143)
			(layers "F.Cu" "F.Mask" "F.Paste")
			(net "M_A_DQS_DN4")
			(options
				(clearance outline)
				(anchor circle)
			)
			(primitives
				(gr_poly
					(pts
						(xy 0 0.9017) (xy -0.03175 0.89916) (xy -0.0635 0.889) (xy -0.09144 0.87376) (xy -0.11684 0.85344)
						(xy -0.13716 0.82804) (xy -0.1524 0.8001) (xy -0.16256 0.76835) (xy -0.1651 0.7366) (xy -0.1651 0.11938)
						(xy -0.17272 0.11176) (xy -0.19812 0.0762) (xy -0.2032 0.06604) (xy -0.20701 0.05715) (xy -0.21209 0.04699)
						(xy -0.2159 0.03683) (xy -0.21844 0.02667) (xy -0.22225 0.01524) (xy -0.22352 0.00508) (xy -0.22606 -0.00508)
						(xy -0.22733 -0.01651) (xy -0.22733 -0.02667) (xy -0.2286 -0.0381) (xy -0.22733 -0.04953) (xy -0.22733 -0.05969)
						(xy -0.22606 -0.07112) (xy -0.22352 -0.08128) (xy -0.22225 -0.09144) (xy -0.21844 -0.10287) (xy -0.2159 -0.11303)
						(xy -0.21209 -0.12319) (xy -0.20701 -0.13335) (xy -0.2032 -0.14224) (xy -0.19812 -0.1524) (xy -0.17272 -0.18796)
						(xy -0.1651 -0.19558) (xy -0.1651 -0.7366) (xy -0.16256 -0.76835) (xy -0.1524 -0.8001) (xy -0.13716 -0.82804)
						(xy -0.11684 -0.85344) (xy -0.09144 -0.87376) (xy -0.0635 -0.889) (xy -0.03175 -0.89916) (xy 0 -0.9017)
						(xy 0.03175 -0.89916) (xy 0.0635 -0.889) (xy 0.09144 -0.87376) (xy 0.11684 -0.85344) (xy 0.13716 -0.82804)
						(xy 0.1524 -0.8001) (xy 0.16256 -0.76835) (xy 0.1651 -0.7366) (xy 0.1651 -0.19685) (xy 0.17272 -0.18923)
						(xy 0.17907 -0.18034) (xy 0.18669 -0.17145) (xy 0.19177 -0.16256) (xy 0.19812 -0.15367) (xy 0.20828 -0.13335)
						(xy 0.21971 -0.10287) (xy 0.22225 -0.09271) (xy 0.22479 -0.08128) (xy 0.22606 -0.07112) (xy 0.2286 -0.05969)
						(xy 0.2286 -0.01651) (xy 0.22606 -0.00508) (xy 0.22479 0.00508) (xy 0.22225 0.01651) (xy 0.21971 0.02667)
						(xy 0.20828 0.05715) (xy 0.19812 0.07747) (xy 0.19177 0.08636) (xy 0.18669 0.09525) (xy 0.17907 0.10414)
						(xy 0.17272 0.11303) (xy 0.1651 0.12065) (xy 0.1651 0.7366) (xy 0.16256 0.76835) (xy 0.1524 0.8001)
						(xy 0.13716 0.82804) (xy 0.11684 0.85344) (xy 0.09144 0.87376) (xy 0.0635 0.889) (xy 0.03175 0.89916)
					)
					(width 0)
					(fill yes)
				)
			)
		)
		(pad "140" smd custom
			(at 12.450064 -4.106672 180)
			(size 0.1143 0.1143)
			(layers "F.Cu" "F.Mask" "F.Paste")
			(net "GND")
			(options
				(clearance outline)
				(anchor circle)
			)
			(primitives
				(gr_poly
					(pts
						(xy 0 0.9017) (xy -0.03175 0.89916) (xy -0.0635 0.889) (xy -0.09144 0.87376) (xy -0.11684 0.85344)
						(xy -0.13716 0.82804) (xy -0.1524 0.8001) (xy -0.16256 0.76835) (xy -0.1651 0.7366) (xy -0.1651 0.19685)
						(xy -0.17272 0.18923) (xy -0.17907 0.18034) (xy -0.18669 0.17145) (xy -0.19177 0.16256) (xy -0.19812 0.15367)
						(xy -0.20828 0.13335) (xy -0.21971 0.10287) (xy -0.22225 0.09271) (xy -0.22479 0.08128) (xy -0.22606 0.07112)
						(xy -0.2286 0.05969) (xy -0.2286 0.01651) (xy -0.22606 0.00508) (xy -0.22479 -0.00508) (xy -0.22225 -0.01651)
						(xy -0.21971 -0.02667) (xy -0.20828 -0.05715) (xy -0.19812 -0.07747) (xy -0.19177 -0.08636) (xy -0.18669 -0.09525)
						(xy -0.17907 -0.10414) (xy -0.17272 -0.11303) (xy -0.1651 -0.12065) (xy -0.1651 -0.7366) (xy -0.16256 -0.76835)
						(xy -0.1524 -0.8001) (xy -0.13716 -0.82804) (xy -0.11684 -0.85344) (xy -0.09144 -0.87376) (xy -0.0635 -0.889)
						(xy -0.03175 -0.89916) (xy 0 -0.9017) (xy 0.03175 -0.89916) (xy 0.0635 -0.889) (xy 0.09144 -0.87376)
						(xy 0.11684 -0.85344) (xy 0.13716 -0.82804) (xy 0.1524 -0.8001) (xy 0.16256 -0.76835) (xy 0.1651 -0.7366)
						(xy 0.1651 -0.11938) (xy 0.17272 -0.11176) (xy 0.19812 -0.0762) (xy 0.2032 -0.06604) (xy 0.20701 -0.05715)
						(xy 0.21209 -0.04699) (xy 0.2159 -0.03683) (xy 0.21844 -0.02667) (xy 0.22225 -0.01524) (xy 0.22352 -0.00508)
						(xy 0.22606 0.00508) (xy 0.22733 0.01651) (xy 0.22733 0.02667) (xy 0.2286 0.0381) (xy 0.22733 0.04953)
						(xy 0.22733 0.05969) (xy 0.22606 0.07112) (xy 0.22352 0.08128) (xy 0.22225 0.09144) (xy 0.21844 0.10287)
						(xy 0.2159 0.11303) (xy 0.21209 0.12319) (xy 0.20701 0.13335) (xy 0.2032 0.14224) (xy 0.19812 0.1524)
						(xy 0.17272 0.18796) (xy 0.1651 0.19558) (xy 0.1651 0.7366) (xy 0.16256 0.76835) (xy 0.1524 0.8001)
						(xy 0.13716 0.82804) (xy 0.11684 0.85344) (xy 0.09144 0.87376) (xy 0.0635 0.889) (xy 0.03175 0.89916)
					)
					(width 0)
					(fill yes)
				)
			)
		)
		(pad "141" smd custom
			(at 12.750038 4.106672 180)
			(size 0.1143 0.1143)
			(layers "F.Cu" "F.Mask" "F.Paste")
			(net "M_A_DQS_DP4")
			(options
				(clearance outline)
				(anchor circle)
			)
			(primitives
				(gr_poly
					(pts
						(xy 0 0.9017) (xy -0.03175 0.89916) (xy -0.0635 0.889) (xy -0.09144 0.87376) (xy -0.11684 0.85344)
						(xy -0.13716 0.82804) (xy -0.1524 0.8001) (xy -0.16256 0.76835) (xy -0.1651 0.7366) (xy -0.1651 -0.13462)
						(xy -0.17272 -0.14224) (xy -0.19812 -0.1778) (xy -0.2032 -0.18796) (xy -0.20701 -0.19685) (xy -0.21209 -0.20701)
						(xy -0.2159 -0.21717) (xy -0.21844 -0.22733) (xy -0.22225 -0.23876) (xy -0.22352 -0.24892) (xy -0.22606 -0.25908)
						(xy -0.22733 -0.27051) (xy -0.22733 -0.28067) (xy -0.2286 -0.2921) (xy -0.22733 -0.30353) (xy -0.22733 -0.31369)
						(xy -0.22606 -0.32512) (xy -0.22352 -0.33528) (xy -0.22225 -0.34544) (xy -0.21844 -0.35687) (xy -0.2159 -0.36703)
						(xy -0.21209 -0.37719) (xy -0.20701 -0.38735) (xy -0.2032 -0.39624) (xy -0.19812 -0.4064) (xy -0.17272 -0.44196)
						(xy -0.1651 -0.44958) (xy -0.1651 -0.7366) (xy -0.16256 -0.76835) (xy -0.1524 -0.8001) (xy -0.13716 -0.82804)
						(xy -0.11684 -0.85344) (xy -0.09144 -0.87376) (xy -0.0635 -0.889) (xy -0.03175 -0.89916) (xy 0 -0.9017)
						(xy 0.03175 -0.89916) (xy 0.0635 -0.889) (xy 0.09144 -0.87376) (xy 0.11684 -0.85344) (xy 0.13716 -0.82804)
						(xy 0.1524 -0.8001) (xy 0.16256 -0.76835) (xy 0.1651 -0.7366) (xy 0.1651 -0.44958) (xy 0.17272 -0.44196)
						(xy 0.19812 -0.4064) (xy 0.2032 -0.39624) (xy 0.20701 -0.38735) (xy 0.21209 -0.37719) (xy 0.2159 -0.36703)
						(xy 0.21844 -0.35687) (xy 0.22225 -0.34544) (xy 0.22352 -0.33528) (xy 0.22606 -0.32512) (xy 0.22733 -0.31369)
						(xy 0.22733 -0.30353) (xy 0.2286 -0.2921) (xy 0.22733 -0.28067) (xy 0.22733 -0.27051) (xy 0.22606 -0.25908)
						(xy 0.22352 -0.24892) (xy 0.22225 -0.23876) (xy 0.21844 -0.22733) (xy 0.2159 -0.21717) (xy 0.21209 -0.20701)
						(xy 0.20701 -0.19685) (xy 0.2032 -0.18796) (xy 0.19812 -0.1778) (xy 0.17272 -0.14224) (xy 0.1651 -0.13462)
						(xy 0.1651 0.7366) (xy 0.16256 0.76835) (xy 0.1524 0.8001) (xy 0.13716 0.82804) (xy 0.11684 0.85344)
						(xy 0.09144 0.87376) (xy 0.0635 0.889) (xy 0.03175 0.89916)
					)
					(width 0)
					(fill yes)
				)
			)
		)
		(pad "142" smd custom
			(at 13.050012 -4.106672 180)
			(size 0.1143 0.1143)
			(layers "F.Cu" "F.Mask" "F.Paste")
			(net "M_A_DQ34")
			(options
				(clearance outline)
				(anchor circle)
			)
			(primitives
				(gr_poly
					(pts
						(xy 0 0.9017) (xy -0.03175 0.89916) (xy -0.0635 0.889) (xy -0.09144 0.87376) (xy -0.11684 0.85344)
						(xy -0.13716 0.82804) (xy -0.1524 0.8001) (xy -0.16256 0.76835) (xy -0.1651 0.7366) (xy -0.1651 0.44958)
						(xy -0.17272 0.44196) (xy -0.19812 0.4064) (xy -0.2032 0.39624) (xy -0.20701 0.38735) (xy -0.21209 0.37719)
						(xy -0.2159 0.36703) (xy -0.21844 0.35687) (xy -0.22225 0.34544) (xy -0.22352 0.33528) (xy -0.22606 0.32512)
						(xy -0.22733 0.31369) (xy -0.22733 0.30353) (xy -0.2286 0.2921) (xy -0.22733 0.28067) (xy -0.22733 0.27051)
						(xy -0.22606 0.25908) (xy -0.22352 0.24892) (xy -0.22225 0.23876) (xy -0.21844 0.22733) (xy -0.2159 0.21717)
						(xy -0.21209 0.20701) (xy -0.20701 0.19685) (xy -0.2032 0.18796) (xy -0.19812 0.1778) (xy -0.17272 0.14224)
						(xy -0.1651 0.13462) (xy -0.1651 -0.7366) (xy -0.16256 -0.76835) (xy -0.1524 -0.8001) (xy -0.13716 -0.82804)
						(xy -0.11684 -0.85344) (xy -0.09144 -0.87376) (xy -0.0635 -0.889) (xy -0.03175 -0.89916) (xy 0 -0.9017)
						(xy 0.03175 -0.89916) (xy 0.0635 -0.889) (xy 0.09144 -0.87376) (xy 0.11684 -0.85344) (xy 0.13716 -0.82804)
						(xy 0.1524 -0.8001) (xy 0.16256 -0.76835) (xy 0.1651 -0.7366) (xy 0.1651 0.13462) (xy 0.17272 0.14224)
						(xy 0.19812 0.1778) (xy 0.2032 0.18796) (xy 0.20701 0.19685) (xy 0.21209 0.20701) (xy 0.2159 0.21717)
						(xy 0.21844 0.22733) (xy 0.22225 0.23876) (xy 0.22352 0.24892) (xy 0.22606 0.25908) (xy 0.22733 0.27051)
						(xy 0.22733 0.28067) (xy 0.2286 0.2921) (xy 0.22733 0.30353) (xy 0.22733 0.31369) (xy 0.22606 0.32512)
						(xy 0.22352 0.33528) (xy 0.22225 0.34544) (xy 0.21844 0.35687) (xy 0.2159 0.36703) (xy 0.21209 0.37719)
						(xy 0.20701 0.38735) (xy 0.2032 0.39624) (xy 0.19812 0.4064) (xy 0.17272 0.44196) (xy 0.1651 0.44958)
						(xy 0.1651 0.7366) (xy 0.16256 0.76835) (xy 0.1524 0.8001) (xy 0.13716 0.82804) (xy 0.11684 0.85344)
						(xy 0.09144 0.87376) (xy 0.0635 0.889) (xy 0.03175 0.89916)
					)
					(width 0)
					(fill yes)
				)
			)
		)
		(pad "143" smd custom
			(at 13.349986 4.106672 180)
			(size 0.1143 0.1143)
			(layers "F.Cu" "F.Mask" "F.Paste")
			(net "GND")
			(options
				(clearance outline)
				(anchor circle)
			)
			(primitives
				(gr_poly
					(pts
						(xy 0 0.9017) (xy -0.03175 0.89916) (xy -0.0635 0.889) (xy -0.09144 0.87376) (xy -0.11684 0.85344)
						(xy -0.13716 0.82804) (xy -0.1524 0.8001) (xy -0.16256 0.76835) (xy -0.1651 0.7366) (xy -0.1651 0.11938)
						(xy -0.17272 0.11176) (xy -0.19812 0.0762) (xy -0.2032 0.06604) (xy -0.20701 0.05715) (xy -0.21209 0.04699)
						(xy -0.2159 0.03683) (xy -0.21844 0.02667) (xy -0.22225 0.01524) (xy -0.22352 0.00508) (xy -0.22606 -0.00508)
						(xy -0.22733 -0.01651) (xy -0.22733 -0.02667) (xy -0.2286 -0.0381) (xy -0.22733 -0.04953) (xy -0.22733 -0.05969)
						(xy -0.22606 -0.07112) (xy -0.22352 -0.08128) (xy -0.22225 -0.09144) (xy -0.21844 -0.10287) (xy -0.2159 -0.11303)
						(xy -0.21209 -0.12319) (xy -0.20701 -0.13335) (xy -0.2032 -0.14224) (xy -0.19812 -0.1524) (xy -0.17272 -0.18796)
						(xy -0.1651 -0.19558) (xy -0.1651 -0.7366) (xy -0.16256 -0.76835) (xy -0.1524 -0.8001) (xy -0.13716 -0.82804)
						(xy -0.11684 -0.85344) (xy -0.09144 -0.87376) (xy -0.0635 -0.889) (xy -0.03175 -0.89916) (xy 0 -0.9017)
						(xy 0.03175 -0.89916) (xy 0.0635 -0.889) (xy 0.09144 -0.87376) (xy 0.11684 -0.85344) (xy 0.13716 -0.82804)
						(xy 0.1524 -0.8001) (xy 0.16256 -0.76835) (xy 0.1651 -0.7366) (xy 0.1651 -0.19685) (xy 0.17272 -0.18923)
						(xy 0.17907 -0.18034) (xy 0.18669 -0.17145) (xy 0.19177 -0.16256) (xy 0.19812 -0.15367) (xy 0.20828 -0.13335)
						(xy 0.21971 -0.10287) (xy 0.22225 -0.09271) (xy 0.22479 -0.08128) (xy 0.22606 -0.07112) (xy 0.2286 -0.05969)
						(xy 0.2286 -0.01651) (xy 0.22606 -0.00508) (xy 0.22479 0.00508) (xy 0.22225 0.01651) (xy 0.21971 0.02667)
						(xy 0.20828 0.05715) (xy 0.19812 0.07747) (xy 0.19177 0.08636) (xy 0.18669 0.09525) (xy 0.17907 0.10414)
						(xy 0.17272 0.11303) (xy 0.1651 0.12065) (xy 0.1651 0.7366) (xy 0.16256 0.76835) (xy 0.1524 0.8001)
						(xy 0.13716 0.82804) (xy 0.11684 0.85344) (xy 0.09144 0.87376) (xy 0.0635 0.889) (xy 0.03175 0.89916)
					)
					(width 0)
					(fill yes)
				)
			)
		)
		(pad "144" smd custom
			(at 13.64996 -4.106672 180)
			(size 0.1143 0.1143)
			(layers "F.Cu" "F.Mask" "F.Paste")
			(net "M_A_DQ35")
			(options
				(clearance outline)
				(anchor circle)
			)
			(primitives
				(gr_poly
					(pts
						(xy 0 0.9017) (xy -0.03175 0.89916) (xy -0.0635 0.889) (xy -0.09144 0.87376) (xy -0.11684 0.85344)
						(xy -0.13716 0.82804) (xy -0.1524 0.8001) (xy -0.16256 0.76835) (xy -0.1651 0.7366) (xy -0.1651 0.19685)
						(xy -0.17272 0.18923) (xy -0.17907 0.18034) (xy -0.18669 0.17145) (xy -0.19177 0.16256) (xy -0.19812 0.15367)
						(xy -0.20828 0.13335) (xy -0.21971 0.10287) (xy -0.22225 0.09271) (xy -0.22479 0.08128) (xy -0.22606 0.07112)
						(xy -0.2286 0.05969) (xy -0.2286 0.01651) (xy -0.22606 0.00508) (xy -0.22479 -0.00508) (xy -0.22225 -0.01651)
						(xy -0.21971 -0.02667) (xy -0.20828 -0.05715) (xy -0.19812 -0.07747) (xy -0.19177 -0.08636) (xy -0.18669 -0.09525)
						(xy -0.17907 -0.10414) (xy -0.17272 -0.11303) (xy -0.1651 -0.12065) (xy -0.1651 -0.7366) (xy -0.16256 -0.76835)
						(xy -0.1524 -0.8001) (xy -0.13716 -0.82804) (xy -0.11684 -0.85344) (xy -0.09144 -0.87376) (xy -0.0635 -0.889)
						(xy -0.03175 -0.89916) (xy 0 -0.9017) (xy 0.03175 -0.89916) (xy 0.0635 -0.889) (xy 0.09144 -0.87376)
						(xy 0.11684 -0.85344) (xy 0.13716 -0.82804) (xy 0.1524 -0.8001) (xy 0.16256 -0.76835) (xy 0.1651 -0.7366)
						(xy 0.1651 -0.11938) (xy 0.17272 -0.11176) (xy 0.19812 -0.0762) (xy 0.2032 -0.06604) (xy 0.20701 -0.05715)
						(xy 0.21209 -0.04699) (xy 0.2159 -0.03683) (xy 0.21844 -0.02667) (xy 0.22225 -0.01524) (xy 0.22352 -0.00508)
						(xy 0.22606 0.00508) (xy 0.22733 0.01651) (xy 0.22733 0.02667) (xy 0.2286 0.0381) (xy 0.22733 0.04953)
						(xy 0.22733 0.05969) (xy 0.22606 0.07112) (xy 0.22352 0.08128) (xy 0.22225 0.09144) (xy 0.21844 0.10287)
						(xy 0.2159 0.11303) (xy 0.21209 0.12319) (xy 0.20701 0.13335) (xy 0.2032 0.14224) (xy 0.19812 0.1524)
						(xy 0.17272 0.18796) (xy 0.1651 0.19558) (xy 0.1651 0.7366) (xy 0.16256 0.76835) (xy 0.1524 0.8001)
						(xy 0.13716 0.82804) (xy 0.11684 0.85344) (xy 0.09144 0.87376) (xy 0.0635 0.889) (xy 0.03175 0.89916)
					)
					(width 0)
					(fill yes)
				)
			)
		)
		(pad "145" smd custom
			(at 13.949934 4.106672 180)
			(size 0.1143 0.1143)
			(layers "F.Cu" "F.Mask" "F.Paste")
			(net "M_A_DQ38")
			(options
				(clearance outline)
				(anchor circle)
			)
			(primitives
				(gr_poly
					(pts
						(xy 0 0.9017) (xy -0.03175 0.89916) (xy -0.0635 0.889) (xy -0.09144 0.87376) (xy -0.11684 0.85344)
						(xy -0.13716 0.82804) (xy -0.1524 0.8001) (xy -0.16256 0.76835) (xy -0.1651 0.7366) (xy -0.1651 -0.13462)
						(xy -0.17272 -0.14224) (xy -0.19812 -0.1778) (xy -0.2032 -0.18796) (xy -0.20701 -0.19685) (xy -0.21209 -0.20701)
						(xy -0.2159 -0.21717) (xy -0.21844 -0.22733) (xy -0.22225 -0.23876) (xy -0.22352 -0.24892) (xy -0.22606 -0.25908)
						(xy -0.22733 -0.27051) (xy -0.22733 -0.28067) (xy -0.2286 -0.2921) (xy -0.22733 -0.30353) (xy -0.22733 -0.31369)
						(xy -0.22606 -0.32512) (xy -0.22352 -0.33528) (xy -0.22225 -0.34544) (xy -0.21844 -0.35687) (xy -0.2159 -0.36703)
						(xy -0.21209 -0.37719) (xy -0.20701 -0.38735) (xy -0.2032 -0.39624) (xy -0.19812 -0.4064) (xy -0.17272 -0.44196)
						(xy -0.1651 -0.44958) (xy -0.1651 -0.7366) (xy -0.16256 -0.76835) (xy -0.1524 -0.8001) (xy -0.13716 -0.82804)
						(xy -0.11684 -0.85344) (xy -0.09144 -0.87376) (xy -0.0635 -0.889) (xy -0.03175 -0.89916) (xy 0 -0.9017)
						(xy 0.03175 -0.89916) (xy 0.0635 -0.889) (xy 0.09144 -0.87376) (xy 0.11684 -0.85344) (xy 0.13716 -0.82804)
						(xy 0.1524 -0.8001) (xy 0.16256 -0.76835) (xy 0.1651 -0.7366) (xy 0.1651 -0.44958) (xy 0.17272 -0.44196)
						(xy 0.19812 -0.4064) (xy 0.2032 -0.39624) (xy 0.20701 -0.38735) (xy 0.21209 -0.37719) (xy 0.2159 -0.36703)
						(xy 0.21844 -0.35687) (xy 0.22225 -0.34544) (xy 0.22352 -0.33528) (xy 0.22606 -0.32512) (xy 0.22733 -0.31369)
						(xy 0.22733 -0.30353) (xy 0.2286 -0.2921) (xy 0.22733 -0.28067) (xy 0.22733 -0.27051) (xy 0.22606 -0.25908)
						(xy 0.22352 -0.24892) (xy 0.22225 -0.23876) (xy 0.21844 -0.22733) (xy 0.2159 -0.21717) (xy 0.21209 -0.20701)
						(xy 0.20701 -0.19685) (xy 0.2032 -0.18796) (xy 0.19812 -0.1778) (xy 0.17272 -0.14224) (xy 0.1651 -0.13462)
						(xy 0.1651 0.7366) (xy 0.16256 0.76835) (xy 0.1524 0.8001) (xy 0.13716 0.82804) (xy 0.11684 0.85344)
						(xy 0.09144 0.87376) (xy 0.0635 0.889) (xy 0.03175 0.89916)
					)
					(width 0)
					(fill yes)
				)
			)
		)
		(pad "146" smd custom
			(at 14.249908 -4.106672 180)
			(size 0.1143 0.1143)
			(layers "F.Cu" "F.Mask" "F.Paste")
			(net "GND")
			(options
				(clearance outline)
				(anchor circle)
			)
			(primitives
				(gr_poly
					(pts
						(xy 0 0.9017) (xy -0.03175 0.89916) (xy -0.0635 0.889) (xy -0.09144 0.87376) (xy -0.11684 0.85344)
						(xy -0.13716 0.82804) (xy -0.1524 0.8001) (xy -0.16256 0.76835) (xy -0.1651 0.7366) (xy -0.1651 0.44958)
						(xy -0.17272 0.44196) (xy -0.19812 0.4064) (xy -0.2032 0.39624) (xy -0.20701 0.38735) (xy -0.21209 0.37719)
						(xy -0.2159 0.36703) (xy -0.21844 0.35687) (xy -0.22225 0.34544) (xy -0.22352 0.33528) (xy -0.22606 0.32512)
						(xy -0.22733 0.31369) (xy -0.22733 0.30353) (xy -0.2286 0.2921) (xy -0.22733 0.28067) (xy -0.22733 0.27051)
						(xy -0.22606 0.25908) (xy -0.22352 0.24892) (xy -0.22225 0.23876) (xy -0.21844 0.22733) (xy -0.2159 0.21717)
						(xy -0.21209 0.20701) (xy -0.20701 0.19685) (xy -0.2032 0.18796) (xy -0.19812 0.1778) (xy -0.17272 0.14224)
						(xy -0.1651 0.13462) (xy -0.1651 -0.7366) (xy -0.16256 -0.76835) (xy -0.1524 -0.8001) (xy -0.13716 -0.82804)
						(xy -0.11684 -0.85344) (xy -0.09144 -0.87376) (xy -0.0635 -0.889) (xy -0.03175 -0.89916) (xy 0 -0.9017)
						(xy 0.03175 -0.89916) (xy 0.0635 -0.889) (xy 0.09144 -0.87376) (xy 0.11684 -0.85344) (xy 0.13716 -0.82804)
						(xy 0.1524 -0.8001) (xy 0.16256 -0.76835) (xy 0.1651 -0.7366) (xy 0.1651 0.13462) (xy 0.17272 0.14224)
						(xy 0.19812 0.1778) (xy 0.2032 0.18796) (xy 0.20701 0.19685) (xy 0.21209 0.20701) (xy 0.2159 0.21717)
						(xy 0.21844 0.22733) (xy 0.22225 0.23876) (xy 0.22352 0.24892) (xy 0.22606 0.25908) (xy 0.22733 0.27051)
						(xy 0.22733 0.28067) (xy 0.2286 0.2921) (xy 0.22733 0.30353) (xy 0.22733 0.31369) (xy 0.22606 0.32512)
						(xy 0.22352 0.33528) (xy 0.22225 0.34544) (xy 0.21844 0.35687) (xy 0.2159 0.36703) (xy 0.21209 0.37719)
						(xy 0.20701 0.38735) (xy 0.2032 0.39624) (xy 0.19812 0.4064) (xy 0.17272 0.44196) (xy 0.1651 0.44958)
						(xy 0.1651 0.7366) (xy 0.16256 0.76835) (xy 0.1524 0.8001) (xy 0.13716 0.82804) (xy 0.11684 0.85344)
						(xy 0.09144 0.87376) (xy 0.0635 0.889) (xy 0.03175 0.89916)
					)
					(width 0)
					(fill yes)
				)
			)
		)
		(pad "147" smd custom
			(at 14.549882 4.106672 180)
			(size 0.1143 0.1143)
			(layers "F.Cu" "F.Mask" "F.Paste")
			(net "M_A_DQ39")
			(options
				(clearance outline)
				(anchor circle)
			)
			(primitives
				(gr_poly
					(pts
						(xy 0 0.9017) (xy -0.03175 0.89916) (xy -0.0635 0.889) (xy -0.09144 0.87376) (xy -0.11684 0.85344)
						(xy -0.13716 0.82804) (xy -0.1524 0.8001) (xy -0.16256 0.76835) (xy -0.1651 0.7366) (xy -0.1651 0.11938)
						(xy -0.17272 0.11176) (xy -0.19812 0.0762) (xy -0.2032 0.06604) (xy -0.20701 0.05715) (xy -0.21209 0.04699)
						(xy -0.2159 0.03683) (xy -0.21844 0.02667) (xy -0.22225 0.01524) (xy -0.22352 0.00508) (xy -0.22606 -0.00508)
						(xy -0.22733 -0.01651) (xy -0.22733 -0.02667) (xy -0.2286 -0.0381) (xy -0.22733 -0.04953) (xy -0.22733 -0.05969)
						(xy -0.22606 -0.07112) (xy -0.22352 -0.08128) (xy -0.22225 -0.09144) (xy -0.21844 -0.10287) (xy -0.2159 -0.11303)
						(xy -0.21209 -0.12319) (xy -0.20701 -0.13335) (xy -0.2032 -0.14224) (xy -0.19812 -0.1524) (xy -0.17272 -0.18796)
						(xy -0.1651 -0.19558) (xy -0.1651 -0.7366) (xy -0.16256 -0.76835) (xy -0.1524 -0.8001) (xy -0.13716 -0.82804)
						(xy -0.11684 -0.85344) (xy -0.09144 -0.87376) (xy -0.0635 -0.889) (xy -0.03175 -0.89916) (xy 0 -0.9017)
						(xy 0.03175 -0.89916) (xy 0.0635 -0.889) (xy 0.09144 -0.87376) (xy 0.11684 -0.85344) (xy 0.13716 -0.82804)
						(xy 0.1524 -0.8001) (xy 0.16256 -0.76835) (xy 0.1651 -0.7366) (xy 0.1651 -0.19685) (xy 0.17272 -0.18923)
						(xy 0.17907 -0.18034) (xy 0.18669 -0.17145) (xy 0.19177 -0.16256) (xy 0.19812 -0.15367) (xy 0.20828 -0.13335)
						(xy 0.21971 -0.10287) (xy 0.22225 -0.09271) (xy 0.22479 -0.08128) (xy 0.22606 -0.07112) (xy 0.2286 -0.05969)
						(xy 0.2286 -0.01651) (xy 0.22606 -0.00508) (xy 0.22479 0.00508) (xy 0.22225 0.01651) (xy 0.21971 0.02667)
						(xy 0.20828 0.05715) (xy 0.19812 0.07747) (xy 0.19177 0.08636) (xy 0.18669 0.09525) (xy 0.17907 0.10414)
						(xy 0.17272 0.11303) (xy 0.1651 0.12065) (xy 0.1651 0.7366) (xy 0.16256 0.76835) (xy 0.1524 0.8001)
						(xy 0.13716 0.82804) (xy 0.11684 0.85344) (xy 0.09144 0.87376) (xy 0.0635 0.889) (xy 0.03175 0.89916)
					)
					(width 0)
					(fill yes)
				)
			)
		)
		(pad "148" smd custom
			(at 14.85011 -4.106672 180)
			(size 0.1143 0.1143)
			(layers "F.Cu" "F.Mask" "F.Paste")
			(net "M_A_DQ40")
			(options
				(clearance outline)
				(anchor circle)
			)
			(primitives
				(gr_poly
					(pts
						(xy 0 0.9017) (xy -0.03175 0.89916) (xy -0.0635 0.889) (xy -0.09144 0.87376) (xy -0.11684 0.85344)
						(xy -0.13716 0.82804) (xy -0.1524 0.8001) (xy -0.16256 0.76835) (xy -0.1651 0.7366) (xy -0.1651 0.19685)
						(xy -0.17272 0.18923) (xy -0.17907 0.18034) (xy -0.18669 0.17145) (xy -0.19177 0.16256) (xy -0.19812 0.15367)
						(xy -0.20828 0.13335) (xy -0.21971 0.10287) (xy -0.22225 0.09271) (xy -0.22479 0.08128) (xy -0.22606 0.07112)
						(xy -0.2286 0.05969) (xy -0.2286 0.01651) (xy -0.22606 0.00508) (xy -0.22479 -0.00508) (xy -0.22225 -0.01651)
						(xy -0.21971 -0.02667) (xy -0.20828 -0.05715) (xy -0.19812 -0.07747) (xy -0.19177 -0.08636) (xy -0.18669 -0.09525)
						(xy -0.17907 -0.10414) (xy -0.17272 -0.11303) (xy -0.1651 -0.12065) (xy -0.1651 -0.7366) (xy -0.16256 -0.76835)
						(xy -0.1524 -0.8001) (xy -0.13716 -0.82804) (xy -0.11684 -0.85344) (xy -0.09144 -0.87376) (xy -0.0635 -0.889)
						(xy -0.03175 -0.89916) (xy 0 -0.9017) (xy 0.03175 -0.89916) (xy 0.0635 -0.889) (xy 0.09144 -0.87376)
						(xy 0.11684 -0.85344) (xy 0.13716 -0.82804) (xy 0.1524 -0.8001) (xy 0.16256 -0.76835) (xy 0.1651 -0.7366)
						(xy 0.1651 -0.11938) (xy 0.17272 -0.11176) (xy 0.19812 -0.0762) (xy 0.2032 -0.06604) (xy 0.20701 -0.05715)
						(xy 0.21209 -0.04699) (xy 0.2159 -0.03683) (xy 0.21844 -0.02667) (xy 0.22225 -0.01524) (xy 0.22352 -0.00508)
						(xy 0.22606 0.00508) (xy 0.22733 0.01651) (xy 0.22733 0.02667) (xy 0.2286 0.0381) (xy 0.22733 0.04953)
						(xy 0.22733 0.05969) (xy 0.22606 0.07112) (xy 0.22352 0.08128) (xy 0.22225 0.09144) (xy 0.21844 0.10287)
						(xy 0.2159 0.11303) (xy 0.21209 0.12319) (xy 0.20701 0.13335) (xy 0.2032 0.14224) (xy 0.19812 0.1524)
						(xy 0.17272 0.18796) (xy 0.1651 0.19558) (xy 0.1651 0.7366) (xy 0.16256 0.76835) (xy 0.1524 0.8001)
						(xy 0.13716 0.82804) (xy 0.11684 0.85344) (xy 0.09144 0.87376) (xy 0.0635 0.889) (xy 0.03175 0.89916)
					)
					(width 0)
					(fill yes)
				)
			)
		)
		(pad "149" smd custom
			(at 15.150084 4.106672 180)
			(size 0.1143 0.1143)
			(layers "F.Cu" "F.Mask" "F.Paste")
			(net "GND")
			(options
				(clearance outline)
				(anchor circle)
			)
			(primitives
				(gr_poly
					(pts
						(xy 0 0.9017) (xy -0.03175 0.89916) (xy -0.0635 0.889) (xy -0.09144 0.87376) (xy -0.11684 0.85344)
						(xy -0.13716 0.82804) (xy -0.1524 0.8001) (xy -0.16256 0.76835) (xy -0.1651 0.7366) (xy -0.1651 -0.13462)
						(xy -0.17272 -0.14224) (xy -0.19812 -0.1778) (xy -0.2032 -0.18796) (xy -0.20701 -0.19685) (xy -0.21209 -0.20701)
						(xy -0.2159 -0.21717) (xy -0.21844 -0.22733) (xy -0.22225 -0.23876) (xy -0.22352 -0.24892) (xy -0.22606 -0.25908)
						(xy -0.22733 -0.27051) (xy -0.22733 -0.28067) (xy -0.2286 -0.2921) (xy -0.22733 -0.30353) (xy -0.22733 -0.31369)
						(xy -0.22606 -0.32512) (xy -0.22352 -0.33528) (xy -0.22225 -0.34544) (xy -0.21844 -0.35687) (xy -0.2159 -0.36703)
						(xy -0.21209 -0.37719) (xy -0.20701 -0.38735) (xy -0.2032 -0.39624) (xy -0.19812 -0.4064) (xy -0.17272 -0.44196)
						(xy -0.1651 -0.44958) (xy -0.1651 -0.7366) (xy -0.16256 -0.76835) (xy -0.1524 -0.8001) (xy -0.13716 -0.82804)
						(xy -0.11684 -0.85344) (xy -0.09144 -0.87376) (xy -0.0635 -0.889) (xy -0.03175 -0.89916) (xy 0 -0.9017)
						(xy 0.03175 -0.89916) (xy 0.0635 -0.889) (xy 0.09144 -0.87376) (xy 0.11684 -0.85344) (xy 0.13716 -0.82804)
						(xy 0.1524 -0.8001) (xy 0.16256 -0.76835) (xy 0.1651 -0.7366) (xy 0.1651 -0.44958) (xy 0.17272 -0.44196)
						(xy 0.19812 -0.4064) (xy 0.2032 -0.39624) (xy 0.20701 -0.38735) (xy 0.21209 -0.37719) (xy 0.2159 -0.36703)
						(xy 0.21844 -0.35687) (xy 0.22225 -0.34544) (xy 0.22352 -0.33528) (xy 0.22606 -0.32512) (xy 0.22733 -0.31369)
						(xy 0.22733 -0.30353) (xy 0.2286 -0.2921) (xy 0.22733 -0.28067) (xy 0.22733 -0.27051) (xy 0.22606 -0.25908)
						(xy 0.22352 -0.24892) (xy 0.22225 -0.23876) (xy 0.21844 -0.22733) (xy 0.2159 -0.21717) (xy 0.21209 -0.20701)
						(xy 0.20701 -0.19685) (xy 0.2032 -0.18796) (xy 0.19812 -0.1778) (xy 0.17272 -0.14224) (xy 0.1651 -0.13462)
						(xy 0.1651 0.7366) (xy 0.16256 0.76835) (xy 0.1524 0.8001) (xy 0.13716 0.82804) (xy 0.11684 0.85344)
						(xy 0.09144 0.87376) (xy 0.0635 0.889) (xy 0.03175 0.89916)
					)
					(width 0)
					(fill yes)
				)
			)
		)
		(pad "150" smd custom
			(at 15.450058 -4.106672 180)
			(size 0.1143 0.1143)
			(layers "F.Cu" "F.Mask" "F.Paste")
			(net "M_A_DQ41")
			(options
				(clearance outline)
				(anchor circle)
			)
			(primitives
				(gr_poly
					(pts
						(xy 0 0.9017) (xy -0.03175 0.89916) (xy -0.0635 0.889) (xy -0.09144 0.87376) (xy -0.11684 0.85344)
						(xy -0.13716 0.82804) (xy -0.1524 0.8001) (xy -0.16256 0.76835) (xy -0.1651 0.7366) (xy -0.1651 0.44958)
						(xy -0.17272 0.44196) (xy -0.19812 0.4064) (xy -0.2032 0.39624) (xy -0.20701 0.38735) (xy -0.21209 0.37719)
						(xy -0.2159 0.36703) (xy -0.21844 0.35687) (xy -0.22225 0.34544) (xy -0.22352 0.33528) (xy -0.22606 0.32512)
						(xy -0.22733 0.31369) (xy -0.22733 0.30353) (xy -0.2286 0.2921) (xy -0.22733 0.28067) (xy -0.22733 0.27051)
						(xy -0.22606 0.25908) (xy -0.22352 0.24892) (xy -0.22225 0.23876) (xy -0.21844 0.22733) (xy -0.2159 0.21717)
						(xy -0.21209 0.20701) (xy -0.20701 0.19685) (xy -0.2032 0.18796) (xy -0.19812 0.1778) (xy -0.17272 0.14224)
						(xy -0.1651 0.13462) (xy -0.1651 -0.7366) (xy -0.16256 -0.76835) (xy -0.1524 -0.8001) (xy -0.13716 -0.82804)
						(xy -0.11684 -0.85344) (xy -0.09144 -0.87376) (xy -0.0635 -0.889) (xy -0.03175 -0.89916) (xy 0 -0.9017)
						(xy 0.03175 -0.89916) (xy 0.0635 -0.889) (xy 0.09144 -0.87376) (xy 0.11684 -0.85344) (xy 0.13716 -0.82804)
						(xy 0.1524 -0.8001) (xy 0.16256 -0.76835) (xy 0.1651 -0.7366) (xy 0.1651 0.13462) (xy 0.17272 0.14224)
						(xy 0.19812 0.1778) (xy 0.2032 0.18796) (xy 0.20701 0.19685) (xy 0.21209 0.20701) (xy 0.2159 0.21717)
						(xy 0.21844 0.22733) (xy 0.22225 0.23876) (xy 0.22352 0.24892) (xy 0.22606 0.25908) (xy 0.22733 0.27051)
						(xy 0.22733 0.28067) (xy 0.2286 0.2921) (xy 0.22733 0.30353) (xy 0.22733 0.31369) (xy 0.22606 0.32512)
						(xy 0.22352 0.33528) (xy 0.22225 0.34544) (xy 0.21844 0.35687) (xy 0.2159 0.36703) (xy 0.21209 0.37719)
						(xy 0.20701 0.38735) (xy 0.2032 0.39624) (xy 0.19812 0.4064) (xy 0.17272 0.44196) (xy 0.1651 0.44958)
						(xy 0.1651 0.7366) (xy 0.16256 0.76835) (xy 0.1524 0.8001) (xy 0.13716 0.82804) (xy 0.11684 0.85344)
						(xy 0.09144 0.87376) (xy 0.0635 0.889) (xy 0.03175 0.89916)
					)
					(width 0)
					(fill yes)
				)
			)
		)
		(pad "151" smd custom
			(at 15.750032 4.106672 180)
			(size 0.1143 0.1143)
			(layers "F.Cu" "F.Mask" "F.Paste")
			(net "M_A_DQ44")
			(options
				(clearance outline)
				(anchor circle)
			)
			(primitives
				(gr_poly
					(pts
						(xy 0 0.9017) (xy -0.03175 0.89916) (xy -0.0635 0.889) (xy -0.09144 0.87376) (xy -0.11684 0.85344)
						(xy -0.13716 0.82804) (xy -0.1524 0.8001) (xy -0.16256 0.76835) (xy -0.1651 0.7366) (xy -0.1651 0.11938)
						(xy -0.17272 0.11176) (xy -0.19812 0.0762) (xy -0.2032 0.06604) (xy -0.20701 0.05715) (xy -0.21209 0.04699)
						(xy -0.2159 0.03683) (xy -0.21844 0.02667) (xy -0.22225 0.01524) (xy -0.22352 0.00508) (xy -0.22606 -0.00508)
						(xy -0.22733 -0.01651) (xy -0.22733 -0.02667) (xy -0.2286 -0.0381) (xy -0.22733 -0.04953) (xy -0.22733 -0.05969)
						(xy -0.22606 -0.07112) (xy -0.22352 -0.08128) (xy -0.22225 -0.09144) (xy -0.21844 -0.10287) (xy -0.2159 -0.11303)
						(xy -0.21209 -0.12319) (xy -0.20701 -0.13335) (xy -0.2032 -0.14224) (xy -0.19812 -0.1524) (xy -0.17272 -0.18796)
						(xy -0.1651 -0.19558) (xy -0.1651 -0.7366) (xy -0.16256 -0.76835) (xy -0.1524 -0.8001) (xy -0.13716 -0.82804)
						(xy -0.11684 -0.85344) (xy -0.09144 -0.87376) (xy -0.0635 -0.889) (xy -0.03175 -0.89916) (xy 0 -0.9017)
						(xy 0.03175 -0.89916) (xy 0.0635 -0.889) (xy 0.09144 -0.87376) (xy 0.11684 -0.85344) (xy 0.13716 -0.82804)
						(xy 0.1524 -0.8001) (xy 0.16256 -0.76835) (xy 0.1651 -0.7366) (xy 0.1651 -0.19685) (xy 0.17272 -0.18923)
						(xy 0.17907 -0.18034) (xy 0.18669 -0.17145) (xy 0.19177 -0.16256) (xy 0.19812 -0.15367) (xy 0.20828 -0.13335)
						(xy 0.21971 -0.10287) (xy 0.22225 -0.09271) (xy 0.22479 -0.08128) (xy 0.22606 -0.07112) (xy 0.2286 -0.05969)
						(xy 0.2286 -0.01651) (xy 0.22606 -0.00508) (xy 0.22479 0.00508) (xy 0.22225 0.01651) (xy 0.21971 0.02667)
						(xy 0.20828 0.05715) (xy 0.19812 0.07747) (xy 0.19177 0.08636) (xy 0.18669 0.09525) (xy 0.17907 0.10414)
						(xy 0.17272 0.11303) (xy 0.1651 0.12065) (xy 0.1651 0.7366) (xy 0.16256 0.76835) (xy 0.1524 0.8001)
						(xy 0.13716 0.82804) (xy 0.11684 0.85344) (xy 0.09144 0.87376) (xy 0.0635 0.889) (xy 0.03175 0.89916)
					)
					(width 0)
					(fill yes)
				)
			)
		)
		(pad "152" smd custom
			(at 16.050006 -4.106672 180)
			(size 0.1143 0.1143)
			(layers "F.Cu" "F.Mask" "F.Paste")
			(net "GND")
			(options
				(clearance outline)
				(anchor circle)
			)
			(primitives
				(gr_poly
					(pts
						(xy 0 0.9017) (xy -0.03175 0.89916) (xy -0.0635 0.889) (xy -0.09144 0.87376) (xy -0.11684 0.85344)
						(xy -0.13716 0.82804) (xy -0.1524 0.8001) (xy -0.16256 0.76835) (xy -0.1651 0.7366) (xy -0.1651 0.19685)
						(xy -0.17272 0.18923) (xy -0.17907 0.18034) (xy -0.18669 0.17145) (xy -0.19177 0.16256) (xy -0.19812 0.15367)
						(xy -0.20828 0.13335) (xy -0.21971 0.10287) (xy -0.22225 0.09271) (xy -0.22479 0.08128) (xy -0.22606 0.07112)
						(xy -0.2286 0.05969) (xy -0.2286 0.01651) (xy -0.22606 0.00508) (xy -0.22479 -0.00508) (xy -0.22225 -0.01651)
						(xy -0.21971 -0.02667) (xy -0.20828 -0.05715) (xy -0.19812 -0.07747) (xy -0.19177 -0.08636) (xy -0.18669 -0.09525)
						(xy -0.17907 -0.10414) (xy -0.17272 -0.11303) (xy -0.1651 -0.12065) (xy -0.1651 -0.7366) (xy -0.16256 -0.76835)
						(xy -0.1524 -0.8001) (xy -0.13716 -0.82804) (xy -0.11684 -0.85344) (xy -0.09144 -0.87376) (xy -0.0635 -0.889)
						(xy -0.03175 -0.89916) (xy 0 -0.9017) (xy 0.03175 -0.89916) (xy 0.0635 -0.889) (xy 0.09144 -0.87376)
						(xy 0.11684 -0.85344) (xy 0.13716 -0.82804) (xy 0.1524 -0.8001) (xy 0.16256 -0.76835) (xy 0.1651 -0.7366)
						(xy 0.1651 -0.11938) (xy 0.17272 -0.11176) (xy 0.19812 -0.0762) (xy 0.2032 -0.06604) (xy 0.20701 -0.05715)
						(xy 0.21209 -0.04699) (xy 0.2159 -0.03683) (xy 0.21844 -0.02667) (xy 0.22225 -0.01524) (xy 0.22352 -0.00508)
						(xy 0.22606 0.00508) (xy 0.22733 0.01651) (xy 0.22733 0.02667) (xy 0.2286 0.0381) (xy 0.22733 0.04953)
						(xy 0.22733 0.05969) (xy 0.22606 0.07112) (xy 0.22352 0.08128) (xy 0.22225 0.09144) (xy 0.21844 0.10287)
						(xy 0.2159 0.11303) (xy 0.21209 0.12319) (xy 0.20701 0.13335) (xy 0.2032 0.14224) (xy 0.19812 0.1524)
						(xy 0.17272 0.18796) (xy 0.1651 0.19558) (xy 0.1651 0.7366) (xy 0.16256 0.76835) (xy 0.1524 0.8001)
						(xy 0.13716 0.82804) (xy 0.11684 0.85344) (xy 0.09144 0.87376) (xy 0.0635 0.889) (xy 0.03175 0.89916)
					)
					(width 0)
					(fill yes)
				)
			)
		)
		(pad "153" smd custom
			(at 16.34998 4.106672 180)
			(size 0.1143 0.1143)
			(layers "F.Cu" "F.Mask" "F.Paste")
			(net "M_A_DQ45")
			(options
				(clearance outline)
				(anchor circle)
			)
			(primitives
				(gr_poly
					(pts
						(xy 0 0.9017) (xy -0.03175 0.89916) (xy -0.0635 0.889) (xy -0.09144 0.87376) (xy -0.11684 0.85344)
						(xy -0.13716 0.82804) (xy -0.1524 0.8001) (xy -0.16256 0.76835) (xy -0.1651 0.7366) (xy -0.1651 -0.13462)
						(xy -0.17272 -0.14224) (xy -0.19812 -0.1778) (xy -0.2032 -0.18796) (xy -0.20701 -0.19685) (xy -0.21209 -0.20701)
						(xy -0.2159 -0.21717) (xy -0.21844 -0.22733) (xy -0.22225 -0.23876) (xy -0.22352 -0.24892) (xy -0.22606 -0.25908)
						(xy -0.22733 -0.27051) (xy -0.22733 -0.28067) (xy -0.2286 -0.2921) (xy -0.22733 -0.30353) (xy -0.22733 -0.31369)
						(xy -0.22606 -0.32512) (xy -0.22352 -0.33528) (xy -0.22225 -0.34544) (xy -0.21844 -0.35687) (xy -0.2159 -0.36703)
						(xy -0.21209 -0.37719) (xy -0.20701 -0.38735) (xy -0.2032 -0.39624) (xy -0.19812 -0.4064) (xy -0.17272 -0.44196)
						(xy -0.1651 -0.44958) (xy -0.1651 -0.7366) (xy -0.16256 -0.76835) (xy -0.1524 -0.8001) (xy -0.13716 -0.82804)
						(xy -0.11684 -0.85344) (xy -0.09144 -0.87376) (xy -0.0635 -0.889) (xy -0.03175 -0.89916) (xy 0 -0.9017)
						(xy 0.03175 -0.89916) (xy 0.0635 -0.889) (xy 0.09144 -0.87376) (xy 0.11684 -0.85344) (xy 0.13716 -0.82804)
						(xy 0.1524 -0.8001) (xy 0.16256 -0.76835) (xy 0.1651 -0.7366) (xy 0.1651 -0.44958) (xy 0.17272 -0.44196)
						(xy 0.19812 -0.4064) (xy 0.2032 -0.39624) (xy 0.20701 -0.38735) (xy 0.21209 -0.37719) (xy 0.2159 -0.36703)
						(xy 0.21844 -0.35687) (xy 0.22225 -0.34544) (xy 0.22352 -0.33528) (xy 0.22606 -0.32512) (xy 0.22733 -0.31369)
						(xy 0.22733 -0.30353) (xy 0.2286 -0.2921) (xy 0.22733 -0.28067) (xy 0.22733 -0.27051) (xy 0.22606 -0.25908)
						(xy 0.22352 -0.24892) (xy 0.22225 -0.23876) (xy 0.21844 -0.22733) (xy 0.2159 -0.21717) (xy 0.21209 -0.20701)
						(xy 0.20701 -0.19685) (xy 0.2032 -0.18796) (xy 0.19812 -0.1778) (xy 0.17272 -0.14224) (xy 0.1651 -0.13462)
						(xy 0.1651 0.7366) (xy 0.16256 0.76835) (xy 0.1524 0.8001) (xy 0.13716 0.82804) (xy 0.11684 0.85344)
						(xy 0.09144 0.87376) (xy 0.0635 0.889) (xy 0.03175 0.89916)
					)
					(width 0)
					(fill yes)
				)
			)
		)
		(pad "154" smd custom
			(at 16.649954 -4.106672 180)
			(size 0.1143 0.1143)
			(layers "F.Cu" "F.Mask" "F.Paste")
			(net "M_A_DQS_DN5")
			(options
				(clearance outline)
				(anchor circle)
			)
			(primitives
				(gr_poly
					(pts
						(xy 0 0.9017) (xy -0.03175 0.89916) (xy -0.0635 0.889) (xy -0.09144 0.87376) (xy -0.11684 0.85344)
						(xy -0.13716 0.82804) (xy -0.1524 0.8001) (xy -0.16256 0.76835) (xy -0.1651 0.7366) (xy -0.1651 0.44958)
						(xy -0.17272 0.44196) (xy -0.19812 0.4064) (xy -0.2032 0.39624) (xy -0.20701 0.38735) (xy -0.21209 0.37719)
						(xy -0.2159 0.36703) (xy -0.21844 0.35687) (xy -0.22225 0.34544) (xy -0.22352 0.33528) (xy -0.22606 0.32512)
						(xy -0.22733 0.31369) (xy -0.22733 0.30353) (xy -0.2286 0.2921) (xy -0.22733 0.28067) (xy -0.22733 0.27051)
						(xy -0.22606 0.25908) (xy -0.22352 0.24892) (xy -0.22225 0.23876) (xy -0.21844 0.22733) (xy -0.2159 0.21717)
						(xy -0.21209 0.20701) (xy -0.20701 0.19685) (xy -0.2032 0.18796) (xy -0.19812 0.1778) (xy -0.17272 0.14224)
						(xy -0.1651 0.13462) (xy -0.1651 -0.7366) (xy -0.16256 -0.76835) (xy -0.1524 -0.8001) (xy -0.13716 -0.82804)
						(xy -0.11684 -0.85344) (xy -0.09144 -0.87376) (xy -0.0635 -0.889) (xy -0.03175 -0.89916) (xy 0 -0.9017)
						(xy 0.03175 -0.89916) (xy 0.0635 -0.889) (xy 0.09144 -0.87376) (xy 0.11684 -0.85344) (xy 0.13716 -0.82804)
						(xy 0.1524 -0.8001) (xy 0.16256 -0.76835) (xy 0.1651 -0.7366) (xy 0.1651 0.13462) (xy 0.17272 0.14224)
						(xy 0.19812 0.1778) (xy 0.2032 0.18796) (xy 0.20701 0.19685) (xy 0.21209 0.20701) (xy 0.2159 0.21717)
						(xy 0.21844 0.22733) (xy 0.22225 0.23876) (xy 0.22352 0.24892) (xy 0.22606 0.25908) (xy 0.22733 0.27051)
						(xy 0.22733 0.28067) (xy 0.2286 0.2921) (xy 0.22733 0.30353) (xy 0.22733 0.31369) (xy 0.22606 0.32512)
						(xy 0.22352 0.33528) (xy 0.22225 0.34544) (xy 0.21844 0.35687) (xy 0.2159 0.36703) (xy 0.21209 0.37719)
						(xy 0.20701 0.38735) (xy 0.2032 0.39624) (xy 0.19812 0.4064) (xy 0.17272 0.44196) (xy 0.1651 0.44958)
						(xy 0.1651 0.7366) (xy 0.16256 0.76835) (xy 0.1524 0.8001) (xy 0.13716 0.82804) (xy 0.11684 0.85344)
						(xy 0.09144 0.87376) (xy 0.0635 0.889) (xy 0.03175 0.89916)
					)
					(width 0)
					(fill yes)
				)
			)
		)
		(pad "155" smd custom
			(at 16.949928 4.106672 180)
			(size 0.1143 0.1143)
			(layers "F.Cu" "F.Mask" "F.Paste")
			(net "GND")
			(options
				(clearance outline)
				(anchor circle)
			)
			(primitives
				(gr_poly
					(pts
						(xy 0 0.9017) (xy -0.03175 0.89916) (xy -0.0635 0.889) (xy -0.09144 0.87376) (xy -0.11684 0.85344)
						(xy -0.13716 0.82804) (xy -0.1524 0.8001) (xy -0.16256 0.76835) (xy -0.1651 0.7366) (xy -0.1651 0.11938)
						(xy -0.17272 0.11176) (xy -0.19812 0.0762) (xy -0.2032 0.06604) (xy -0.20701 0.05715) (xy -0.21209 0.04699)
						(xy -0.2159 0.03683) (xy -0.21844 0.02667) (xy -0.22225 0.01524) (xy -0.22352 0.00508) (xy -0.22606 -0.00508)
						(xy -0.22733 -0.01651) (xy -0.22733 -0.02667) (xy -0.2286 -0.0381) (xy -0.22733 -0.04953) (xy -0.22733 -0.05969)
						(xy -0.22606 -0.07112) (xy -0.22352 -0.08128) (xy -0.22225 -0.09144) (xy -0.21844 -0.10287) (xy -0.2159 -0.11303)
						(xy -0.21209 -0.12319) (xy -0.20701 -0.13335) (xy -0.2032 -0.14224) (xy -0.19812 -0.1524) (xy -0.17272 -0.18796)
						(xy -0.1651 -0.19558) (xy -0.1651 -0.7366) (xy -0.16256 -0.76835) (xy -0.1524 -0.8001) (xy -0.13716 -0.82804)
						(xy -0.11684 -0.85344) (xy -0.09144 -0.87376) (xy -0.0635 -0.889) (xy -0.03175 -0.89916) (xy 0 -0.9017)
						(xy 0.03175 -0.89916) (xy 0.0635 -0.889) (xy 0.09144 -0.87376) (xy 0.11684 -0.85344) (xy 0.13716 -0.82804)
						(xy 0.1524 -0.8001) (xy 0.16256 -0.76835) (xy 0.1651 -0.7366) (xy 0.1651 -0.19685) (xy 0.17272 -0.18923)
						(xy 0.17907 -0.18034) (xy 0.18669 -0.17145) (xy 0.19177 -0.16256) (xy 0.19812 -0.15367) (xy 0.20828 -0.13335)
						(xy 0.21971 -0.10287) (xy 0.22225 -0.09271) (xy 0.22479 -0.08128) (xy 0.22606 -0.07112) (xy 0.2286 -0.05969)
						(xy 0.2286 -0.01651) (xy 0.22606 -0.00508) (xy 0.22479 0.00508) (xy 0.22225 0.01651) (xy 0.21971 0.02667)
						(xy 0.20828 0.05715) (xy 0.19812 0.07747) (xy 0.19177 0.08636) (xy 0.18669 0.09525) (xy 0.17907 0.10414)
						(xy 0.17272 0.11303) (xy 0.1651 0.12065) (xy 0.1651 0.7366) (xy 0.16256 0.76835) (xy 0.1524 0.8001)
						(xy 0.13716 0.82804) (xy 0.11684 0.85344) (xy 0.09144 0.87376) (xy 0.0635 0.889) (xy 0.03175 0.89916)
					)
					(width 0)
					(fill yes)
				)
			)
		)
		(pad "156" smd custom
			(at 17.249902 -4.106672 180)
			(size 0.1143 0.1143)
			(layers "F.Cu" "F.Mask" "F.Paste")
			(net "M_A_DQS_DP5")
			(options
				(clearance outline)
				(anchor circle)
			)
			(primitives
				(gr_poly
					(pts
						(xy 0 0.9017) (xy -0.03175 0.89916) (xy -0.0635 0.889) (xy -0.09144 0.87376) (xy -0.11684 0.85344)
						(xy -0.13716 0.82804) (xy -0.1524 0.8001) (xy -0.16256 0.76835) (xy -0.1651 0.7366) (xy -0.1651 0.19685)
						(xy -0.17272 0.18923) (xy -0.17907 0.18034) (xy -0.18669 0.17145) (xy -0.19177 0.16256) (xy -0.19812 0.15367)
						(xy -0.20828 0.13335) (xy -0.21971 0.10287) (xy -0.22225 0.09271) (xy -0.22479 0.08128) (xy -0.22606 0.07112)
						(xy -0.2286 0.05969) (xy -0.2286 0.01651) (xy -0.22606 0.00508) (xy -0.22479 -0.00508) (xy -0.22225 -0.01651)
						(xy -0.21971 -0.02667) (xy -0.20828 -0.05715) (xy -0.19812 -0.07747) (xy -0.19177 -0.08636) (xy -0.18669 -0.09525)
						(xy -0.17907 -0.10414) (xy -0.17272 -0.11303) (xy -0.1651 -0.12065) (xy -0.1651 -0.7366) (xy -0.16256 -0.76835)
						(xy -0.1524 -0.8001) (xy -0.13716 -0.82804) (xy -0.11684 -0.85344) (xy -0.09144 -0.87376) (xy -0.0635 -0.889)
						(xy -0.03175 -0.89916) (xy 0 -0.9017) (xy 0.03175 -0.89916) (xy 0.0635 -0.889) (xy 0.09144 -0.87376)
						(xy 0.11684 -0.85344) (xy 0.13716 -0.82804) (xy 0.1524 -0.8001) (xy 0.16256 -0.76835) (xy 0.1651 -0.7366)
						(xy 0.1651 -0.11938) (xy 0.17272 -0.11176) (xy 0.19812 -0.0762) (xy 0.2032 -0.06604) (xy 0.20701 -0.05715)
						(xy 0.21209 -0.04699) (xy 0.2159 -0.03683) (xy 0.21844 -0.02667) (xy 0.22225 -0.01524) (xy 0.22352 -0.00508)
						(xy 0.22606 0.00508) (xy 0.22733 0.01651) (xy 0.22733 0.02667) (xy 0.2286 0.0381) (xy 0.22733 0.04953)
						(xy 0.22733 0.05969) (xy 0.22606 0.07112) (xy 0.22352 0.08128) (xy 0.22225 0.09144) (xy 0.21844 0.10287)
						(xy 0.2159 0.11303) (xy 0.21209 0.12319) (xy 0.20701 0.13335) (xy 0.2032 0.14224) (xy 0.19812 0.1524)
						(xy 0.17272 0.18796) (xy 0.1651 0.19558) (xy 0.1651 0.7366) (xy 0.16256 0.76835) (xy 0.1524 0.8001)
						(xy 0.13716 0.82804) (xy 0.11684 0.85344) (xy 0.09144 0.87376) (xy 0.0635 0.889) (xy 0.03175 0.89916)
					)
					(width 0)
					(fill yes)
				)
			)
		)
		(pad "157" smd custom
			(at 17.549876 4.106672 180)
			(size 0.1143 0.1143)
			(layers "F.Cu" "F.Mask" "F.Paste")
			(net "GND")
			(options
				(clearance outline)
				(anchor circle)
			)
			(primitives
				(gr_poly
					(pts
						(xy 0 0.9017) (xy -0.03175 0.89916) (xy -0.0635 0.889) (xy -0.09144 0.87376) (xy -0.11684 0.85344)
						(xy -0.13716 0.82804) (xy -0.1524 0.8001) (xy -0.16256 0.76835) (xy -0.1651 0.7366) (xy -0.1651 -0.13462)
						(xy -0.17272 -0.14224) (xy -0.19812 -0.1778) (xy -0.2032 -0.18796) (xy -0.20701 -0.19685) (xy -0.21209 -0.20701)
						(xy -0.2159 -0.21717) (xy -0.21844 -0.22733) (xy -0.22225 -0.23876) (xy -0.22352 -0.24892) (xy -0.22606 -0.25908)
						(xy -0.22733 -0.27051) (xy -0.22733 -0.28067) (xy -0.2286 -0.2921) (xy -0.22733 -0.30353) (xy -0.22733 -0.31369)
						(xy -0.22606 -0.32512) (xy -0.22352 -0.33528) (xy -0.22225 -0.34544) (xy -0.21844 -0.35687) (xy -0.2159 -0.36703)
						(xy -0.21209 -0.37719) (xy -0.20701 -0.38735) (xy -0.2032 -0.39624) (xy -0.19812 -0.4064) (xy -0.17272 -0.44196)
						(xy -0.1651 -0.44958) (xy -0.1651 -0.7366) (xy -0.16256 -0.76835) (xy -0.1524 -0.8001) (xy -0.13716 -0.82804)
						(xy -0.11684 -0.85344) (xy -0.09144 -0.87376) (xy -0.0635 -0.889) (xy -0.03175 -0.89916) (xy 0 -0.9017)
						(xy 0.03175 -0.89916) (xy 0.0635 -0.889) (xy 0.09144 -0.87376) (xy 0.11684 -0.85344) (xy 0.13716 -0.82804)
						(xy 0.1524 -0.8001) (xy 0.16256 -0.76835) (xy 0.1651 -0.7366) (xy 0.1651 -0.44958) (xy 0.17272 -0.44196)
						(xy 0.19812 -0.4064) (xy 0.2032 -0.39624) (xy 0.20701 -0.38735) (xy 0.21209 -0.37719) (xy 0.2159 -0.36703)
						(xy 0.21844 -0.35687) (xy 0.22225 -0.34544) (xy 0.22352 -0.33528) (xy 0.22606 -0.32512) (xy 0.22733 -0.31369)
						(xy 0.22733 -0.30353) (xy 0.2286 -0.2921) (xy 0.22733 -0.28067) (xy 0.22733 -0.27051) (xy 0.22606 -0.25908)
						(xy 0.22352 -0.24892) (xy 0.22225 -0.23876) (xy 0.21844 -0.22733) (xy 0.2159 -0.21717) (xy 0.21209 -0.20701)
						(xy 0.20701 -0.19685) (xy 0.2032 -0.18796) (xy 0.19812 -0.1778) (xy 0.17272 -0.14224) (xy 0.1651 -0.13462)
						(xy 0.1651 0.7366) (xy 0.16256 0.76835) (xy 0.1524 0.8001) (xy 0.13716 0.82804) (xy 0.11684 0.85344)
						(xy 0.09144 0.87376) (xy 0.0635 0.889) (xy 0.03175 0.89916)
					)
					(width 0)
					(fill yes)
				)
			)
		)
		(pad "158" smd custom
			(at 17.850104 -4.106672 180)
			(size 0.1143 0.1143)
			(layers "F.Cu" "F.Mask" "F.Paste")
			(net "GND")
			(options
				(clearance outline)
				(anchor circle)
			)
			(primitives
				(gr_poly
					(pts
						(xy 0 0.9017) (xy -0.03175 0.89916) (xy -0.0635 0.889) (xy -0.09144 0.87376) (xy -0.11684 0.85344)
						(xy -0.13716 0.82804) (xy -0.1524 0.8001) (xy -0.16256 0.76835) (xy -0.1651 0.7366) (xy -0.1651 0.44958)
						(xy -0.17272 0.44196) (xy -0.19812 0.4064) (xy -0.2032 0.39624) (xy -0.20701 0.38735) (xy -0.21209 0.37719)
						(xy -0.2159 0.36703) (xy -0.21844 0.35687) (xy -0.22225 0.34544) (xy -0.22352 0.33528) (xy -0.22606 0.32512)
						(xy -0.22733 0.31369) (xy -0.22733 0.30353) (xy -0.2286 0.2921) (xy -0.22733 0.28067) (xy -0.22733 0.27051)
						(xy -0.22606 0.25908) (xy -0.22352 0.24892) (xy -0.22225 0.23876) (xy -0.21844 0.22733) (xy -0.2159 0.21717)
						(xy -0.21209 0.20701) (xy -0.20701 0.19685) (xy -0.2032 0.18796) (xy -0.19812 0.1778) (xy -0.17272 0.14224)
						(xy -0.1651 0.13462) (xy -0.1651 -0.7366) (xy -0.16256 -0.76835) (xy -0.1524 -0.8001) (xy -0.13716 -0.82804)
						(xy -0.11684 -0.85344) (xy -0.09144 -0.87376) (xy -0.0635 -0.889) (xy -0.03175 -0.89916) (xy 0 -0.9017)
						(xy 0.03175 -0.89916) (xy 0.0635 -0.889) (xy 0.09144 -0.87376) (xy 0.11684 -0.85344) (xy 0.13716 -0.82804)
						(xy 0.1524 -0.8001) (xy 0.16256 -0.76835) (xy 0.1651 -0.7366) (xy 0.1651 0.13462) (xy 0.17272 0.14224)
						(xy 0.19812 0.1778) (xy 0.2032 0.18796) (xy 0.20701 0.19685) (xy 0.21209 0.20701) (xy 0.2159 0.21717)
						(xy 0.21844 0.22733) (xy 0.22225 0.23876) (xy 0.22352 0.24892) (xy 0.22606 0.25908) (xy 0.22733 0.27051)
						(xy 0.22733 0.28067) (xy 0.2286 0.2921) (xy 0.22733 0.30353) (xy 0.22733 0.31369) (xy 0.22606 0.32512)
						(xy 0.22352 0.33528) (xy 0.22225 0.34544) (xy 0.21844 0.35687) (xy 0.2159 0.36703) (xy 0.21209 0.37719)
						(xy 0.20701 0.38735) (xy 0.2032 0.39624) (xy 0.19812 0.4064) (xy 0.17272 0.44196) (xy 0.1651 0.44958)
						(xy 0.1651 0.7366) (xy 0.16256 0.76835) (xy 0.1524 0.8001) (xy 0.13716 0.82804) (xy 0.11684 0.85344)
						(xy 0.09144 0.87376) (xy 0.0635 0.889) (xy 0.03175 0.89916)
					)
					(width 0)
					(fill yes)
				)
			)
		)
		(pad "159" smd custom
			(at 18.150078 4.106672 180)
			(size 0.1143 0.1143)
			(layers "F.Cu" "F.Mask" "F.Paste")
			(net "M_A_DQ46")
			(options
				(clearance outline)
				(anchor circle)
			)
			(primitives
				(gr_poly
					(pts
						(xy 0 0.9017) (xy -0.03175 0.89916) (xy -0.0635 0.889) (xy -0.09144 0.87376) (xy -0.11684 0.85344)
						(xy -0.13716 0.82804) (xy -0.1524 0.8001) (xy -0.16256 0.76835) (xy -0.1651 0.7366) (xy -0.1651 0.11938)
						(xy -0.17272 0.11176) (xy -0.19812 0.0762) (xy -0.2032 0.06604) (xy -0.20701 0.05715) (xy -0.21209 0.04699)
						(xy -0.2159 0.03683) (xy -0.21844 0.02667) (xy -0.22225 0.01524) (xy -0.22352 0.00508) (xy -0.22606 -0.00508)
						(xy -0.22733 -0.01651) (xy -0.22733 -0.02667) (xy -0.2286 -0.0381) (xy -0.22733 -0.04953) (xy -0.22733 -0.05969)
						(xy -0.22606 -0.07112) (xy -0.22352 -0.08128) (xy -0.22225 -0.09144) (xy -0.21844 -0.10287) (xy -0.2159 -0.11303)
						(xy -0.21209 -0.12319) (xy -0.20701 -0.13335) (xy -0.2032 -0.14224) (xy -0.19812 -0.1524) (xy -0.17272 -0.18796)
						(xy -0.1651 -0.19558) (xy -0.1651 -0.7366) (xy -0.16256 -0.76835) (xy -0.1524 -0.8001) (xy -0.13716 -0.82804)
						(xy -0.11684 -0.85344) (xy -0.09144 -0.87376) (xy -0.0635 -0.889) (xy -0.03175 -0.89916) (xy 0 -0.9017)
						(xy 0.03175 -0.89916) (xy 0.0635 -0.889) (xy 0.09144 -0.87376) (xy 0.11684 -0.85344) (xy 0.13716 -0.82804)
						(xy 0.1524 -0.8001) (xy 0.16256 -0.76835) (xy 0.1651 -0.7366) (xy 0.1651 -0.19685) (xy 0.17272 -0.18923)
						(xy 0.17907 -0.18034) (xy 0.18669 -0.17145) (xy 0.19177 -0.16256) (xy 0.19812 -0.15367) (xy 0.20828 -0.13335)
						(xy 0.21971 -0.10287) (xy 0.22225 -0.09271) (xy 0.22479 -0.08128) (xy 0.22606 -0.07112) (xy 0.2286 -0.05969)
						(xy 0.2286 -0.01651) (xy 0.22606 -0.00508) (xy 0.22479 0.00508) (xy 0.22225 0.01651) (xy 0.21971 0.02667)
						(xy 0.20828 0.05715) (xy 0.19812 0.07747) (xy 0.19177 0.08636) (xy 0.18669 0.09525) (xy 0.17907 0.10414)
						(xy 0.17272 0.11303) (xy 0.1651 0.12065) (xy 0.1651 0.7366) (xy 0.16256 0.76835) (xy 0.1524 0.8001)
						(xy 0.13716 0.82804) (xy 0.11684 0.85344) (xy 0.09144 0.87376) (xy 0.0635 0.889) (xy 0.03175 0.89916)
					)
					(width 0)
					(fill yes)
				)
			)
		)
		(pad "160" smd custom
			(at 18.450052 -4.106672 180)
			(size 0.1143 0.1143)
			(layers "F.Cu" "F.Mask" "F.Paste")
			(net "M_A_DQ42")
			(options
				(clearance outline)
				(anchor circle)
			)
			(primitives
				(gr_poly
					(pts
						(xy 0 0.9017) (xy -0.03175 0.89916) (xy -0.0635 0.889) (xy -0.09144 0.87376) (xy -0.11684 0.85344)
						(xy -0.13716 0.82804) (xy -0.1524 0.8001) (xy -0.16256 0.76835) (xy -0.1651 0.7366) (xy -0.1651 0.19685)
						(xy -0.17272 0.18923) (xy -0.17907 0.18034) (xy -0.18669 0.17145) (xy -0.19177 0.16256) (xy -0.19812 0.15367)
						(xy -0.20828 0.13335) (xy -0.21971 0.10287) (xy -0.22225 0.09271) (xy -0.22479 0.08128) (xy -0.22606 0.07112)
						(xy -0.2286 0.05969) (xy -0.2286 0.01651) (xy -0.22606 0.00508) (xy -0.22479 -0.00508) (xy -0.22225 -0.01651)
						(xy -0.21971 -0.02667) (xy -0.20828 -0.05715) (xy -0.19812 -0.07747) (xy -0.19177 -0.08636) (xy -0.18669 -0.09525)
						(xy -0.17907 -0.10414) (xy -0.17272 -0.11303) (xy -0.1651 -0.12065) (xy -0.1651 -0.7366) (xy -0.16256 -0.76835)
						(xy -0.1524 -0.8001) (xy -0.13716 -0.82804) (xy -0.11684 -0.85344) (xy -0.09144 -0.87376) (xy -0.0635 -0.889)
						(xy -0.03175 -0.89916) (xy 0 -0.9017) (xy 0.03175 -0.89916) (xy 0.0635 -0.889) (xy 0.09144 -0.87376)
						(xy 0.11684 -0.85344) (xy 0.13716 -0.82804) (xy 0.1524 -0.8001) (xy 0.16256 -0.76835) (xy 0.1651 -0.7366)
						(xy 0.1651 -0.11938) (xy 0.17272 -0.11176) (xy 0.19812 -0.0762) (xy 0.2032 -0.06604) (xy 0.20701 -0.05715)
						(xy 0.21209 -0.04699) (xy 0.2159 -0.03683) (xy 0.21844 -0.02667) (xy 0.22225 -0.01524) (xy 0.22352 -0.00508)
						(xy 0.22606 0.00508) (xy 0.22733 0.01651) (xy 0.22733 0.02667) (xy 0.2286 0.0381) (xy 0.22733 0.04953)
						(xy 0.22733 0.05969) (xy 0.22606 0.07112) (xy 0.22352 0.08128) (xy 0.22225 0.09144) (xy 0.21844 0.10287)
						(xy 0.2159 0.11303) (xy 0.21209 0.12319) (xy 0.20701 0.13335) (xy 0.2032 0.14224) (xy 0.19812 0.1524)
						(xy 0.17272 0.18796) (xy 0.1651 0.19558) (xy 0.1651 0.7366) (xy 0.16256 0.76835) (xy 0.1524 0.8001)
						(xy 0.13716 0.82804) (xy 0.11684 0.85344) (xy 0.09144 0.87376) (xy 0.0635 0.889) (xy 0.03175 0.89916)
					)
					(width 0)
					(fill yes)
				)
			)
		)
		(pad "161" smd custom
			(at 18.750026 4.106672 180)
			(size 0.1143 0.1143)
			(layers "F.Cu" "F.Mask" "F.Paste")
			(net "M_A_DQ47")
			(options
				(clearance outline)
				(anchor circle)
			)
			(primitives
				(gr_poly
					(pts
						(xy 0 0.9017) (xy -0.03175 0.89916) (xy -0.0635 0.889) (xy -0.09144 0.87376) (xy -0.11684 0.85344)
						(xy -0.13716 0.82804) (xy -0.1524 0.8001) (xy -0.16256 0.76835) (xy -0.1651 0.7366) (xy -0.1651 -0.13462)
						(xy -0.17272 -0.14224) (xy -0.19812 -0.1778) (xy -0.2032 -0.18796) (xy -0.20701 -0.19685) (xy -0.21209 -0.20701)
						(xy -0.2159 -0.21717) (xy -0.21844 -0.22733) (xy -0.22225 -0.23876) (xy -0.22352 -0.24892) (xy -0.22606 -0.25908)
						(xy -0.22733 -0.27051) (xy -0.22733 -0.28067) (xy -0.2286 -0.2921) (xy -0.22733 -0.30353) (xy -0.22733 -0.31369)
						(xy -0.22606 -0.32512) (xy -0.22352 -0.33528) (xy -0.22225 -0.34544) (xy -0.21844 -0.35687) (xy -0.2159 -0.36703)
						(xy -0.21209 -0.37719) (xy -0.20701 -0.38735) (xy -0.2032 -0.39624) (xy -0.19812 -0.4064) (xy -0.17272 -0.44196)
						(xy -0.1651 -0.44958) (xy -0.1651 -0.7366) (xy -0.16256 -0.76835) (xy -0.1524 -0.8001) (xy -0.13716 -0.82804)
						(xy -0.11684 -0.85344) (xy -0.09144 -0.87376) (xy -0.0635 -0.889) (xy -0.03175 -0.89916) (xy 0 -0.9017)
						(xy 0.03175 -0.89916) (xy 0.0635 -0.889) (xy 0.09144 -0.87376) (xy 0.11684 -0.85344) (xy 0.13716 -0.82804)
						(xy 0.1524 -0.8001) (xy 0.16256 -0.76835) (xy 0.1651 -0.7366) (xy 0.1651 -0.44958) (xy 0.17272 -0.44196)
						(xy 0.19812 -0.4064) (xy 0.2032 -0.39624) (xy 0.20701 -0.38735) (xy 0.21209 -0.37719) (xy 0.2159 -0.36703)
						(xy 0.21844 -0.35687) (xy 0.22225 -0.34544) (xy 0.22352 -0.33528) (xy 0.22606 -0.32512) (xy 0.22733 -0.31369)
						(xy 0.22733 -0.30353) (xy 0.2286 -0.2921) (xy 0.22733 -0.28067) (xy 0.22733 -0.27051) (xy 0.22606 -0.25908)
						(xy 0.22352 -0.24892) (xy 0.22225 -0.23876) (xy 0.21844 -0.22733) (xy 0.2159 -0.21717) (xy 0.21209 -0.20701)
						(xy 0.20701 -0.19685) (xy 0.2032 -0.18796) (xy 0.19812 -0.1778) (xy 0.17272 -0.14224) (xy 0.1651 -0.13462)
						(xy 0.1651 0.7366) (xy 0.16256 0.76835) (xy 0.1524 0.8001) (xy 0.13716 0.82804) (xy 0.11684 0.85344)
						(xy 0.09144 0.87376) (xy 0.0635 0.889) (xy 0.03175 0.89916)
					)
					(width 0)
					(fill yes)
				)
			)
		)
		(pad "162" smd custom
			(at 19.05 -4.106672 180)
			(size 0.1143 0.1143)
			(layers "F.Cu" "F.Mask" "F.Paste")
			(net "M_A_DQ43")
			(options
				(clearance outline)
				(anchor circle)
			)
			(primitives
				(gr_poly
					(pts
						(xy 0 0.9017) (xy -0.03175 0.89916) (xy -0.0635 0.889) (xy -0.09144 0.87376) (xy -0.11684 0.85344)
						(xy -0.13716 0.82804) (xy -0.1524 0.8001) (xy -0.16256 0.76835) (xy -0.1651 0.7366) (xy -0.1651 0.44958)
						(xy -0.17272 0.44196) (xy -0.19812 0.4064) (xy -0.2032 0.39624) (xy -0.20701 0.38735) (xy -0.21209 0.37719)
						(xy -0.2159 0.36703) (xy -0.21844 0.35687) (xy -0.22225 0.34544) (xy -0.22352 0.33528) (xy -0.22606 0.32512)
						(xy -0.22733 0.31369) (xy -0.22733 0.30353) (xy -0.2286 0.2921) (xy -0.22733 0.28067) (xy -0.22733 0.27051)
						(xy -0.22606 0.25908) (xy -0.22352 0.24892) (xy -0.22225 0.23876) (xy -0.21844 0.22733) (xy -0.2159 0.21717)
						(xy -0.21209 0.20701) (xy -0.20701 0.19685) (xy -0.2032 0.18796) (xy -0.19812 0.1778) (xy -0.17272 0.14224)
						(xy -0.1651 0.13462) (xy -0.1651 -0.7366) (xy -0.16256 -0.76835) (xy -0.1524 -0.8001) (xy -0.13716 -0.82804)
						(xy -0.11684 -0.85344) (xy -0.09144 -0.87376) (xy -0.0635 -0.889) (xy -0.03175 -0.89916) (xy 0 -0.9017)
						(xy 0.03175 -0.89916) (xy 0.0635 -0.889) (xy 0.09144 -0.87376) (xy 0.11684 -0.85344) (xy 0.13716 -0.82804)
						(xy 0.1524 -0.8001) (xy 0.16256 -0.76835) (xy 0.1651 -0.7366) (xy 0.1651 0.13462) (xy 0.17272 0.14224)
						(xy 0.19812 0.1778) (xy 0.2032 0.18796) (xy 0.20701 0.19685) (xy 0.21209 0.20701) (xy 0.2159 0.21717)
						(xy 0.21844 0.22733) (xy 0.22225 0.23876) (xy 0.22352 0.24892) (xy 0.22606 0.25908) (xy 0.22733 0.27051)
						(xy 0.22733 0.28067) (xy 0.2286 0.2921) (xy 0.22733 0.30353) (xy 0.22733 0.31369) (xy 0.22606 0.32512)
						(xy 0.22352 0.33528) (xy 0.22225 0.34544) (xy 0.21844 0.35687) (xy 0.2159 0.36703) (xy 0.21209 0.37719)
						(xy 0.20701 0.38735) (xy 0.2032 0.39624) (xy 0.19812 0.4064) (xy 0.17272 0.44196) (xy 0.1651 0.44958)
						(xy 0.1651 0.7366) (xy 0.16256 0.76835) (xy 0.1524 0.8001) (xy 0.13716 0.82804) (xy 0.11684 0.85344)
						(xy 0.09144 0.87376) (xy 0.0635 0.889) (xy 0.03175 0.89916)
					)
					(width 0)
					(fill yes)
				)
			)
		)
		(pad "163" smd custom
			(at 19.349974 4.106672 180)
			(size 0.1143 0.1143)
			(layers "F.Cu" "F.Mask" "F.Paste")
			(net "GND")
			(options
				(clearance outline)
				(anchor circle)
			)
			(primitives
				(gr_poly
					(pts
						(xy 0 0.9017) (xy -0.03175 0.89916) (xy -0.0635 0.889) (xy -0.09144 0.87376) (xy -0.11684 0.85344)
						(xy -0.13716 0.82804) (xy -0.1524 0.8001) (xy -0.16256 0.76835) (xy -0.1651 0.7366) (xy -0.1651 0.11938)
						(xy -0.17272 0.11176) (xy -0.19812 0.0762) (xy -0.2032 0.06604) (xy -0.20701 0.05715) (xy -0.21209 0.04699)
						(xy -0.2159 0.03683) (xy -0.21844 0.02667) (xy -0.22225 0.01524) (xy -0.22352 0.00508) (xy -0.22606 -0.00508)
						(xy -0.22733 -0.01651) (xy -0.22733 -0.02667) (xy -0.2286 -0.0381) (xy -0.22733 -0.04953) (xy -0.22733 -0.05969)
						(xy -0.22606 -0.07112) (xy -0.22352 -0.08128) (xy -0.22225 -0.09144) (xy -0.21844 -0.10287) (xy -0.2159 -0.11303)
						(xy -0.21209 -0.12319) (xy -0.20701 -0.13335) (xy -0.2032 -0.14224) (xy -0.19812 -0.1524) (xy -0.17272 -0.18796)
						(xy -0.1651 -0.19558) (xy -0.1651 -0.7366) (xy -0.16256 -0.76835) (xy -0.1524 -0.8001) (xy -0.13716 -0.82804)
						(xy -0.11684 -0.85344) (xy -0.09144 -0.87376) (xy -0.0635 -0.889) (xy -0.03175 -0.89916) (xy 0 -0.9017)
						(xy 0.03175 -0.89916) (xy 0.0635 -0.889) (xy 0.09144 -0.87376) (xy 0.11684 -0.85344) (xy 0.13716 -0.82804)
						(xy 0.1524 -0.8001) (xy 0.16256 -0.76835) (xy 0.1651 -0.7366) (xy 0.1651 -0.19685) (xy 0.17272 -0.18923)
						(xy 0.17907 -0.18034) (xy 0.18669 -0.17145) (xy 0.19177 -0.16256) (xy 0.19812 -0.15367) (xy 0.20828 -0.13335)
						(xy 0.21971 -0.10287) (xy 0.22225 -0.09271) (xy 0.22479 -0.08128) (xy 0.22606 -0.07112) (xy 0.2286 -0.05969)
						(xy 0.2286 -0.01651) (xy 0.22606 -0.00508) (xy 0.22479 0.00508) (xy 0.22225 0.01651) (xy 0.21971 0.02667)
						(xy 0.20828 0.05715) (xy 0.19812 0.07747) (xy 0.19177 0.08636) (xy 0.18669 0.09525) (xy 0.17907 0.10414)
						(xy 0.17272 0.11303) (xy 0.1651 0.12065) (xy 0.1651 0.7366) (xy 0.16256 0.76835) (xy 0.1524 0.8001)
						(xy 0.13716 0.82804) (xy 0.11684 0.85344) (xy 0.09144 0.87376) (xy 0.0635 0.889) (xy 0.03175 0.89916)
					)
					(width 0)
					(fill yes)
				)
			)
		)
		(pad "164" smd custom
			(at 19.649948 -4.106672 180)
			(size 0.1143 0.1143)
			(layers "F.Cu" "F.Mask" "F.Paste")
			(net "GND")
			(options
				(clearance outline)
				(anchor circle)
			)
			(primitives
				(gr_poly
					(pts
						(xy 0 0.9017) (xy -0.03175 0.89916) (xy -0.0635 0.889) (xy -0.09144 0.87376) (xy -0.11684 0.85344)
						(xy -0.13716 0.82804) (xy -0.1524 0.8001) (xy -0.16256 0.76835) (xy -0.1651 0.7366) (xy -0.1651 0.19685)
						(xy -0.17272 0.18923) (xy -0.17907 0.18034) (xy -0.18669 0.17145) (xy -0.19177 0.16256) (xy -0.19812 0.15367)
						(xy -0.20828 0.13335) (xy -0.21971 0.10287) (xy -0.22225 0.09271) (xy -0.22479 0.08128) (xy -0.22606 0.07112)
						(xy -0.2286 0.05969) (xy -0.2286 0.01651) (xy -0.22606 0.00508) (xy -0.22479 -0.00508) (xy -0.22225 -0.01651)
						(xy -0.21971 -0.02667) (xy -0.20828 -0.05715) (xy -0.19812 -0.07747) (xy -0.19177 -0.08636) (xy -0.18669 -0.09525)
						(xy -0.17907 -0.10414) (xy -0.17272 -0.11303) (xy -0.1651 -0.12065) (xy -0.1651 -0.7366) (xy -0.16256 -0.76835)
						(xy -0.1524 -0.8001) (xy -0.13716 -0.82804) (xy -0.11684 -0.85344) (xy -0.09144 -0.87376) (xy -0.0635 -0.889)
						(xy -0.03175 -0.89916) (xy 0 -0.9017) (xy 0.03175 -0.89916) (xy 0.0635 -0.889) (xy 0.09144 -0.87376)
						(xy 0.11684 -0.85344) (xy 0.13716 -0.82804) (xy 0.1524 -0.8001) (xy 0.16256 -0.76835) (xy 0.1651 -0.7366)
						(xy 0.1651 -0.11938) (xy 0.17272 -0.11176) (xy 0.19812 -0.0762) (xy 0.2032 -0.06604) (xy 0.20701 -0.05715)
						(xy 0.21209 -0.04699) (xy 0.2159 -0.03683) (xy 0.21844 -0.02667) (xy 0.22225 -0.01524) (xy 0.22352 -0.00508)
						(xy 0.22606 0.00508) (xy 0.22733 0.01651) (xy 0.22733 0.02667) (xy 0.2286 0.0381) (xy 0.22733 0.04953)
						(xy 0.22733 0.05969) (xy 0.22606 0.07112) (xy 0.22352 0.08128) (xy 0.22225 0.09144) (xy 0.21844 0.10287)
						(xy 0.2159 0.11303) (xy 0.21209 0.12319) (xy 0.20701 0.13335) (xy 0.2032 0.14224) (xy 0.19812 0.1524)
						(xy 0.17272 0.18796) (xy 0.1651 0.19558) (xy 0.1651 0.7366) (xy 0.16256 0.76835) (xy 0.1524 0.8001)
						(xy 0.13716 0.82804) (xy 0.11684 0.85344) (xy 0.09144 0.87376) (xy 0.0635 0.889) (xy 0.03175 0.89916)
					)
					(width 0)
					(fill yes)
				)
			)
		)
		(pad "165" smd custom
			(at 19.949922 4.106672 180)
			(size 0.1143 0.1143)
			(layers "F.Cu" "F.Mask" "F.Paste")
			(net "M_A_DQ52")
			(options
				(clearance outline)
				(anchor circle)
			)
			(primitives
				(gr_poly
					(pts
						(xy 0 0.9017) (xy -0.03175 0.89916) (xy -0.0635 0.889) (xy -0.09144 0.87376) (xy -0.11684 0.85344)
						(xy -0.13716 0.82804) (xy -0.1524 0.8001) (xy -0.16256 0.76835) (xy -0.1651 0.7366) (xy -0.1651 -0.13462)
						(xy -0.17272 -0.14224) (xy -0.19812 -0.1778) (xy -0.2032 -0.18796) (xy -0.20701 -0.19685) (xy -0.21209 -0.20701)
						(xy -0.2159 -0.21717) (xy -0.21844 -0.22733) (xy -0.22225 -0.23876) (xy -0.22352 -0.24892) (xy -0.22606 -0.25908)
						(xy -0.22733 -0.27051) (xy -0.22733 -0.28067) (xy -0.2286 -0.2921) (xy -0.22733 -0.30353) (xy -0.22733 -0.31369)
						(xy -0.22606 -0.32512) (xy -0.22352 -0.33528) (xy -0.22225 -0.34544) (xy -0.21844 -0.35687) (xy -0.2159 -0.36703)
						(xy -0.21209 -0.37719) (xy -0.20701 -0.38735) (xy -0.2032 -0.39624) (xy -0.19812 -0.4064) (xy -0.17272 -0.44196)
						(xy -0.1651 -0.44958) (xy -0.1651 -0.7366) (xy -0.16256 -0.76835) (xy -0.1524 -0.8001) (xy -0.13716 -0.82804)
						(xy -0.11684 -0.85344) (xy -0.09144 -0.87376) (xy -0.0635 -0.889) (xy -0.03175 -0.89916) (xy 0 -0.9017)
						(xy 0.03175 -0.89916) (xy 0.0635 -0.889) (xy 0.09144 -0.87376) (xy 0.11684 -0.85344) (xy 0.13716 -0.82804)
						(xy 0.1524 -0.8001) (xy 0.16256 -0.76835) (xy 0.1651 -0.7366) (xy 0.1651 -0.44958) (xy 0.17272 -0.44196)
						(xy 0.19812 -0.4064) (xy 0.2032 -0.39624) (xy 0.20701 -0.38735) (xy 0.21209 -0.37719) (xy 0.2159 -0.36703)
						(xy 0.21844 -0.35687) (xy 0.22225 -0.34544) (xy 0.22352 -0.33528) (xy 0.22606 -0.32512) (xy 0.22733 -0.31369)
						(xy 0.22733 -0.30353) (xy 0.2286 -0.2921) (xy 0.22733 -0.28067) (xy 0.22733 -0.27051) (xy 0.22606 -0.25908)
						(xy 0.22352 -0.24892) (xy 0.22225 -0.23876) (xy 0.21844 -0.22733) (xy 0.2159 -0.21717) (xy 0.21209 -0.20701)
						(xy 0.20701 -0.19685) (xy 0.2032 -0.18796) (xy 0.19812 -0.1778) (xy 0.17272 -0.14224) (xy 0.1651 -0.13462)
						(xy 0.1651 0.7366) (xy 0.16256 0.76835) (xy 0.1524 0.8001) (xy 0.13716 0.82804) (xy 0.11684 0.85344)
						(xy 0.09144 0.87376) (xy 0.0635 0.889) (xy 0.03175 0.89916)
					)
					(width 0)
					(fill yes)
				)
			)
		)
		(pad "166" smd custom
			(at 20.249896 -4.106672 180)
			(size 0.1143 0.1143)
			(layers "F.Cu" "F.Mask" "F.Paste")
			(net "M_A_DQ48")
			(options
				(clearance outline)
				(anchor circle)
			)
			(primitives
				(gr_poly
					(pts
						(xy 0 0.9017) (xy -0.03175 0.89916) (xy -0.0635 0.889) (xy -0.09144 0.87376) (xy -0.11684 0.85344)
						(xy -0.13716 0.82804) (xy -0.1524 0.8001) (xy -0.16256 0.76835) (xy -0.1651 0.7366) (xy -0.1651 0.44958)
						(xy -0.17272 0.44196) (xy -0.19812 0.4064) (xy -0.2032 0.39624) (xy -0.20701 0.38735) (xy -0.21209 0.37719)
						(xy -0.2159 0.36703) (xy -0.21844 0.35687) (xy -0.22225 0.34544) (xy -0.22352 0.33528) (xy -0.22606 0.32512)
						(xy -0.22733 0.31369) (xy -0.22733 0.30353) (xy -0.2286 0.2921) (xy -0.22733 0.28067) (xy -0.22733 0.27051)
						(xy -0.22606 0.25908) (xy -0.22352 0.24892) (xy -0.22225 0.23876) (xy -0.21844 0.22733) (xy -0.2159 0.21717)
						(xy -0.21209 0.20701) (xy -0.20701 0.19685) (xy -0.2032 0.18796) (xy -0.19812 0.1778) (xy -0.17272 0.14224)
						(xy -0.1651 0.13462) (xy -0.1651 -0.7366) (xy -0.16256 -0.76835) (xy -0.1524 -0.8001) (xy -0.13716 -0.82804)
						(xy -0.11684 -0.85344) (xy -0.09144 -0.87376) (xy -0.0635 -0.889) (xy -0.03175 -0.89916) (xy 0 -0.9017)
						(xy 0.03175 -0.89916) (xy 0.0635 -0.889) (xy 0.09144 -0.87376) (xy 0.11684 -0.85344) (xy 0.13716 -0.82804)
						(xy 0.1524 -0.8001) (xy 0.16256 -0.76835) (xy 0.1651 -0.7366) (xy 0.1651 0.13462) (xy 0.17272 0.14224)
						(xy 0.19812 0.1778) (xy 0.2032 0.18796) (xy 0.20701 0.19685) (xy 0.21209 0.20701) (xy 0.2159 0.21717)
						(xy 0.21844 0.22733) (xy 0.22225 0.23876) (xy 0.22352 0.24892) (xy 0.22606 0.25908) (xy 0.22733 0.27051)
						(xy 0.22733 0.28067) (xy 0.2286 0.2921) (xy 0.22733 0.30353) (xy 0.22733 0.31369) (xy 0.22606 0.32512)
						(xy 0.22352 0.33528) (xy 0.22225 0.34544) (xy 0.21844 0.35687) (xy 0.2159 0.36703) (xy 0.21209 0.37719)
						(xy 0.20701 0.38735) (xy 0.2032 0.39624) (xy 0.19812 0.4064) (xy 0.17272 0.44196) (xy 0.1651 0.44958)
						(xy 0.1651 0.7366) (xy 0.16256 0.76835) (xy 0.1524 0.8001) (xy 0.13716 0.82804) (xy 0.11684 0.85344)
						(xy 0.09144 0.87376) (xy 0.0635 0.889) (xy 0.03175 0.89916)
					)
					(width 0)
					(fill yes)
				)
			)
		)
		(pad "167" smd custom
			(at 20.550124 4.106672 180)
			(size 0.1143 0.1143)
			(layers "F.Cu" "F.Mask" "F.Paste")
			(net "M_A_DQ53")
			(options
				(clearance outline)
				(anchor circle)
			)
			(primitives
				(gr_poly
					(pts
						(xy 0 0.9017) (xy -0.03175 0.89916) (xy -0.0635 0.889) (xy -0.09144 0.87376) (xy -0.11684 0.85344)
						(xy -0.13716 0.82804) (xy -0.1524 0.8001) (xy -0.16256 0.76835) (xy -0.1651 0.7366) (xy -0.1651 0.11938)
						(xy -0.17272 0.11176) (xy -0.19812 0.0762) (xy -0.2032 0.06604) (xy -0.20701 0.05715) (xy -0.21209 0.04699)
						(xy -0.2159 0.03683) (xy -0.21844 0.02667) (xy -0.22225 0.01524) (xy -0.22352 0.00508) (xy -0.22606 -0.00508)
						(xy -0.22733 -0.01651) (xy -0.22733 -0.02667) (xy -0.2286 -0.0381) (xy -0.22733 -0.04953) (xy -0.22733 -0.05969)
						(xy -0.22606 -0.07112) (xy -0.22352 -0.08128) (xy -0.22225 -0.09144) (xy -0.21844 -0.10287) (xy -0.2159 -0.11303)
						(xy -0.21209 -0.12319) (xy -0.20701 -0.13335) (xy -0.2032 -0.14224) (xy -0.19812 -0.1524) (xy -0.17272 -0.18796)
						(xy -0.1651 -0.19558) (xy -0.1651 -0.7366) (xy -0.16256 -0.76835) (xy -0.1524 -0.8001) (xy -0.13716 -0.82804)
						(xy -0.11684 -0.85344) (xy -0.09144 -0.87376) (xy -0.0635 -0.889) (xy -0.03175 -0.89916) (xy 0 -0.9017)
						(xy 0.03175 -0.89916) (xy 0.0635 -0.889) (xy 0.09144 -0.87376) (xy 0.11684 -0.85344) (xy 0.13716 -0.82804)
						(xy 0.1524 -0.8001) (xy 0.16256 -0.76835) (xy 0.1651 -0.7366) (xy 0.1651 -0.19685) (xy 0.17272 -0.18923)
						(xy 0.17907 -0.18034) (xy 0.18669 -0.17145) (xy 0.19177 -0.16256) (xy 0.19812 -0.15367) (xy 0.20828 -0.13335)
						(xy 0.21971 -0.10287) (xy 0.22225 -0.09271) (xy 0.22479 -0.08128) (xy 0.22606 -0.07112) (xy 0.2286 -0.05969)
						(xy 0.2286 -0.01651) (xy 0.22606 -0.00508) (xy 0.22479 0.00508) (xy 0.22225 0.01651) (xy 0.21971 0.02667)
						(xy 0.20828 0.05715) (xy 0.19812 0.07747) (xy 0.19177 0.08636) (xy 0.18669 0.09525) (xy 0.17907 0.10414)
						(xy 0.17272 0.11303) (xy 0.1651 0.12065) (xy 0.1651 0.7366) (xy 0.16256 0.76835) (xy 0.1524 0.8001)
						(xy 0.13716 0.82804) (xy 0.11684 0.85344) (xy 0.09144 0.87376) (xy 0.0635 0.889) (xy 0.03175 0.89916)
					)
					(width 0)
					(fill yes)
				)
			)
		)
		(pad "168" smd custom
			(at 20.850098 -4.106672 180)
			(size 0.1143 0.1143)
			(layers "F.Cu" "F.Mask" "F.Paste")
			(net "M_A_DQ49")
			(options
				(clearance outline)
				(anchor circle)
			)
			(primitives
				(gr_poly
					(pts
						(xy 0 0.9017) (xy -0.03175 0.89916) (xy -0.0635 0.889) (xy -0.09144 0.87376) (xy -0.11684 0.85344)
						(xy -0.13716 0.82804) (xy -0.1524 0.8001) (xy -0.16256 0.76835) (xy -0.1651 0.7366) (xy -0.1651 0.19685)
						(xy -0.17272 0.18923) (xy -0.17907 0.18034) (xy -0.18669 0.17145) (xy -0.19177 0.16256) (xy -0.19812 0.15367)
						(xy -0.20828 0.13335) (xy -0.21971 0.10287) (xy -0.22225 0.09271) (xy -0.22479 0.08128) (xy -0.22606 0.07112)
						(xy -0.2286 0.05969) (xy -0.2286 0.01651) (xy -0.22606 0.00508) (xy -0.22479 -0.00508) (xy -0.22225 -0.01651)
						(xy -0.21971 -0.02667) (xy -0.20828 -0.05715) (xy -0.19812 -0.07747) (xy -0.19177 -0.08636) (xy -0.18669 -0.09525)
						(xy -0.17907 -0.10414) (xy -0.17272 -0.11303) (xy -0.1651 -0.12065) (xy -0.1651 -0.7366) (xy -0.16256 -0.76835)
						(xy -0.1524 -0.8001) (xy -0.13716 -0.82804) (xy -0.11684 -0.85344) (xy -0.09144 -0.87376) (xy -0.0635 -0.889)
						(xy -0.03175 -0.89916) (xy 0 -0.9017) (xy 0.03175 -0.89916) (xy 0.0635 -0.889) (xy 0.09144 -0.87376)
						(xy 0.11684 -0.85344) (xy 0.13716 -0.82804) (xy 0.1524 -0.8001) (xy 0.16256 -0.76835) (xy 0.1651 -0.7366)
						(xy 0.1651 -0.11938) (xy 0.17272 -0.11176) (xy 0.19812 -0.0762) (xy 0.2032 -0.06604) (xy 0.20701 -0.05715)
						(xy 0.21209 -0.04699) (xy 0.2159 -0.03683) (xy 0.21844 -0.02667) (xy 0.22225 -0.01524) (xy 0.22352 -0.00508)
						(xy 0.22606 0.00508) (xy 0.22733 0.01651) (xy 0.22733 0.02667) (xy 0.2286 0.0381) (xy 0.22733 0.04953)
						(xy 0.22733 0.05969) (xy 0.22606 0.07112) (xy 0.22352 0.08128) (xy 0.22225 0.09144) (xy 0.21844 0.10287)
						(xy 0.2159 0.11303) (xy 0.21209 0.12319) (xy 0.20701 0.13335) (xy 0.2032 0.14224) (xy 0.19812 0.1524)
						(xy 0.17272 0.18796) (xy 0.1651 0.19558) (xy 0.1651 0.7366) (xy 0.16256 0.76835) (xy 0.1524 0.8001)
						(xy 0.13716 0.82804) (xy 0.11684 0.85344) (xy 0.09144 0.87376) (xy 0.0635 0.889) (xy 0.03175 0.89916)
					)
					(width 0)
					(fill yes)
				)
			)
		)
		(pad "169" smd custom
			(at 21.150072 4.106672 180)
			(size 0.1143 0.1143)
			(layers "F.Cu" "F.Mask" "F.Paste")
			(net "GND")
			(options
				(clearance outline)
				(anchor circle)
			)
			(primitives
				(gr_poly
					(pts
						(xy 0 0.9017) (xy -0.03175 0.89916) (xy -0.0635 0.889) (xy -0.09144 0.87376) (xy -0.11684 0.85344)
						(xy -0.13716 0.82804) (xy -0.1524 0.8001) (xy -0.16256 0.76835) (xy -0.1651 0.7366) (xy -0.1651 -0.13462)
						(xy -0.17272 -0.14224) (xy -0.19812 -0.1778) (xy -0.2032 -0.18796) (xy -0.20701 -0.19685) (xy -0.21209 -0.20701)
						(xy -0.2159 -0.21717) (xy -0.21844 -0.22733) (xy -0.22225 -0.23876) (xy -0.22352 -0.24892) (xy -0.22606 -0.25908)
						(xy -0.22733 -0.27051) (xy -0.22733 -0.28067) (xy -0.2286 -0.2921) (xy -0.22733 -0.30353) (xy -0.22733 -0.31369)
						(xy -0.22606 -0.32512) (xy -0.22352 -0.33528) (xy -0.22225 -0.34544) (xy -0.21844 -0.35687) (xy -0.2159 -0.36703)
						(xy -0.21209 -0.37719) (xy -0.20701 -0.38735) (xy -0.2032 -0.39624) (xy -0.19812 -0.4064) (xy -0.17272 -0.44196)
						(xy -0.1651 -0.44958) (xy -0.1651 -0.7366) (xy -0.16256 -0.76835) (xy -0.1524 -0.8001) (xy -0.13716 -0.82804)
						(xy -0.11684 -0.85344) (xy -0.09144 -0.87376) (xy -0.0635 -0.889) (xy -0.03175 -0.89916) (xy 0 -0.9017)
						(xy 0.03175 -0.89916) (xy 0.0635 -0.889) (xy 0.09144 -0.87376) (xy 0.11684 -0.85344) (xy 0.13716 -0.82804)
						(xy 0.1524 -0.8001) (xy 0.16256 -0.76835) (xy 0.1651 -0.7366) (xy 0.1651 -0.44958) (xy 0.17272 -0.44196)
						(xy 0.19812 -0.4064) (xy 0.2032 -0.39624) (xy 0.20701 -0.38735) (xy 0.21209 -0.37719) (xy 0.2159 -0.36703)
						(xy 0.21844 -0.35687) (xy 0.22225 -0.34544) (xy 0.22352 -0.33528) (xy 0.22606 -0.32512) (xy 0.22733 -0.31369)
						(xy 0.22733 -0.30353) (xy 0.2286 -0.2921) (xy 0.22733 -0.28067) (xy 0.22733 -0.27051) (xy 0.22606 -0.25908)
						(xy 0.22352 -0.24892) (xy 0.22225 -0.23876) (xy 0.21844 -0.22733) (xy 0.2159 -0.21717) (xy 0.21209 -0.20701)
						(xy 0.20701 -0.19685) (xy 0.2032 -0.18796) (xy 0.19812 -0.1778) (xy 0.17272 -0.14224) (xy 0.1651 -0.13462)
						(xy 0.1651 0.7366) (xy 0.16256 0.76835) (xy 0.1524 0.8001) (xy 0.13716 0.82804) (xy 0.11684 0.85344)
						(xy 0.09144 0.87376) (xy 0.0635 0.889) (xy 0.03175 0.89916)
					)
					(width 0)
					(fill yes)
				)
			)
		)
		(pad "170" smd custom
			(at 21.450046 -4.106672 180)
			(size 0.1143 0.1143)
			(layers "F.Cu" "F.Mask" "F.Paste")
			(net "GND")
			(options
				(clearance outline)
				(anchor circle)
			)
			(primitives
				(gr_poly
					(pts
						(xy 0 0.9017) (xy -0.03175 0.89916) (xy -0.0635 0.889) (xy -0.09144 0.87376) (xy -0.11684 0.85344)
						(xy -0.13716 0.82804) (xy -0.1524 0.8001) (xy -0.16256 0.76835) (xy -0.1651 0.7366) (xy -0.1651 0.44958)
						(xy -0.17272 0.44196) (xy -0.19812 0.4064) (xy -0.2032 0.39624) (xy -0.20701 0.38735) (xy -0.21209 0.37719)
						(xy -0.2159 0.36703) (xy -0.21844 0.35687) (xy -0.22225 0.34544) (xy -0.22352 0.33528) (xy -0.22606 0.32512)
						(xy -0.22733 0.31369) (xy -0.22733 0.30353) (xy -0.2286 0.2921) (xy -0.22733 0.28067) (xy -0.22733 0.27051)
						(xy -0.22606 0.25908) (xy -0.22352 0.24892) (xy -0.22225 0.23876) (xy -0.21844 0.22733) (xy -0.2159 0.21717)
						(xy -0.21209 0.20701) (xy -0.20701 0.19685) (xy -0.2032 0.18796) (xy -0.19812 0.1778) (xy -0.17272 0.14224)
						(xy -0.1651 0.13462) (xy -0.1651 -0.7366) (xy -0.16256 -0.76835) (xy -0.1524 -0.8001) (xy -0.13716 -0.82804)
						(xy -0.11684 -0.85344) (xy -0.09144 -0.87376) (xy -0.0635 -0.889) (xy -0.03175 -0.89916) (xy 0 -0.9017)
						(xy 0.03175 -0.89916) (xy 0.0635 -0.889) (xy 0.09144 -0.87376) (xy 0.11684 -0.85344) (xy 0.13716 -0.82804)
						(xy 0.1524 -0.8001) (xy 0.16256 -0.76835) (xy 0.1651 -0.7366) (xy 0.1651 0.13462) (xy 0.17272 0.14224)
						(xy 0.19812 0.1778) (xy 0.2032 0.18796) (xy 0.20701 0.19685) (xy 0.21209 0.20701) (xy 0.2159 0.21717)
						(xy 0.21844 0.22733) (xy 0.22225 0.23876) (xy 0.22352 0.24892) (xy 0.22606 0.25908) (xy 0.22733 0.27051)
						(xy 0.22733 0.28067) (xy 0.2286 0.2921) (xy 0.22733 0.30353) (xy 0.22733 0.31369) (xy 0.22606 0.32512)
						(xy 0.22352 0.33528) (xy 0.22225 0.34544) (xy 0.21844 0.35687) (xy 0.2159 0.36703) (xy 0.21209 0.37719)
						(xy 0.20701 0.38735) (xy 0.2032 0.39624) (xy 0.19812 0.4064) (xy 0.17272 0.44196) (xy 0.1651 0.44958)
						(xy 0.1651 0.7366) (xy 0.16256 0.76835) (xy 0.1524 0.8001) (xy 0.13716 0.82804) (xy 0.11684 0.85344)
						(xy 0.09144 0.87376) (xy 0.0635 0.889) (xy 0.03175 0.89916)
					)
					(width 0)
					(fill yes)
				)
			)
		)
		(pad "171" smd custom
			(at 21.75002 4.106672 180)
			(size 0.1143 0.1143)
			(layers "F.Cu" "F.Mask" "F.Paste")
			(net "M_A_DQS_DN6")
			(options
				(clearance outline)
				(anchor circle)
			)
			(primitives
				(gr_poly
					(pts
						(xy 0 0.9017) (xy -0.03175 0.89916) (xy -0.0635 0.889) (xy -0.09144 0.87376) (xy -0.11684 0.85344)
						(xy -0.13716 0.82804) (xy -0.1524 0.8001) (xy -0.16256 0.76835) (xy -0.1651 0.7366) (xy -0.1651 0.11938)
						(xy -0.17272 0.11176) (xy -0.19812 0.0762) (xy -0.2032 0.06604) (xy -0.20701 0.05715) (xy -0.21209 0.04699)
						(xy -0.2159 0.03683) (xy -0.21844 0.02667) (xy -0.22225 0.01524) (xy -0.22352 0.00508) (xy -0.22606 -0.00508)
						(xy -0.22733 -0.01651) (xy -0.22733 -0.02667) (xy -0.2286 -0.0381) (xy -0.22733 -0.04953) (xy -0.22733 -0.05969)
						(xy -0.22606 -0.07112) (xy -0.22352 -0.08128) (xy -0.22225 -0.09144) (xy -0.21844 -0.10287) (xy -0.2159 -0.11303)
						(xy -0.21209 -0.12319) (xy -0.20701 -0.13335) (xy -0.2032 -0.14224) (xy -0.19812 -0.1524) (xy -0.17272 -0.18796)
						(xy -0.1651 -0.19558) (xy -0.1651 -0.7366) (xy -0.16256 -0.76835) (xy -0.1524 -0.8001) (xy -0.13716 -0.82804)
						(xy -0.11684 -0.85344) (xy -0.09144 -0.87376) (xy -0.0635 -0.889) (xy -0.03175 -0.89916) (xy 0 -0.9017)
						(xy 0.03175 -0.89916) (xy 0.0635 -0.889) (xy 0.09144 -0.87376) (xy 0.11684 -0.85344) (xy 0.13716 -0.82804)
						(xy 0.1524 -0.8001) (xy 0.16256 -0.76835) (xy 0.1651 -0.7366) (xy 0.1651 -0.19685) (xy 0.17272 -0.18923)
						(xy 0.17907 -0.18034) (xy 0.18669 -0.17145) (xy 0.19177 -0.16256) (xy 0.19812 -0.15367) (xy 0.20828 -0.13335)
						(xy 0.21971 -0.10287) (xy 0.22225 -0.09271) (xy 0.22479 -0.08128) (xy 0.22606 -0.07112) (xy 0.2286 -0.05969)
						(xy 0.2286 -0.01651) (xy 0.22606 -0.00508) (xy 0.22479 0.00508) (xy 0.22225 0.01651) (xy 0.21971 0.02667)
						(xy 0.20828 0.05715) (xy 0.19812 0.07747) (xy 0.19177 0.08636) (xy 0.18669 0.09525) (xy 0.17907 0.10414)
						(xy 0.17272 0.11303) (xy 0.1651 0.12065) (xy 0.1651 0.7366) (xy 0.16256 0.76835) (xy 0.1524 0.8001)
						(xy 0.13716 0.82804) (xy 0.11684 0.85344) (xy 0.09144 0.87376) (xy 0.0635 0.889) (xy 0.03175 0.89916)
					)
					(width 0)
					(fill yes)
				)
			)
		)
		(pad "172" smd custom
			(at 22.049994 -4.106672 180)
			(size 0.1143 0.1143)
			(layers "F.Cu" "F.Mask" "F.Paste")
			(net "GND")
			(options
				(clearance outline)
				(anchor circle)
			)
			(primitives
				(gr_poly
					(pts
						(xy 0 0.9017) (xy -0.03175 0.89916) (xy -0.0635 0.889) (xy -0.09144 0.87376) (xy -0.11684 0.85344)
						(xy -0.13716 0.82804) (xy -0.1524 0.8001) (xy -0.16256 0.76835) (xy -0.1651 0.7366) (xy -0.1651 0.19685)
						(xy -0.17272 0.18923) (xy -0.17907 0.18034) (xy -0.18669 0.17145) (xy -0.19177 0.16256) (xy -0.19812 0.15367)
						(xy -0.20828 0.13335) (xy -0.21971 0.10287) (xy -0.22225 0.09271) (xy -0.22479 0.08128) (xy -0.22606 0.07112)
						(xy -0.2286 0.05969) (xy -0.2286 0.01651) (xy -0.22606 0.00508) (xy -0.22479 -0.00508) (xy -0.22225 -0.01651)
						(xy -0.21971 -0.02667) (xy -0.20828 -0.05715) (xy -0.19812 -0.07747) (xy -0.19177 -0.08636) (xy -0.18669 -0.09525)
						(xy -0.17907 -0.10414) (xy -0.17272 -0.11303) (xy -0.1651 -0.12065) (xy -0.1651 -0.7366) (xy -0.16256 -0.76835)
						(xy -0.1524 -0.8001) (xy -0.13716 -0.82804) (xy -0.11684 -0.85344) (xy -0.09144 -0.87376) (xy -0.0635 -0.889)
						(xy -0.03175 -0.89916) (xy 0 -0.9017) (xy 0.03175 -0.89916) (xy 0.0635 -0.889) (xy 0.09144 -0.87376)
						(xy 0.11684 -0.85344) (xy 0.13716 -0.82804) (xy 0.1524 -0.8001) (xy 0.16256 -0.76835) (xy 0.1651 -0.7366)
						(xy 0.1651 -0.11938) (xy 0.17272 -0.11176) (xy 0.19812 -0.0762) (xy 0.2032 -0.06604) (xy 0.20701 -0.05715)
						(xy 0.21209 -0.04699) (xy 0.2159 -0.03683) (xy 0.21844 -0.02667) (xy 0.22225 -0.01524) (xy 0.22352 -0.00508)
						(xy 0.22606 0.00508) (xy 0.22733 0.01651) (xy 0.22733 0.02667) (xy 0.2286 0.0381) (xy 0.22733 0.04953)
						(xy 0.22733 0.05969) (xy 0.22606 0.07112) (xy 0.22352 0.08128) (xy 0.22225 0.09144) (xy 0.21844 0.10287)
						(xy 0.2159 0.11303) (xy 0.21209 0.12319) (xy 0.20701 0.13335) (xy 0.2032 0.14224) (xy 0.19812 0.1524)
						(xy 0.17272 0.18796) (xy 0.1651 0.19558) (xy 0.1651 0.7366) (xy 0.16256 0.76835) (xy 0.1524 0.8001)
						(xy 0.13716 0.82804) (xy 0.11684 0.85344) (xy 0.09144 0.87376) (xy 0.0635 0.889) (xy 0.03175 0.89916)
					)
					(width 0)
					(fill yes)
				)
			)
		)
		(pad "173" smd custom
			(at 22.349968 4.106672 180)
			(size 0.1143 0.1143)
			(layers "F.Cu" "F.Mask" "F.Paste")
			(net "M_A_DQS_DP6")
			(options
				(clearance outline)
				(anchor circle)
			)
			(primitives
				(gr_poly
					(pts
						(xy 0 0.9017) (xy -0.03175 0.89916) (xy -0.0635 0.889) (xy -0.09144 0.87376) (xy -0.11684 0.85344)
						(xy -0.13716 0.82804) (xy -0.1524 0.8001) (xy -0.16256 0.76835) (xy -0.1651 0.7366) (xy -0.1651 -0.13462)
						(xy -0.17272 -0.14224) (xy -0.19812 -0.1778) (xy -0.2032 -0.18796) (xy -0.20701 -0.19685) (xy -0.21209 -0.20701)
						(xy -0.2159 -0.21717) (xy -0.21844 -0.22733) (xy -0.22225 -0.23876) (xy -0.22352 -0.24892) (xy -0.22606 -0.25908)
						(xy -0.22733 -0.27051) (xy -0.22733 -0.28067) (xy -0.2286 -0.2921) (xy -0.22733 -0.30353) (xy -0.22733 -0.31369)
						(xy -0.22606 -0.32512) (xy -0.22352 -0.33528) (xy -0.22225 -0.34544) (xy -0.21844 -0.35687) (xy -0.2159 -0.36703)
						(xy -0.21209 -0.37719) (xy -0.20701 -0.38735) (xy -0.2032 -0.39624) (xy -0.19812 -0.4064) (xy -0.17272 -0.44196)
						(xy -0.1651 -0.44958) (xy -0.1651 -0.7366) (xy -0.16256 -0.76835) (xy -0.1524 -0.8001) (xy -0.13716 -0.82804)
						(xy -0.11684 -0.85344) (xy -0.09144 -0.87376) (xy -0.0635 -0.889) (xy -0.03175 -0.89916) (xy 0 -0.9017)
						(xy 0.03175 -0.89916) (xy 0.0635 -0.889) (xy 0.09144 -0.87376) (xy 0.11684 -0.85344) (xy 0.13716 -0.82804)
						(xy 0.1524 -0.8001) (xy 0.16256 -0.76835) (xy 0.1651 -0.7366) (xy 0.1651 -0.44958) (xy 0.17272 -0.44196)
						(xy 0.19812 -0.4064) (xy 0.2032 -0.39624) (xy 0.20701 -0.38735) (xy 0.21209 -0.37719) (xy 0.2159 -0.36703)
						(xy 0.21844 -0.35687) (xy 0.22225 -0.34544) (xy 0.22352 -0.33528) (xy 0.22606 -0.32512) (xy 0.22733 -0.31369)
						(xy 0.22733 -0.30353) (xy 0.2286 -0.2921) (xy 0.22733 -0.28067) (xy 0.22733 -0.27051) (xy 0.22606 -0.25908)
						(xy 0.22352 -0.24892) (xy 0.22225 -0.23876) (xy 0.21844 -0.22733) (xy 0.2159 -0.21717) (xy 0.21209 -0.20701)
						(xy 0.20701 -0.19685) (xy 0.2032 -0.18796) (xy 0.19812 -0.1778) (xy 0.17272 -0.14224) (xy 0.1651 -0.13462)
						(xy 0.1651 0.7366) (xy 0.16256 0.76835) (xy 0.1524 0.8001) (xy 0.13716 0.82804) (xy 0.11684 0.85344)
						(xy 0.09144 0.87376) (xy 0.0635 0.889) (xy 0.03175 0.89916)
					)
					(width 0)
					(fill yes)
				)
			)
		)
		(pad "174" smd custom
			(at 22.649942 -4.106672 180)
			(size 0.1143 0.1143)
			(layers "F.Cu" "F.Mask" "F.Paste")
			(net "M_A_DQ50")
			(options
				(clearance outline)
				(anchor circle)
			)
			(primitives
				(gr_poly
					(pts
						(xy 0 0.9017) (xy -0.03175 0.89916) (xy -0.0635 0.889) (xy -0.09144 0.87376) (xy -0.11684 0.85344)
						(xy -0.13716 0.82804) (xy -0.1524 0.8001) (xy -0.16256 0.76835) (xy -0.1651 0.7366) (xy -0.1651 0.44958)
						(xy -0.17272 0.44196) (xy -0.19812 0.4064) (xy -0.2032 0.39624) (xy -0.20701 0.38735) (xy -0.21209 0.37719)
						(xy -0.2159 0.36703) (xy -0.21844 0.35687) (xy -0.22225 0.34544) (xy -0.22352 0.33528) (xy -0.22606 0.32512)
						(xy -0.22733 0.31369) (xy -0.22733 0.30353) (xy -0.2286 0.2921) (xy -0.22733 0.28067) (xy -0.22733 0.27051)
						(xy -0.22606 0.25908) (xy -0.22352 0.24892) (xy -0.22225 0.23876) (xy -0.21844 0.22733) (xy -0.2159 0.21717)
						(xy -0.21209 0.20701) (xy -0.20701 0.19685) (xy -0.2032 0.18796) (xy -0.19812 0.1778) (xy -0.17272 0.14224)
						(xy -0.1651 0.13462) (xy -0.1651 -0.7366) (xy -0.16256 -0.76835) (xy -0.1524 -0.8001) (xy -0.13716 -0.82804)
						(xy -0.11684 -0.85344) (xy -0.09144 -0.87376) (xy -0.0635 -0.889) (xy -0.03175 -0.89916) (xy 0 -0.9017)
						(xy 0.03175 -0.89916) (xy 0.0635 -0.889) (xy 0.09144 -0.87376) (xy 0.11684 -0.85344) (xy 0.13716 -0.82804)
						(xy 0.1524 -0.8001) (xy 0.16256 -0.76835) (xy 0.1651 -0.7366) (xy 0.1651 0.13462) (xy 0.17272 0.14224)
						(xy 0.19812 0.1778) (xy 0.2032 0.18796) (xy 0.20701 0.19685) (xy 0.21209 0.20701) (xy 0.2159 0.21717)
						(xy 0.21844 0.22733) (xy 0.22225 0.23876) (xy 0.22352 0.24892) (xy 0.22606 0.25908) (xy 0.22733 0.27051)
						(xy 0.22733 0.28067) (xy 0.2286 0.2921) (xy 0.22733 0.30353) (xy 0.22733 0.31369) (xy 0.22606 0.32512)
						(xy 0.22352 0.33528) (xy 0.22225 0.34544) (xy 0.21844 0.35687) (xy 0.2159 0.36703) (xy 0.21209 0.37719)
						(xy 0.20701 0.38735) (xy 0.2032 0.39624) (xy 0.19812 0.4064) (xy 0.17272 0.44196) (xy 0.1651 0.44958)
						(xy 0.1651 0.7366) (xy 0.16256 0.76835) (xy 0.1524 0.8001) (xy 0.13716 0.82804) (xy 0.11684 0.85344)
						(xy 0.09144 0.87376) (xy 0.0635 0.889) (xy 0.03175 0.89916)
					)
					(width 0)
					(fill yes)
				)
			)
		)
		(pad "175" smd custom
			(at 22.949916 4.106672 180)
			(size 0.1143 0.1143)
			(layers "F.Cu" "F.Mask" "F.Paste")
			(net "GND")
			(options
				(clearance outline)
				(anchor circle)
			)
			(primitives
				(gr_poly
					(pts
						(xy 0 0.9017) (xy -0.03175 0.89916) (xy -0.0635 0.889) (xy -0.09144 0.87376) (xy -0.11684 0.85344)
						(xy -0.13716 0.82804) (xy -0.1524 0.8001) (xy -0.16256 0.76835) (xy -0.1651 0.7366) (xy -0.1651 0.11938)
						(xy -0.17272 0.11176) (xy -0.19812 0.0762) (xy -0.2032 0.06604) (xy -0.20701 0.05715) (xy -0.21209 0.04699)
						(xy -0.2159 0.03683) (xy -0.21844 0.02667) (xy -0.22225 0.01524) (xy -0.22352 0.00508) (xy -0.22606 -0.00508)
						(xy -0.22733 -0.01651) (xy -0.22733 -0.02667) (xy -0.2286 -0.0381) (xy -0.22733 -0.04953) (xy -0.22733 -0.05969)
						(xy -0.22606 -0.07112) (xy -0.22352 -0.08128) (xy -0.22225 -0.09144) (xy -0.21844 -0.10287) (xy -0.2159 -0.11303)
						(xy -0.21209 -0.12319) (xy -0.20701 -0.13335) (xy -0.2032 -0.14224) (xy -0.19812 -0.1524) (xy -0.17272 -0.18796)
						(xy -0.1651 -0.19558) (xy -0.1651 -0.7366) (xy -0.16256 -0.76835) (xy -0.1524 -0.8001) (xy -0.13716 -0.82804)
						(xy -0.11684 -0.85344) (xy -0.09144 -0.87376) (xy -0.0635 -0.889) (xy -0.03175 -0.89916) (xy 0 -0.9017)
						(xy 0.03175 -0.89916) (xy 0.0635 -0.889) (xy 0.09144 -0.87376) (xy 0.11684 -0.85344) (xy 0.13716 -0.82804)
						(xy 0.1524 -0.8001) (xy 0.16256 -0.76835) (xy 0.1651 -0.7366) (xy 0.1651 -0.19685) (xy 0.17272 -0.18923)
						(xy 0.17907 -0.18034) (xy 0.18669 -0.17145) (xy 0.19177 -0.16256) (xy 0.19812 -0.15367) (xy 0.20828 -0.13335)
						(xy 0.21971 -0.10287) (xy 0.22225 -0.09271) (xy 0.22479 -0.08128) (xy 0.22606 -0.07112) (xy 0.2286 -0.05969)
						(xy 0.2286 -0.01651) (xy 0.22606 -0.00508) (xy 0.22479 0.00508) (xy 0.22225 0.01651) (xy 0.21971 0.02667)
						(xy 0.20828 0.05715) (xy 0.19812 0.07747) (xy 0.19177 0.08636) (xy 0.18669 0.09525) (xy 0.17907 0.10414)
						(xy 0.17272 0.11303) (xy 0.1651 0.12065) (xy 0.1651 0.7366) (xy 0.16256 0.76835) (xy 0.1524 0.8001)
						(xy 0.13716 0.82804) (xy 0.11684 0.85344) (xy 0.09144 0.87376) (xy 0.0635 0.889) (xy 0.03175 0.89916)
					)
					(width 0)
					(fill yes)
				)
			)
		)
		(pad "176" smd custom
			(at 23.24989 -4.106672 180)
			(size 0.1143 0.1143)
			(layers "F.Cu" "F.Mask" "F.Paste")
			(net "M_A_DQ51")
			(options
				(clearance outline)
				(anchor circle)
			)
			(primitives
				(gr_poly
					(pts
						(xy 0 0.9017) (xy -0.03175 0.89916) (xy -0.0635 0.889) (xy -0.09144 0.87376) (xy -0.11684 0.85344)
						(xy -0.13716 0.82804) (xy -0.1524 0.8001) (xy -0.16256 0.76835) (xy -0.1651 0.7366) (xy -0.1651 0.19685)
						(xy -0.17272 0.18923) (xy -0.17907 0.18034) (xy -0.18669 0.17145) (xy -0.19177 0.16256) (xy -0.19812 0.15367)
						(xy -0.20828 0.13335) (xy -0.21971 0.10287) (xy -0.22225 0.09271) (xy -0.22479 0.08128) (xy -0.22606 0.07112)
						(xy -0.2286 0.05969) (xy -0.2286 0.01651) (xy -0.22606 0.00508) (xy -0.22479 -0.00508) (xy -0.22225 -0.01651)
						(xy -0.21971 -0.02667) (xy -0.20828 -0.05715) (xy -0.19812 -0.07747) (xy -0.19177 -0.08636) (xy -0.18669 -0.09525)
						(xy -0.17907 -0.10414) (xy -0.17272 -0.11303) (xy -0.1651 -0.12065) (xy -0.1651 -0.7366) (xy -0.16256 -0.76835)
						(xy -0.1524 -0.8001) (xy -0.13716 -0.82804) (xy -0.11684 -0.85344) (xy -0.09144 -0.87376) (xy -0.0635 -0.889)
						(xy -0.03175 -0.89916) (xy 0 -0.9017) (xy 0.03175 -0.89916) (xy 0.0635 -0.889) (xy 0.09144 -0.87376)
						(xy 0.11684 -0.85344) (xy 0.13716 -0.82804) (xy 0.1524 -0.8001) (xy 0.16256 -0.76835) (xy 0.1651 -0.7366)
						(xy 0.1651 -0.11938) (xy 0.17272 -0.11176) (xy 0.19812 -0.0762) (xy 0.2032 -0.06604) (xy 0.20701 -0.05715)
						(xy 0.21209 -0.04699) (xy 0.2159 -0.03683) (xy 0.21844 -0.02667) (xy 0.22225 -0.01524) (xy 0.22352 -0.00508)
						(xy 0.22606 0.00508) (xy 0.22733 0.01651) (xy 0.22733 0.02667) (xy 0.2286 0.0381) (xy 0.22733 0.04953)
						(xy 0.22733 0.05969) (xy 0.22606 0.07112) (xy 0.22352 0.08128) (xy 0.22225 0.09144) (xy 0.21844 0.10287)
						(xy 0.2159 0.11303) (xy 0.21209 0.12319) (xy 0.20701 0.13335) (xy 0.2032 0.14224) (xy 0.19812 0.1524)
						(xy 0.17272 0.18796) (xy 0.1651 0.19558) (xy 0.1651 0.7366) (xy 0.16256 0.76835) (xy 0.1524 0.8001)
						(xy 0.13716 0.82804) (xy 0.11684 0.85344) (xy 0.09144 0.87376) (xy 0.0635 0.889) (xy 0.03175 0.89916)
					)
					(width 0)
					(fill yes)
				)
			)
		)
		(pad "177" smd custom
			(at 23.550118 4.106672 180)
			(size 0.1143 0.1143)
			(layers "F.Cu" "F.Mask" "F.Paste")
			(net "M_A_DQ54")
			(options
				(clearance outline)
				(anchor circle)
			)
			(primitives
				(gr_poly
					(pts
						(xy 0 0.9017) (xy -0.03175 0.89916) (xy -0.0635 0.889) (xy -0.09144 0.87376) (xy -0.11684 0.85344)
						(xy -0.13716 0.82804) (xy -0.1524 0.8001) (xy -0.16256 0.76835) (xy -0.1651 0.7366) (xy -0.1651 -0.13462)
						(xy -0.17272 -0.14224) (xy -0.19812 -0.1778) (xy -0.2032 -0.18796) (xy -0.20701 -0.19685) (xy -0.21209 -0.20701)
						(xy -0.2159 -0.21717) (xy -0.21844 -0.22733) (xy -0.22225 -0.23876) (xy -0.22352 -0.24892) (xy -0.22606 -0.25908)
						(xy -0.22733 -0.27051) (xy -0.22733 -0.28067) (xy -0.2286 -0.2921) (xy -0.22733 -0.30353) (xy -0.22733 -0.31369)
						(xy -0.22606 -0.32512) (xy -0.22352 -0.33528) (xy -0.22225 -0.34544) (xy -0.21844 -0.35687) (xy -0.2159 -0.36703)
						(xy -0.21209 -0.37719) (xy -0.20701 -0.38735) (xy -0.2032 -0.39624) (xy -0.19812 -0.4064) (xy -0.17272 -0.44196)
						(xy -0.1651 -0.44958) (xy -0.1651 -0.7366) (xy -0.16256 -0.76835) (xy -0.1524 -0.8001) (xy -0.13716 -0.82804)
						(xy -0.11684 -0.85344) (xy -0.09144 -0.87376) (xy -0.0635 -0.889) (xy -0.03175 -0.89916) (xy 0 -0.9017)
						(xy 0.03175 -0.89916) (xy 0.0635 -0.889) (xy 0.09144 -0.87376) (xy 0.11684 -0.85344) (xy 0.13716 -0.82804)
						(xy 0.1524 -0.8001) (xy 0.16256 -0.76835) (xy 0.1651 -0.7366) (xy 0.1651 -0.44958) (xy 0.17272 -0.44196)
						(xy 0.19812 -0.4064) (xy 0.2032 -0.39624) (xy 0.20701 -0.38735) (xy 0.21209 -0.37719) (xy 0.2159 -0.36703)
						(xy 0.21844 -0.35687) (xy 0.22225 -0.34544) (xy 0.22352 -0.33528) (xy 0.22606 -0.32512) (xy 0.22733 -0.31369)
						(xy 0.22733 -0.30353) (xy 0.2286 -0.2921) (xy 0.22733 -0.28067) (xy 0.22733 -0.27051) (xy 0.22606 -0.25908)
						(xy 0.22352 -0.24892) (xy 0.22225 -0.23876) (xy 0.21844 -0.22733) (xy 0.2159 -0.21717) (xy 0.21209 -0.20701)
						(xy 0.20701 -0.19685) (xy 0.2032 -0.18796) (xy 0.19812 -0.1778) (xy 0.17272 -0.14224) (xy 0.1651 -0.13462)
						(xy 0.1651 0.7366) (xy 0.16256 0.76835) (xy 0.1524 0.8001) (xy 0.13716 0.82804) (xy 0.11684 0.85344)
						(xy 0.09144 0.87376) (xy 0.0635 0.889) (xy 0.03175 0.89916)
					)
					(width 0)
					(fill yes)
				)
			)
		)
		(pad "178" smd custom
			(at 23.850092 -4.106672 180)
			(size 0.1143 0.1143)
			(layers "F.Cu" "F.Mask" "F.Paste")
			(net "GND")
			(options
				(clearance outline)
				(anchor circle)
			)
			(primitives
				(gr_poly
					(pts
						(xy 0 0.9017) (xy -0.03175 0.89916) (xy -0.0635 0.889) (xy -0.09144 0.87376) (xy -0.11684 0.85344)
						(xy -0.13716 0.82804) (xy -0.1524 0.8001) (xy -0.16256 0.76835) (xy -0.1651 0.7366) (xy -0.1651 0.44958)
						(xy -0.17272 0.44196) (xy -0.19812 0.4064) (xy -0.2032 0.39624) (xy -0.20701 0.38735) (xy -0.21209 0.37719)
						(xy -0.2159 0.36703) (xy -0.21844 0.35687) (xy -0.22225 0.34544) (xy -0.22352 0.33528) (xy -0.22606 0.32512)
						(xy -0.22733 0.31369) (xy -0.22733 0.30353) (xy -0.2286 0.2921) (xy -0.22733 0.28067) (xy -0.22733 0.27051)
						(xy -0.22606 0.25908) (xy -0.22352 0.24892) (xy -0.22225 0.23876) (xy -0.21844 0.22733) (xy -0.2159 0.21717)
						(xy -0.21209 0.20701) (xy -0.20701 0.19685) (xy -0.2032 0.18796) (xy -0.19812 0.1778) (xy -0.17272 0.14224)
						(xy -0.1651 0.13462) (xy -0.1651 -0.7366) (xy -0.16256 -0.76835) (xy -0.1524 -0.8001) (xy -0.13716 -0.82804)
						(xy -0.11684 -0.85344) (xy -0.09144 -0.87376) (xy -0.0635 -0.889) (xy -0.03175 -0.89916) (xy 0 -0.9017)
						(xy 0.03175 -0.89916) (xy 0.0635 -0.889) (xy 0.09144 -0.87376) (xy 0.11684 -0.85344) (xy 0.13716 -0.82804)
						(xy 0.1524 -0.8001) (xy 0.16256 -0.76835) (xy 0.1651 -0.7366) (xy 0.1651 0.13462) (xy 0.17272 0.14224)
						(xy 0.19812 0.1778) (xy 0.2032 0.18796) (xy 0.20701 0.19685) (xy 0.21209 0.20701) (xy 0.2159 0.21717)
						(xy 0.21844 0.22733) (xy 0.22225 0.23876) (xy 0.22352 0.24892) (xy 0.22606 0.25908) (xy 0.22733 0.27051)
						(xy 0.22733 0.28067) (xy 0.2286 0.2921) (xy 0.22733 0.30353) (xy 0.22733 0.31369) (xy 0.22606 0.32512)
						(xy 0.22352 0.33528) (xy 0.22225 0.34544) (xy 0.21844 0.35687) (xy 0.2159 0.36703) (xy 0.21209 0.37719)
						(xy 0.20701 0.38735) (xy 0.2032 0.39624) (xy 0.19812 0.4064) (xy 0.17272 0.44196) (xy 0.1651 0.44958)
						(xy 0.1651 0.7366) (xy 0.16256 0.76835) (xy 0.1524 0.8001) (xy 0.13716 0.82804) (xy 0.11684 0.85344)
						(xy 0.09144 0.87376) (xy 0.0635 0.889) (xy 0.03175 0.89916)
					)
					(width 0)
					(fill yes)
				)
			)
		)
		(pad "179" smd custom
			(at 24.150066 4.106672 180)
			(size 0.1143 0.1143)
			(layers "F.Cu" "F.Mask" "F.Paste")
			(net "M_A_DQ55")
			(options
				(clearance outline)
				(anchor circle)
			)
			(primitives
				(gr_poly
					(pts
						(xy 0 0.9017) (xy -0.03175 0.89916) (xy -0.0635 0.889) (xy -0.09144 0.87376) (xy -0.11684 0.85344)
						(xy -0.13716 0.82804) (xy -0.1524 0.8001) (xy -0.16256 0.76835) (xy -0.1651 0.7366) (xy -0.1651 0.11938)
						(xy -0.17272 0.11176) (xy -0.19812 0.0762) (xy -0.2032 0.06604) (xy -0.20701 0.05715) (xy -0.21209 0.04699)
						(xy -0.2159 0.03683) (xy -0.21844 0.02667) (xy -0.22225 0.01524) (xy -0.22352 0.00508) (xy -0.22606 -0.00508)
						(xy -0.22733 -0.01651) (xy -0.22733 -0.02667) (xy -0.2286 -0.0381) (xy -0.22733 -0.04953) (xy -0.22733 -0.05969)
						(xy -0.22606 -0.07112) (xy -0.22352 -0.08128) (xy -0.22225 -0.09144) (xy -0.21844 -0.10287) (xy -0.2159 -0.11303)
						(xy -0.21209 -0.12319) (xy -0.20701 -0.13335) (xy -0.2032 -0.14224) (xy -0.19812 -0.1524) (xy -0.17272 -0.18796)
						(xy -0.1651 -0.19558) (xy -0.1651 -0.7366) (xy -0.16256 -0.76835) (xy -0.1524 -0.8001) (xy -0.13716 -0.82804)
						(xy -0.11684 -0.85344) (xy -0.09144 -0.87376) (xy -0.0635 -0.889) (xy -0.03175 -0.89916) (xy 0 -0.9017)
						(xy 0.03175 -0.89916) (xy 0.0635 -0.889) (xy 0.09144 -0.87376) (xy 0.11684 -0.85344) (xy 0.13716 -0.82804)
						(xy 0.1524 -0.8001) (xy 0.16256 -0.76835) (xy 0.1651 -0.7366) (xy 0.1651 -0.19685) (xy 0.17272 -0.18923)
						(xy 0.17907 -0.18034) (xy 0.18669 -0.17145) (xy 0.19177 -0.16256) (xy 0.19812 -0.15367) (xy 0.20828 -0.13335)
						(xy 0.21971 -0.10287) (xy 0.22225 -0.09271) (xy 0.22479 -0.08128) (xy 0.22606 -0.07112) (xy 0.2286 -0.05969)
						(xy 0.2286 -0.01651) (xy 0.22606 -0.00508) (xy 0.22479 0.00508) (xy 0.22225 0.01651) (xy 0.21971 0.02667)
						(xy 0.20828 0.05715) (xy 0.19812 0.07747) (xy 0.19177 0.08636) (xy 0.18669 0.09525) (xy 0.17907 0.10414)
						(xy 0.17272 0.11303) (xy 0.1651 0.12065) (xy 0.1651 0.7366) (xy 0.16256 0.76835) (xy 0.1524 0.8001)
						(xy 0.13716 0.82804) (xy 0.11684 0.85344) (xy 0.09144 0.87376) (xy 0.0635 0.889) (xy 0.03175 0.89916)
					)
					(width 0)
					(fill yes)
				)
			)
		)
		(pad "180" smd custom
			(at 24.45004 -4.106672 180)
			(size 0.1143 0.1143)
			(layers "F.Cu" "F.Mask" "F.Paste")
			(net "M_A_DQ56")
			(options
				(clearance outline)
				(anchor circle)
			)
			(primitives
				(gr_poly
					(pts
						(xy 0 0.9017) (xy -0.03175 0.89916) (xy -0.0635 0.889) (xy -0.09144 0.87376) (xy -0.11684 0.85344)
						(xy -0.13716 0.82804) (xy -0.1524 0.8001) (xy -0.16256 0.76835) (xy -0.1651 0.7366) (xy -0.1651 0.19685)
						(xy -0.17272 0.18923) (xy -0.17907 0.18034) (xy -0.18669 0.17145) (xy -0.19177 0.16256) (xy -0.19812 0.15367)
						(xy -0.20828 0.13335) (xy -0.21971 0.10287) (xy -0.22225 0.09271) (xy -0.22479 0.08128) (xy -0.22606 0.07112)
						(xy -0.2286 0.05969) (xy -0.2286 0.01651) (xy -0.22606 0.00508) (xy -0.22479 -0.00508) (xy -0.22225 -0.01651)
						(xy -0.21971 -0.02667) (xy -0.20828 -0.05715) (xy -0.19812 -0.07747) (xy -0.19177 -0.08636) (xy -0.18669 -0.09525)
						(xy -0.17907 -0.10414) (xy -0.17272 -0.11303) (xy -0.1651 -0.12065) (xy -0.1651 -0.7366) (xy -0.16256 -0.76835)
						(xy -0.1524 -0.8001) (xy -0.13716 -0.82804) (xy -0.11684 -0.85344) (xy -0.09144 -0.87376) (xy -0.0635 -0.889)
						(xy -0.03175 -0.89916) (xy 0 -0.9017) (xy 0.03175 -0.89916) (xy 0.0635 -0.889) (xy 0.09144 -0.87376)
						(xy 0.11684 -0.85344) (xy 0.13716 -0.82804) (xy 0.1524 -0.8001) (xy 0.16256 -0.76835) (xy 0.1651 -0.7366)
						(xy 0.1651 -0.11938) (xy 0.17272 -0.11176) (xy 0.19812 -0.0762) (xy 0.2032 -0.06604) (xy 0.20701 -0.05715)
						(xy 0.21209 -0.04699) (xy 0.2159 -0.03683) (xy 0.21844 -0.02667) (xy 0.22225 -0.01524) (xy 0.22352 -0.00508)
						(xy 0.22606 0.00508) (xy 0.22733 0.01651) (xy 0.22733 0.02667) (xy 0.2286 0.0381) (xy 0.22733 0.04953)
						(xy 0.22733 0.05969) (xy 0.22606 0.07112) (xy 0.22352 0.08128) (xy 0.22225 0.09144) (xy 0.21844 0.10287)
						(xy 0.2159 0.11303) (xy 0.21209 0.12319) (xy 0.20701 0.13335) (xy 0.2032 0.14224) (xy 0.19812 0.1524)
						(xy 0.17272 0.18796) (xy 0.1651 0.19558) (xy 0.1651 0.7366) (xy 0.16256 0.76835) (xy 0.1524 0.8001)
						(xy 0.13716 0.82804) (xy 0.11684 0.85344) (xy 0.09144 0.87376) (xy 0.0635 0.889) (xy 0.03175 0.89916)
					)
					(width 0)
					(fill yes)
				)
			)
		)
		(pad "181" smd custom
			(at 24.750014 4.106672 180)
			(size 0.1143 0.1143)
			(layers "F.Cu" "F.Mask" "F.Paste")
			(net "GND")
			(options
				(clearance outline)
				(anchor circle)
			)
			(primitives
				(gr_poly
					(pts
						(xy 0 0.9017) (xy -0.03175 0.89916) (xy -0.0635 0.889) (xy -0.09144 0.87376) (xy -0.11684 0.85344)
						(xy -0.13716 0.82804) (xy -0.1524 0.8001) (xy -0.16256 0.76835) (xy -0.1651 0.7366) (xy -0.1651 -0.13462)
						(xy -0.17272 -0.14224) (xy -0.19812 -0.1778) (xy -0.2032 -0.18796) (xy -0.20701 -0.19685) (xy -0.21209 -0.20701)
						(xy -0.2159 -0.21717) (xy -0.21844 -0.22733) (xy -0.22225 -0.23876) (xy -0.22352 -0.24892) (xy -0.22606 -0.25908)
						(xy -0.22733 -0.27051) (xy -0.22733 -0.28067) (xy -0.2286 -0.2921) (xy -0.22733 -0.30353) (xy -0.22733 -0.31369)
						(xy -0.22606 -0.32512) (xy -0.22352 -0.33528) (xy -0.22225 -0.34544) (xy -0.21844 -0.35687) (xy -0.2159 -0.36703)
						(xy -0.21209 -0.37719) (xy -0.20701 -0.38735) (xy -0.2032 -0.39624) (xy -0.19812 -0.4064) (xy -0.17272 -0.44196)
						(xy -0.1651 -0.44958) (xy -0.1651 -0.7366) (xy -0.16256 -0.76835) (xy -0.1524 -0.8001) (xy -0.13716 -0.82804)
						(xy -0.11684 -0.85344) (xy -0.09144 -0.87376) (xy -0.0635 -0.889) (xy -0.03175 -0.89916) (xy 0 -0.9017)
						(xy 0.03175 -0.89916) (xy 0.0635 -0.889) (xy 0.09144 -0.87376) (xy 0.11684 -0.85344) (xy 0.13716 -0.82804)
						(xy 0.1524 -0.8001) (xy 0.16256 -0.76835) (xy 0.1651 -0.7366) (xy 0.1651 -0.44958) (xy 0.17272 -0.44196)
						(xy 0.19812 -0.4064) (xy 0.2032 -0.39624) (xy 0.20701 -0.38735) (xy 0.21209 -0.37719) (xy 0.2159 -0.36703)
						(xy 0.21844 -0.35687) (xy 0.22225 -0.34544) (xy 0.22352 -0.33528) (xy 0.22606 -0.32512) (xy 0.22733 -0.31369)
						(xy 0.22733 -0.30353) (xy 0.2286 -0.2921) (xy 0.22733 -0.28067) (xy 0.22733 -0.27051) (xy 0.22606 -0.25908)
						(xy 0.22352 -0.24892) (xy 0.22225 -0.23876) (xy 0.21844 -0.22733) (xy 0.2159 -0.21717) (xy 0.21209 -0.20701)
						(xy 0.20701 -0.19685) (xy 0.2032 -0.18796) (xy 0.19812 -0.1778) (xy 0.17272 -0.14224) (xy 0.1651 -0.13462)
						(xy 0.1651 0.7366) (xy 0.16256 0.76835) (xy 0.1524 0.8001) (xy 0.13716 0.82804) (xy 0.11684 0.85344)
						(xy 0.09144 0.87376) (xy 0.0635 0.889) (xy 0.03175 0.89916)
					)
					(width 0)
					(fill yes)
				)
			)
		)
		(pad "182" smd custom
			(at 25.049988 -4.106672 180)
			(size 0.1143 0.1143)
			(layers "F.Cu" "F.Mask" "F.Paste")
			(net "M_A_DQ57")
			(options
				(clearance outline)
				(anchor circle)
			)
			(primitives
				(gr_poly
					(pts
						(xy 0 0.9017) (xy -0.03175 0.89916) (xy -0.0635 0.889) (xy -0.09144 0.87376) (xy -0.11684 0.85344)
						(xy -0.13716 0.82804) (xy -0.1524 0.8001) (xy -0.16256 0.76835) (xy -0.1651 0.7366) (xy -0.1651 0.44958)
						(xy -0.17272 0.44196) (xy -0.19812 0.4064) (xy -0.2032 0.39624) (xy -0.20701 0.38735) (xy -0.21209 0.37719)
						(xy -0.2159 0.36703) (xy -0.21844 0.35687) (xy -0.22225 0.34544) (xy -0.22352 0.33528) (xy -0.22606 0.32512)
						(xy -0.22733 0.31369) (xy -0.22733 0.30353) (xy -0.2286 0.2921) (xy -0.22733 0.28067) (xy -0.22733 0.27051)
						(xy -0.22606 0.25908) (xy -0.22352 0.24892) (xy -0.22225 0.23876) (xy -0.21844 0.22733) (xy -0.2159 0.21717)
						(xy -0.21209 0.20701) (xy -0.20701 0.19685) (xy -0.2032 0.18796) (xy -0.19812 0.1778) (xy -0.17272 0.14224)
						(xy -0.1651 0.13462) (xy -0.1651 -0.7366) (xy -0.16256 -0.76835) (xy -0.1524 -0.8001) (xy -0.13716 -0.82804)
						(xy -0.11684 -0.85344) (xy -0.09144 -0.87376) (xy -0.0635 -0.889) (xy -0.03175 -0.89916) (xy 0 -0.9017)
						(xy 0.03175 -0.89916) (xy 0.0635 -0.889) (xy 0.09144 -0.87376) (xy 0.11684 -0.85344) (xy 0.13716 -0.82804)
						(xy 0.1524 -0.8001) (xy 0.16256 -0.76835) (xy 0.1651 -0.7366) (xy 0.1651 0.13462) (xy 0.17272 0.14224)
						(xy 0.19812 0.1778) (xy 0.2032 0.18796) (xy 0.20701 0.19685) (xy 0.21209 0.20701) (xy 0.2159 0.21717)
						(xy 0.21844 0.22733) (xy 0.22225 0.23876) (xy 0.22352 0.24892) (xy 0.22606 0.25908) (xy 0.22733 0.27051)
						(xy 0.22733 0.28067) (xy 0.2286 0.2921) (xy 0.22733 0.30353) (xy 0.22733 0.31369) (xy 0.22606 0.32512)
						(xy 0.22352 0.33528) (xy 0.22225 0.34544) (xy 0.21844 0.35687) (xy 0.2159 0.36703) (xy 0.21209 0.37719)
						(xy 0.20701 0.38735) (xy 0.2032 0.39624) (xy 0.19812 0.4064) (xy 0.17272 0.44196) (xy 0.1651 0.44958)
						(xy 0.1651 0.7366) (xy 0.16256 0.76835) (xy 0.1524 0.8001) (xy 0.13716 0.82804) (xy 0.11684 0.85344)
						(xy 0.09144 0.87376) (xy 0.0635 0.889) (xy 0.03175 0.89916)
					)
					(width 0)
					(fill yes)
				)
			)
		)
		(pad "183" smd custom
			(at 25.349962 4.106672 180)
			(size 0.1143 0.1143)
			(layers "F.Cu" "F.Mask" "F.Paste")
			(net "M_A_DQ60")
			(options
				(clearance outline)
				(anchor circle)
			)
			(primitives
				(gr_poly
					(pts
						(xy 0 0.9017) (xy -0.03175 0.89916) (xy -0.0635 0.889) (xy -0.09144 0.87376) (xy -0.11684 0.85344)
						(xy -0.13716 0.82804) (xy -0.1524 0.8001) (xy -0.16256 0.76835) (xy -0.1651 0.7366) (xy -0.1651 0.11938)
						(xy -0.17272 0.11176) (xy -0.19812 0.0762) (xy -0.2032 0.06604) (xy -0.20701 0.05715) (xy -0.21209 0.04699)
						(xy -0.2159 0.03683) (xy -0.21844 0.02667) (xy -0.22225 0.01524) (xy -0.22352 0.00508) (xy -0.22606 -0.00508)
						(xy -0.22733 -0.01651) (xy -0.22733 -0.02667) (xy -0.2286 -0.0381) (xy -0.22733 -0.04953) (xy -0.22733 -0.05969)
						(xy -0.22606 -0.07112) (xy -0.22352 -0.08128) (xy -0.22225 -0.09144) (xy -0.21844 -0.10287) (xy -0.2159 -0.11303)
						(xy -0.21209 -0.12319) (xy -0.20701 -0.13335) (xy -0.2032 -0.14224) (xy -0.19812 -0.1524) (xy -0.17272 -0.18796)
						(xy -0.1651 -0.19558) (xy -0.1651 -0.7366) (xy -0.16256 -0.76835) (xy -0.1524 -0.8001) (xy -0.13716 -0.82804)
						(xy -0.11684 -0.85344) (xy -0.09144 -0.87376) (xy -0.0635 -0.889) (xy -0.03175 -0.89916) (xy 0 -0.9017)
						(xy 0.03175 -0.89916) (xy 0.0635 -0.889) (xy 0.09144 -0.87376) (xy 0.11684 -0.85344) (xy 0.13716 -0.82804)
						(xy 0.1524 -0.8001) (xy 0.16256 -0.76835) (xy 0.1651 -0.7366) (xy 0.1651 -0.19685) (xy 0.17272 -0.18923)
						(xy 0.17907 -0.18034) (xy 0.18669 -0.17145) (xy 0.19177 -0.16256) (xy 0.19812 -0.15367) (xy 0.20828 -0.13335)
						(xy 0.21971 -0.10287) (xy 0.22225 -0.09271) (xy 0.22479 -0.08128) (xy 0.22606 -0.07112) (xy 0.2286 -0.05969)
						(xy 0.2286 -0.01651) (xy 0.22606 -0.00508) (xy 0.22479 0.00508) (xy 0.22225 0.01651) (xy 0.21971 0.02667)
						(xy 0.20828 0.05715) (xy 0.19812 0.07747) (xy 0.19177 0.08636) (xy 0.18669 0.09525) (xy 0.17907 0.10414)
						(xy 0.17272 0.11303) (xy 0.1651 0.12065) (xy 0.1651 0.7366) (xy 0.16256 0.76835) (xy 0.1524 0.8001)
						(xy 0.13716 0.82804) (xy 0.11684 0.85344) (xy 0.09144 0.87376) (xy 0.0635 0.889) (xy 0.03175 0.89916)
					)
					(width 0)
					(fill yes)
				)
			)
		)
		(pad "184" smd custom
			(at 25.649936 -4.106672 180)
			(size 0.1143 0.1143)
			(layers "F.Cu" "F.Mask" "F.Paste")
			(net "GND")
			(options
				(clearance outline)
				(anchor circle)
			)
			(primitives
				(gr_poly
					(pts
						(xy 0 0.9017) (xy -0.03175 0.89916) (xy -0.0635 0.889) (xy -0.09144 0.87376) (xy -0.11684 0.85344)
						(xy -0.13716 0.82804) (xy -0.1524 0.8001) (xy -0.16256 0.76835) (xy -0.1651 0.7366) (xy -0.1651 0.19685)
						(xy -0.17272 0.18923) (xy -0.17907 0.18034) (xy -0.18669 0.17145) (xy -0.19177 0.16256) (xy -0.19812 0.15367)
						(xy -0.20828 0.13335) (xy -0.21971 0.10287) (xy -0.22225 0.09271) (xy -0.22479 0.08128) (xy -0.22606 0.07112)
						(xy -0.2286 0.05969) (xy -0.2286 0.01651) (xy -0.22606 0.00508) (xy -0.22479 -0.00508) (xy -0.22225 -0.01651)
						(xy -0.21971 -0.02667) (xy -0.20828 -0.05715) (xy -0.19812 -0.07747) (xy -0.19177 -0.08636) (xy -0.18669 -0.09525)
						(xy -0.17907 -0.10414) (xy -0.17272 -0.11303) (xy -0.1651 -0.12065) (xy -0.1651 -0.7366) (xy -0.16256 -0.76835)
						(xy -0.1524 -0.8001) (xy -0.13716 -0.82804) (xy -0.11684 -0.85344) (xy -0.09144 -0.87376) (xy -0.0635 -0.889)
						(xy -0.03175 -0.89916) (xy 0 -0.9017) (xy 0.03175 -0.89916) (xy 0.0635 -0.889) (xy 0.09144 -0.87376)
						(xy 0.11684 -0.85344) (xy 0.13716 -0.82804) (xy 0.1524 -0.8001) (xy 0.16256 -0.76835) (xy 0.1651 -0.7366)
						(xy 0.1651 -0.11938) (xy 0.17272 -0.11176) (xy 0.19812 -0.0762) (xy 0.2032 -0.06604) (xy 0.20701 -0.05715)
						(xy 0.21209 -0.04699) (xy 0.2159 -0.03683) (xy 0.21844 -0.02667) (xy 0.22225 -0.01524) (xy 0.22352 -0.00508)
						(xy 0.22606 0.00508) (xy 0.22733 0.01651) (xy 0.22733 0.02667) (xy 0.2286 0.0381) (xy 0.22733 0.04953)
						(xy 0.22733 0.05969) (xy 0.22606 0.07112) (xy 0.22352 0.08128) (xy 0.22225 0.09144) (xy 0.21844 0.10287)
						(xy 0.2159 0.11303) (xy 0.21209 0.12319) (xy 0.20701 0.13335) (xy 0.2032 0.14224) (xy 0.19812 0.1524)
						(xy 0.17272 0.18796) (xy 0.1651 0.19558) (xy 0.1651 0.7366) (xy 0.16256 0.76835) (xy 0.1524 0.8001)
						(xy 0.13716 0.82804) (xy 0.11684 0.85344) (xy 0.09144 0.87376) (xy 0.0635 0.889) (xy 0.03175 0.89916)
					)
					(width 0)
					(fill yes)
				)
			)
		)
		(pad "185" smd custom
			(at 25.94991 4.106672 180)
			(size 0.1143 0.1143)
			(layers "F.Cu" "F.Mask" "F.Paste")
			(net "M_A_DQ61")
			(options
				(clearance outline)
				(anchor circle)
			)
			(primitives
				(gr_poly
					(pts
						(xy 0 0.9017) (xy -0.03175 0.89916) (xy -0.0635 0.889) (xy -0.09144 0.87376) (xy -0.11684 0.85344)
						(xy -0.13716 0.82804) (xy -0.1524 0.8001) (xy -0.16256 0.76835) (xy -0.1651 0.7366) (xy -0.1651 -0.13462)
						(xy -0.17272 -0.14224) (xy -0.19812 -0.1778) (xy -0.2032 -0.18796) (xy -0.20701 -0.19685) (xy -0.21209 -0.20701)
						(xy -0.2159 -0.21717) (xy -0.21844 -0.22733) (xy -0.22225 -0.23876) (xy -0.22352 -0.24892) (xy -0.22606 -0.25908)
						(xy -0.22733 -0.27051) (xy -0.22733 -0.28067) (xy -0.2286 -0.2921) (xy -0.22733 -0.30353) (xy -0.22733 -0.31369)
						(xy -0.22606 -0.32512) (xy -0.22352 -0.33528) (xy -0.22225 -0.34544) (xy -0.21844 -0.35687) (xy -0.2159 -0.36703)
						(xy -0.21209 -0.37719) (xy -0.20701 -0.38735) (xy -0.2032 -0.39624) (xy -0.19812 -0.4064) (xy -0.17272 -0.44196)
						(xy -0.1651 -0.44958) (xy -0.1651 -0.7366) (xy -0.16256 -0.76835) (xy -0.1524 -0.8001) (xy -0.13716 -0.82804)
						(xy -0.11684 -0.85344) (xy -0.09144 -0.87376) (xy -0.0635 -0.889) (xy -0.03175 -0.89916) (xy 0 -0.9017)
						(xy 0.03175 -0.89916) (xy 0.0635 -0.889) (xy 0.09144 -0.87376) (xy 0.11684 -0.85344) (xy 0.13716 -0.82804)
						(xy 0.1524 -0.8001) (xy 0.16256 -0.76835) (xy 0.1651 -0.7366) (xy 0.1651 -0.44958) (xy 0.17272 -0.44196)
						(xy 0.19812 -0.4064) (xy 0.2032 -0.39624) (xy 0.20701 -0.38735) (xy 0.21209 -0.37719) (xy 0.2159 -0.36703)
						(xy 0.21844 -0.35687) (xy 0.22225 -0.34544) (xy 0.22352 -0.33528) (xy 0.22606 -0.32512) (xy 0.22733 -0.31369)
						(xy 0.22733 -0.30353) (xy 0.2286 -0.2921) (xy 0.22733 -0.28067) (xy 0.22733 -0.27051) (xy 0.22606 -0.25908)
						(xy 0.22352 -0.24892) (xy 0.22225 -0.23876) (xy 0.21844 -0.22733) (xy 0.2159 -0.21717) (xy 0.21209 -0.20701)
						(xy 0.20701 -0.19685) (xy 0.2032 -0.18796) (xy 0.19812 -0.1778) (xy 0.17272 -0.14224) (xy 0.1651 -0.13462)
						(xy 0.1651 0.7366) (xy 0.16256 0.76835) (xy 0.1524 0.8001) (xy 0.13716 0.82804) (xy 0.11684 0.85344)
						(xy 0.09144 0.87376) (xy 0.0635 0.889) (xy 0.03175 0.89916)
					)
					(width 0)
					(fill yes)
				)
			)
		)
		(pad "186" smd custom
			(at 26.249884 -4.106672 180)
			(size 0.1143 0.1143)
			(layers "F.Cu" "F.Mask" "F.Paste")
			(net "M_A_DQS_DN7")
			(options
				(clearance outline)
				(anchor circle)
			)
			(primitives
				(gr_poly
					(pts
						(xy 0 0.9017) (xy -0.03175 0.89916) (xy -0.0635 0.889) (xy -0.09144 0.87376) (xy -0.11684 0.85344)
						(xy -0.13716 0.82804) (xy -0.1524 0.8001) (xy -0.16256 0.76835) (xy -0.1651 0.7366) (xy -0.1651 0.44958)
						(xy -0.17272 0.44196) (xy -0.19812 0.4064) (xy -0.2032 0.39624) (xy -0.20701 0.38735) (xy -0.21209 0.37719)
						(xy -0.2159 0.36703) (xy -0.21844 0.35687) (xy -0.22225 0.34544) (xy -0.22352 0.33528) (xy -0.22606 0.32512)
						(xy -0.22733 0.31369) (xy -0.22733 0.30353) (xy -0.2286 0.2921) (xy -0.22733 0.28067) (xy -0.22733 0.27051)
						(xy -0.22606 0.25908) (xy -0.22352 0.24892) (xy -0.22225 0.23876) (xy -0.21844 0.22733) (xy -0.2159 0.21717)
						(xy -0.21209 0.20701) (xy -0.20701 0.19685) (xy -0.2032 0.18796) (xy -0.19812 0.1778) (xy -0.17272 0.14224)
						(xy -0.1651 0.13462) (xy -0.1651 -0.7366) (xy -0.16256 -0.76835) (xy -0.1524 -0.8001) (xy -0.13716 -0.82804)
						(xy -0.11684 -0.85344) (xy -0.09144 -0.87376) (xy -0.0635 -0.889) (xy -0.03175 -0.89916) (xy 0 -0.9017)
						(xy 0.03175 -0.89916) (xy 0.0635 -0.889) (xy 0.09144 -0.87376) (xy 0.11684 -0.85344) (xy 0.13716 -0.82804)
						(xy 0.1524 -0.8001) (xy 0.16256 -0.76835) (xy 0.1651 -0.7366) (xy 0.1651 0.13462) (xy 0.17272 0.14224)
						(xy 0.19812 0.1778) (xy 0.2032 0.18796) (xy 0.20701 0.19685) (xy 0.21209 0.20701) (xy 0.2159 0.21717)
						(xy 0.21844 0.22733) (xy 0.22225 0.23876) (xy 0.22352 0.24892) (xy 0.22606 0.25908) (xy 0.22733 0.27051)
						(xy 0.22733 0.28067) (xy 0.2286 0.2921) (xy 0.22733 0.30353) (xy 0.22733 0.31369) (xy 0.22606 0.32512)
						(xy 0.22352 0.33528) (xy 0.22225 0.34544) (xy 0.21844 0.35687) (xy 0.2159 0.36703) (xy 0.21209 0.37719)
						(xy 0.20701 0.38735) (xy 0.2032 0.39624) (xy 0.19812 0.4064) (xy 0.17272 0.44196) (xy 0.1651 0.44958)
						(xy 0.1651 0.7366) (xy 0.16256 0.76835) (xy 0.1524 0.8001) (xy 0.13716 0.82804) (xy 0.11684 0.85344)
						(xy 0.09144 0.87376) (xy 0.0635 0.889) (xy 0.03175 0.89916)
					)
					(width 0)
					(fill yes)
				)
			)
		)
		(pad "187" smd custom
			(at 26.550112 4.106672 180)
			(size 0.1143 0.1143)
			(layers "F.Cu" "F.Mask" "F.Paste")
			(net "GND")
			(options
				(clearance outline)
				(anchor circle)
			)
			(primitives
				(gr_poly
					(pts
						(xy 0 0.9017) (xy -0.03175 0.89916) (xy -0.0635 0.889) (xy -0.09144 0.87376) (xy -0.11684 0.85344)
						(xy -0.13716 0.82804) (xy -0.1524 0.8001) (xy -0.16256 0.76835) (xy -0.1651 0.7366) (xy -0.1651 0.11938)
						(xy -0.17272 0.11176) (xy -0.19812 0.0762) (xy -0.2032 0.06604) (xy -0.20701 0.05715) (xy -0.21209 0.04699)
						(xy -0.2159 0.03683) (xy -0.21844 0.02667) (xy -0.22225 0.01524) (xy -0.22352 0.00508) (xy -0.22606 -0.00508)
						(xy -0.22733 -0.01651) (xy -0.22733 -0.02667) (xy -0.2286 -0.0381) (xy -0.22733 -0.04953) (xy -0.22733 -0.05969)
						(xy -0.22606 -0.07112) (xy -0.22352 -0.08128) (xy -0.22225 -0.09144) (xy -0.21844 -0.10287) (xy -0.2159 -0.11303)
						(xy -0.21209 -0.12319) (xy -0.20701 -0.13335) (xy -0.2032 -0.14224) (xy -0.19812 -0.1524) (xy -0.17272 -0.18796)
						(xy -0.1651 -0.19558) (xy -0.1651 -0.7366) (xy -0.16256 -0.76835) (xy -0.1524 -0.8001) (xy -0.13716 -0.82804)
						(xy -0.11684 -0.85344) (xy -0.09144 -0.87376) (xy -0.0635 -0.889) (xy -0.03175 -0.89916) (xy 0 -0.9017)
						(xy 0.03175 -0.89916) (xy 0.0635 -0.889) (xy 0.09144 -0.87376) (xy 0.11684 -0.85344) (xy 0.13716 -0.82804)
						(xy 0.1524 -0.8001) (xy 0.16256 -0.76835) (xy 0.1651 -0.7366) (xy 0.1651 -0.19685) (xy 0.17272 -0.18923)
						(xy 0.17907 -0.18034) (xy 0.18669 -0.17145) (xy 0.19177 -0.16256) (xy 0.19812 -0.15367) (xy 0.20828 -0.13335)
						(xy 0.21971 -0.10287) (xy 0.22225 -0.09271) (xy 0.22479 -0.08128) (xy 0.22606 -0.07112) (xy 0.2286 -0.05969)
						(xy 0.2286 -0.01651) (xy 0.22606 -0.00508) (xy 0.22479 0.00508) (xy 0.22225 0.01651) (xy 0.21971 0.02667)
						(xy 0.20828 0.05715) (xy 0.19812 0.07747) (xy 0.19177 0.08636) (xy 0.18669 0.09525) (xy 0.17907 0.10414)
						(xy 0.17272 0.11303) (xy 0.1651 0.12065) (xy 0.1651 0.7366) (xy 0.16256 0.76835) (xy 0.1524 0.8001)
						(xy 0.13716 0.82804) (xy 0.11684 0.85344) (xy 0.09144 0.87376) (xy 0.0635 0.889) (xy 0.03175 0.89916)
					)
					(width 0)
					(fill yes)
				)
			)
		)
		(pad "188" smd custom
			(at 26.850086 -4.106672 180)
			(size 0.1143 0.1143)
			(layers "F.Cu" "F.Mask" "F.Paste")
			(net "M_A_DQS_DP7")
			(options
				(clearance outline)
				(anchor circle)
			)
			(primitives
				(gr_poly
					(pts
						(xy 0 0.9017) (xy -0.03175 0.89916) (xy -0.0635 0.889) (xy -0.09144 0.87376) (xy -0.11684 0.85344)
						(xy -0.13716 0.82804) (xy -0.1524 0.8001) (xy -0.16256 0.76835) (xy -0.1651 0.7366) (xy -0.1651 0.19685)
						(xy -0.17272 0.18923) (xy -0.17907 0.18034) (xy -0.18669 0.17145) (xy -0.19177 0.16256) (xy -0.19812 0.15367)
						(xy -0.20828 0.13335) (xy -0.21971 0.10287) (xy -0.22225 0.09271) (xy -0.22479 0.08128) (xy -0.22606 0.07112)
						(xy -0.2286 0.05969) (xy -0.2286 0.01651) (xy -0.22606 0.00508) (xy -0.22479 -0.00508) (xy -0.22225 -0.01651)
						(xy -0.21971 -0.02667) (xy -0.20828 -0.05715) (xy -0.19812 -0.07747) (xy -0.19177 -0.08636) (xy -0.18669 -0.09525)
						(xy -0.17907 -0.10414) (xy -0.17272 -0.11303) (xy -0.1651 -0.12065) (xy -0.1651 -0.7366) (xy -0.16256 -0.76835)
						(xy -0.1524 -0.8001) (xy -0.13716 -0.82804) (xy -0.11684 -0.85344) (xy -0.09144 -0.87376) (xy -0.0635 -0.889)
						(xy -0.03175 -0.89916) (xy 0 -0.9017) (xy 0.03175 -0.89916) (xy 0.0635 -0.889) (xy 0.09144 -0.87376)
						(xy 0.11684 -0.85344) (xy 0.13716 -0.82804) (xy 0.1524 -0.8001) (xy 0.16256 -0.76835) (xy 0.1651 -0.7366)
						(xy 0.1651 -0.11938) (xy 0.17272 -0.11176) (xy 0.19812 -0.0762) (xy 0.2032 -0.06604) (xy 0.20701 -0.05715)
						(xy 0.21209 -0.04699) (xy 0.2159 -0.03683) (xy 0.21844 -0.02667) (xy 0.22225 -0.01524) (xy 0.22352 -0.00508)
						(xy 0.22606 0.00508) (xy 0.22733 0.01651) (xy 0.22733 0.02667) (xy 0.2286 0.0381) (xy 0.22733 0.04953)
						(xy 0.22733 0.05969) (xy 0.22606 0.07112) (xy 0.22352 0.08128) (xy 0.22225 0.09144) (xy 0.21844 0.10287)
						(xy 0.2159 0.11303) (xy 0.21209 0.12319) (xy 0.20701 0.13335) (xy 0.2032 0.14224) (xy 0.19812 0.1524)
						(xy 0.17272 0.18796) (xy 0.1651 0.19558) (xy 0.1651 0.7366) (xy 0.16256 0.76835) (xy 0.1524 0.8001)
						(xy 0.13716 0.82804) (xy 0.11684 0.85344) (xy 0.09144 0.87376) (xy 0.0635 0.889) (xy 0.03175 0.89916)
					)
					(width 0)
					(fill yes)
				)
			)
		)
		(pad "189" smd custom
			(at 27.15006 4.106672 180)
			(size 0.1143 0.1143)
			(layers "F.Cu" "F.Mask" "F.Paste")
			(net "GND")
			(options
				(clearance outline)
				(anchor circle)
			)
			(primitives
				(gr_poly
					(pts
						(xy 0 0.9017) (xy -0.03175 0.89916) (xy -0.0635 0.889) (xy -0.09144 0.87376) (xy -0.11684 0.85344)
						(xy -0.13716 0.82804) (xy -0.1524 0.8001) (xy -0.16256 0.76835) (xy -0.1651 0.7366) (xy -0.1651 -0.13462)
						(xy -0.17272 -0.14224) (xy -0.19812 -0.1778) (xy -0.2032 -0.18796) (xy -0.20701 -0.19685) (xy -0.21209 -0.20701)
						(xy -0.2159 -0.21717) (xy -0.21844 -0.22733) (xy -0.22225 -0.23876) (xy -0.22352 -0.24892) (xy -0.22606 -0.25908)
						(xy -0.22733 -0.27051) (xy -0.22733 -0.28067) (xy -0.2286 -0.2921) (xy -0.22733 -0.30353) (xy -0.22733 -0.31369)
						(xy -0.22606 -0.32512) (xy -0.22352 -0.33528) (xy -0.22225 -0.34544) (xy -0.21844 -0.35687) (xy -0.2159 -0.36703)
						(xy -0.21209 -0.37719) (xy -0.20701 -0.38735) (xy -0.2032 -0.39624) (xy -0.19812 -0.4064) (xy -0.17272 -0.44196)
						(xy -0.1651 -0.44958) (xy -0.1651 -0.7366) (xy -0.16256 -0.76835) (xy -0.1524 -0.8001) (xy -0.13716 -0.82804)
						(xy -0.11684 -0.85344) (xy -0.09144 -0.87376) (xy -0.0635 -0.889) (xy -0.03175 -0.89916) (xy 0 -0.9017)
						(xy 0.03175 -0.89916) (xy 0.0635 -0.889) (xy 0.09144 -0.87376) (xy 0.11684 -0.85344) (xy 0.13716 -0.82804)
						(xy 0.1524 -0.8001) (xy 0.16256 -0.76835) (xy 0.1651 -0.7366) (xy 0.1651 -0.44958) (xy 0.17272 -0.44196)
						(xy 0.19812 -0.4064) (xy 0.2032 -0.39624) (xy 0.20701 -0.38735) (xy 0.21209 -0.37719) (xy 0.2159 -0.36703)
						(xy 0.21844 -0.35687) (xy 0.22225 -0.34544) (xy 0.22352 -0.33528) (xy 0.22606 -0.32512) (xy 0.22733 -0.31369)
						(xy 0.22733 -0.30353) (xy 0.2286 -0.2921) (xy 0.22733 -0.28067) (xy 0.22733 -0.27051) (xy 0.22606 -0.25908)
						(xy 0.22352 -0.24892) (xy 0.22225 -0.23876) (xy 0.21844 -0.22733) (xy 0.2159 -0.21717) (xy 0.21209 -0.20701)
						(xy 0.20701 -0.19685) (xy 0.2032 -0.18796) (xy 0.19812 -0.1778) (xy 0.17272 -0.14224) (xy 0.1651 -0.13462)
						(xy 0.1651 0.7366) (xy 0.16256 0.76835) (xy 0.1524 0.8001) (xy 0.13716 0.82804) (xy 0.11684 0.85344)
						(xy 0.09144 0.87376) (xy 0.0635 0.889) (xy 0.03175 0.89916)
					)
					(width 0)
					(fill yes)
				)
			)
		)
		(pad "190" smd custom
			(at 27.450034 -4.106672 180)
			(size 0.1143 0.1143)
			(layers "F.Cu" "F.Mask" "F.Paste")
			(net "GND")
			(options
				(clearance outline)
				(anchor circle)
			)
			(primitives
				(gr_poly
					(pts
						(xy 0 0.9017) (xy -0.03175 0.89916) (xy -0.0635 0.889) (xy -0.09144 0.87376) (xy -0.11684 0.85344)
						(xy -0.13716 0.82804) (xy -0.1524 0.8001) (xy -0.16256 0.76835) (xy -0.1651 0.7366) (xy -0.1651 0.44958)
						(xy -0.17272 0.44196) (xy -0.19812 0.4064) (xy -0.2032 0.39624) (xy -0.20701 0.38735) (xy -0.21209 0.37719)
						(xy -0.2159 0.36703) (xy -0.21844 0.35687) (xy -0.22225 0.34544) (xy -0.22352 0.33528) (xy -0.22606 0.32512)
						(xy -0.22733 0.31369) (xy -0.22733 0.30353) (xy -0.2286 0.2921) (xy -0.22733 0.28067) (xy -0.22733 0.27051)
						(xy -0.22606 0.25908) (xy -0.22352 0.24892) (xy -0.22225 0.23876) (xy -0.21844 0.22733) (xy -0.2159 0.21717)
						(xy -0.21209 0.20701) (xy -0.20701 0.19685) (xy -0.2032 0.18796) (xy -0.19812 0.1778) (xy -0.17272 0.14224)
						(xy -0.1651 0.13462) (xy -0.1651 -0.7366) (xy -0.16256 -0.76835) (xy -0.1524 -0.8001) (xy -0.13716 -0.82804)
						(xy -0.11684 -0.85344) (xy -0.09144 -0.87376) (xy -0.0635 -0.889) (xy -0.03175 -0.89916) (xy 0 -0.9017)
						(xy 0.03175 -0.89916) (xy 0.0635 -0.889) (xy 0.09144 -0.87376) (xy 0.11684 -0.85344) (xy 0.13716 -0.82804)
						(xy 0.1524 -0.8001) (xy 0.16256 -0.76835) (xy 0.1651 -0.7366) (xy 0.1651 0.13462) (xy 0.17272 0.14224)
						(xy 0.19812 0.1778) (xy 0.2032 0.18796) (xy 0.20701 0.19685) (xy 0.21209 0.20701) (xy 0.2159 0.21717)
						(xy 0.21844 0.22733) (xy 0.22225 0.23876) (xy 0.22352 0.24892) (xy 0.22606 0.25908) (xy 0.22733 0.27051)
						(xy 0.22733 0.28067) (xy 0.2286 0.2921) (xy 0.22733 0.30353) (xy 0.22733 0.31369) (xy 0.22606 0.32512)
						(xy 0.22352 0.33528) (xy 0.22225 0.34544) (xy 0.21844 0.35687) (xy 0.2159 0.36703) (xy 0.21209 0.37719)
						(xy 0.20701 0.38735) (xy 0.2032 0.39624) (xy 0.19812 0.4064) (xy 0.17272 0.44196) (xy 0.1651 0.44958)
						(xy 0.1651 0.7366) (xy 0.16256 0.76835) (xy 0.1524 0.8001) (xy 0.13716 0.82804) (xy 0.11684 0.85344)
						(xy 0.09144 0.87376) (xy 0.0635 0.889) (xy 0.03175 0.89916)
					)
					(width 0)
					(fill yes)
				)
			)
		)
		(pad "191" smd custom
			(at 27.750008 4.106672 180)
			(size 0.1143 0.1143)
			(layers "F.Cu" "F.Mask" "F.Paste")
			(net "M_A_DQ62")
			(options
				(clearance outline)
				(anchor circle)
			)
			(primitives
				(gr_poly
					(pts
						(xy 0 0.9017) (xy -0.03175 0.89916) (xy -0.0635 0.889) (xy -0.09144 0.87376) (xy -0.11684 0.85344)
						(xy -0.13716 0.82804) (xy -0.1524 0.8001) (xy -0.16256 0.76835) (xy -0.1651 0.7366) (xy -0.1651 0.11938)
						(xy -0.17272 0.11176) (xy -0.19812 0.0762) (xy -0.2032 0.06604) (xy -0.20701 0.05715) (xy -0.21209 0.04699)
						(xy -0.2159 0.03683) (xy -0.21844 0.02667) (xy -0.22225 0.01524) (xy -0.22352 0.00508) (xy -0.22606 -0.00508)
						(xy -0.22733 -0.01651) (xy -0.22733 -0.02667) (xy -0.2286 -0.0381) (xy -0.22733 -0.04953) (xy -0.22733 -0.05969)
						(xy -0.22606 -0.07112) (xy -0.22352 -0.08128) (xy -0.22225 -0.09144) (xy -0.21844 -0.10287) (xy -0.2159 -0.11303)
						(xy -0.21209 -0.12319) (xy -0.20701 -0.13335) (xy -0.2032 -0.14224) (xy -0.19812 -0.1524) (xy -0.17272 -0.18796)
						(xy -0.1651 -0.19558) (xy -0.1651 -0.7366) (xy -0.16256 -0.76835) (xy -0.1524 -0.8001) (xy -0.13716 -0.82804)
						(xy -0.11684 -0.85344) (xy -0.09144 -0.87376) (xy -0.0635 -0.889) (xy -0.03175 -0.89916) (xy 0 -0.9017)
						(xy 0.03175 -0.89916) (xy 0.0635 -0.889) (xy 0.09144 -0.87376) (xy 0.11684 -0.85344) (xy 0.13716 -0.82804)
						(xy 0.1524 -0.8001) (xy 0.16256 -0.76835) (xy 0.1651 -0.7366) (xy 0.1651 -0.19685) (xy 0.17272 -0.18923)
						(xy 0.17907 -0.18034) (xy 0.18669 -0.17145) (xy 0.19177 -0.16256) (xy 0.19812 -0.15367) (xy 0.20828 -0.13335)
						(xy 0.21971 -0.10287) (xy 0.22225 -0.09271) (xy 0.22479 -0.08128) (xy 0.22606 -0.07112) (xy 0.2286 -0.05969)
						(xy 0.2286 -0.01651) (xy 0.22606 -0.00508) (xy 0.22479 0.00508) (xy 0.22225 0.01651) (xy 0.21971 0.02667)
						(xy 0.20828 0.05715) (xy 0.19812 0.07747) (xy 0.19177 0.08636) (xy 0.18669 0.09525) (xy 0.17907 0.10414)
						(xy 0.17272 0.11303) (xy 0.1651 0.12065) (xy 0.1651 0.7366) (xy 0.16256 0.76835) (xy 0.1524 0.8001)
						(xy 0.13716 0.82804) (xy 0.11684 0.85344) (xy 0.09144 0.87376) (xy 0.0635 0.889) (xy 0.03175 0.89916)
					)
					(width 0)
					(fill yes)
				)
			)
		)
		(pad "192" smd custom
			(at 28.049982 -4.106672 180)
			(size 0.1143 0.1143)
			(layers "F.Cu" "F.Mask" "F.Paste")
			(net "M_A_DQ58")
			(options
				(clearance outline)
				(anchor circle)
			)
			(primitives
				(gr_poly
					(pts
						(xy 0 0.9017) (xy -0.03175 0.89916) (xy -0.0635 0.889) (xy -0.09144 0.87376) (xy -0.11684 0.85344)
						(xy -0.13716 0.82804) (xy -0.1524 0.8001) (xy -0.16256 0.76835) (xy -0.1651 0.7366) (xy -0.1651 0.19685)
						(xy -0.17272 0.18923) (xy -0.17907 0.18034) (xy -0.18669 0.17145) (xy -0.19177 0.16256) (xy -0.19812 0.15367)
						(xy -0.20828 0.13335) (xy -0.21971 0.10287) (xy -0.22225 0.09271) (xy -0.22479 0.08128) (xy -0.22606 0.07112)
						(xy -0.2286 0.05969) (xy -0.2286 0.01651) (xy -0.22606 0.00508) (xy -0.22479 -0.00508) (xy -0.22225 -0.01651)
						(xy -0.21971 -0.02667) (xy -0.20828 -0.05715) (xy -0.19812 -0.07747) (xy -0.19177 -0.08636) (xy -0.18669 -0.09525)
						(xy -0.17907 -0.10414) (xy -0.17272 -0.11303) (xy -0.1651 -0.12065) (xy -0.1651 -0.7366) (xy -0.16256 -0.76835)
						(xy -0.1524 -0.8001) (xy -0.13716 -0.82804) (xy -0.11684 -0.85344) (xy -0.09144 -0.87376) (xy -0.0635 -0.889)
						(xy -0.03175 -0.89916) (xy 0 -0.9017) (xy 0.03175 -0.89916) (xy 0.0635 -0.889) (xy 0.09144 -0.87376)
						(xy 0.11684 -0.85344) (xy 0.13716 -0.82804) (xy 0.1524 -0.8001) (xy 0.16256 -0.76835) (xy 0.1651 -0.7366)
						(xy 0.1651 -0.11938) (xy 0.17272 -0.11176) (xy 0.19812 -0.0762) (xy 0.2032 -0.06604) (xy 0.20701 -0.05715)
						(xy 0.21209 -0.04699) (xy 0.2159 -0.03683) (xy 0.21844 -0.02667) (xy 0.22225 -0.01524) (xy 0.22352 -0.00508)
						(xy 0.22606 0.00508) (xy 0.22733 0.01651) (xy 0.22733 0.02667) (xy 0.2286 0.0381) (xy 0.22733 0.04953)
						(xy 0.22733 0.05969) (xy 0.22606 0.07112) (xy 0.22352 0.08128) (xy 0.22225 0.09144) (xy 0.21844 0.10287)
						(xy 0.2159 0.11303) (xy 0.21209 0.12319) (xy 0.20701 0.13335) (xy 0.2032 0.14224) (xy 0.19812 0.1524)
						(xy 0.17272 0.18796) (xy 0.1651 0.19558) (xy 0.1651 0.7366) (xy 0.16256 0.76835) (xy 0.1524 0.8001)
						(xy 0.13716 0.82804) (xy 0.11684 0.85344) (xy 0.09144 0.87376) (xy 0.0635 0.889) (xy 0.03175 0.89916)
					)
					(width 0)
					(fill yes)
				)
			)
		)
		(pad "193" smd custom
			(at 28.349956 4.106672 180)
			(size 0.1143 0.1143)
			(layers "F.Cu" "F.Mask" "F.Paste")
			(net "M_A_DQ63")
			(options
				(clearance outline)
				(anchor circle)
			)
			(primitives
				(gr_poly
					(pts
						(xy 0 0.9017) (xy -0.03175 0.89916) (xy -0.0635 0.889) (xy -0.09144 0.87376) (xy -0.11684 0.85344)
						(xy -0.13716 0.82804) (xy -0.1524 0.8001) (xy -0.16256 0.76835) (xy -0.1651 0.7366) (xy -0.1651 -0.13462)
						(xy -0.17272 -0.14224) (xy -0.19812 -0.1778) (xy -0.2032 -0.18796) (xy -0.20701 -0.19685) (xy -0.21209 -0.20701)
						(xy -0.2159 -0.21717) (xy -0.21844 -0.22733) (xy -0.22225 -0.23876) (xy -0.22352 -0.24892) (xy -0.22606 -0.25908)
						(xy -0.22733 -0.27051) (xy -0.22733 -0.28067) (xy -0.2286 -0.2921) (xy -0.22733 -0.30353) (xy -0.22733 -0.31369)
						(xy -0.22606 -0.32512) (xy -0.22352 -0.33528) (xy -0.22225 -0.34544) (xy -0.21844 -0.35687) (xy -0.2159 -0.36703)
						(xy -0.21209 -0.37719) (xy -0.20701 -0.38735) (xy -0.2032 -0.39624) (xy -0.19812 -0.4064) (xy -0.17272 -0.44196)
						(xy -0.1651 -0.44958) (xy -0.1651 -0.7366) (xy -0.16256 -0.76835) (xy -0.1524 -0.8001) (xy -0.13716 -0.82804)
						(xy -0.11684 -0.85344) (xy -0.09144 -0.87376) (xy -0.0635 -0.889) (xy -0.03175 -0.89916) (xy 0 -0.9017)
						(xy 0.03175 -0.89916) (xy 0.0635 -0.889) (xy 0.09144 -0.87376) (xy 0.11684 -0.85344) (xy 0.13716 -0.82804)
						(xy 0.1524 -0.8001) (xy 0.16256 -0.76835) (xy 0.1651 -0.7366) (xy 0.1651 -0.44958) (xy 0.17272 -0.44196)
						(xy 0.19812 -0.4064) (xy 0.2032 -0.39624) (xy 0.20701 -0.38735) (xy 0.21209 -0.37719) (xy 0.2159 -0.36703)
						(xy 0.21844 -0.35687) (xy 0.22225 -0.34544) (xy 0.22352 -0.33528) (xy 0.22606 -0.32512) (xy 0.22733 -0.31369)
						(xy 0.22733 -0.30353) (xy 0.2286 -0.2921) (xy 0.22733 -0.28067) (xy 0.22733 -0.27051) (xy 0.22606 -0.25908)
						(xy 0.22352 -0.24892) (xy 0.22225 -0.23876) (xy 0.21844 -0.22733) (xy 0.2159 -0.21717) (xy 0.21209 -0.20701)
						(xy 0.20701 -0.19685) (xy 0.2032 -0.18796) (xy 0.19812 -0.1778) (xy 0.17272 -0.14224) (xy 0.1651 -0.13462)
						(xy 0.1651 0.7366) (xy 0.16256 0.76835) (xy 0.1524 0.8001) (xy 0.13716 0.82804) (xy 0.11684 0.85344)
						(xy 0.09144 0.87376) (xy 0.0635 0.889) (xy 0.03175 0.89916)
					)
					(width 0)
					(fill yes)
				)
			)
		)
		(pad "194" smd custom
			(at 28.64993 -4.106672 180)
			(size 0.1143 0.1143)
			(layers "F.Cu" "F.Mask" "F.Paste")
			(net "M_A_DQ59")
			(options
				(clearance outline)
				(anchor circle)
			)
			(primitives
				(gr_poly
					(pts
						(xy 0 0.9017) (xy -0.03175 0.89916) (xy -0.0635 0.889) (xy -0.09144 0.87376) (xy -0.11684 0.85344)
						(xy -0.13716 0.82804) (xy -0.1524 0.8001) (xy -0.16256 0.76835) (xy -0.1651 0.7366) (xy -0.1651 0.44958)
						(xy -0.17272 0.44196) (xy -0.19812 0.4064) (xy -0.2032 0.39624) (xy -0.20701 0.38735) (xy -0.21209 0.37719)
						(xy -0.2159 0.36703) (xy -0.21844 0.35687) (xy -0.22225 0.34544) (xy -0.22352 0.33528) (xy -0.22606 0.32512)
						(xy -0.22733 0.31369) (xy -0.22733 0.30353) (xy -0.2286 0.2921) (xy -0.22733 0.28067) (xy -0.22733 0.27051)
						(xy -0.22606 0.25908) (xy -0.22352 0.24892) (xy -0.22225 0.23876) (xy -0.21844 0.22733) (xy -0.2159 0.21717)
						(xy -0.21209 0.20701) (xy -0.20701 0.19685) (xy -0.2032 0.18796) (xy -0.19812 0.1778) (xy -0.17272 0.14224)
						(xy -0.1651 0.13462) (xy -0.1651 -0.7366) (xy -0.16256 -0.76835) (xy -0.1524 -0.8001) (xy -0.13716 -0.82804)
						(xy -0.11684 -0.85344) (xy -0.09144 -0.87376) (xy -0.0635 -0.889) (xy -0.03175 -0.89916) (xy 0 -0.9017)
						(xy 0.03175 -0.89916) (xy 0.0635 -0.889) (xy 0.09144 -0.87376) (xy 0.11684 -0.85344) (xy 0.13716 -0.82804)
						(xy 0.1524 -0.8001) (xy 0.16256 -0.76835) (xy 0.1651 -0.7366) (xy 0.1651 0.13462) (xy 0.17272 0.14224)
						(xy 0.19812 0.1778) (xy 0.2032 0.18796) (xy 0.20701 0.19685) (xy 0.21209 0.20701) (xy 0.2159 0.21717)
						(xy 0.21844 0.22733) (xy 0.22225 0.23876) (xy 0.22352 0.24892) (xy 0.22606 0.25908) (xy 0.22733 0.27051)
						(xy 0.22733 0.28067) (xy 0.2286 0.2921) (xy 0.22733 0.30353) (xy 0.22733 0.31369) (xy 0.22606 0.32512)
						(xy 0.22352 0.33528) (xy 0.22225 0.34544) (xy 0.21844 0.35687) (xy 0.2159 0.36703) (xy 0.21209 0.37719)
						(xy 0.20701 0.38735) (xy 0.2032 0.39624) (xy 0.19812 0.4064) (xy 0.17272 0.44196) (xy 0.1651 0.44958)
						(xy 0.1651 0.7366) (xy 0.16256 0.76835) (xy 0.1524 0.8001) (xy 0.13716 0.82804) (xy 0.11684 0.85344)
						(xy 0.09144 0.87376) (xy 0.0635 0.889) (xy 0.03175 0.89916)
					)
					(width 0)
					(fill yes)
				)
			)
		)
		(pad "195" smd custom
			(at 28.949904 4.106672 180)
			(size 0.1143 0.1143)
			(layers "F.Cu" "F.Mask" "F.Paste")
			(net "GND")
			(options
				(clearance outline)
				(anchor circle)
			)
			(primitives
				(gr_poly
					(pts
						(xy 0 0.9017) (xy -0.03175 0.89916) (xy -0.0635 0.889) (xy -0.09144 0.87376) (xy -0.11684 0.85344)
						(xy -0.13716 0.82804) (xy -0.1524 0.8001) (xy -0.16256 0.76835) (xy -0.1651 0.7366) (xy -0.1651 0.11938)
						(xy -0.17272 0.11176) (xy -0.19812 0.0762) (xy -0.2032 0.06604) (xy -0.20701 0.05715) (xy -0.21209 0.04699)
						(xy -0.2159 0.03683) (xy -0.21844 0.02667) (xy -0.22225 0.01524) (xy -0.22352 0.00508) (xy -0.22606 -0.00508)
						(xy -0.22733 -0.01651) (xy -0.22733 -0.02667) (xy -0.2286 -0.0381) (xy -0.22733 -0.04953) (xy -0.22733 -0.05969)
						(xy -0.22606 -0.07112) (xy -0.22352 -0.08128) (xy -0.22225 -0.09144) (xy -0.21844 -0.10287) (xy -0.2159 -0.11303)
						(xy -0.21209 -0.12319) (xy -0.20701 -0.13335) (xy -0.2032 -0.14224) (xy -0.19812 -0.1524) (xy -0.17272 -0.18796)
						(xy -0.1651 -0.19558) (xy -0.1651 -0.7366) (xy -0.16256 -0.76835) (xy -0.1524 -0.8001) (xy -0.13716 -0.82804)
						(xy -0.11684 -0.85344) (xy -0.09144 -0.87376) (xy -0.0635 -0.889) (xy -0.03175 -0.89916) (xy 0 -0.9017)
						(xy 0.03175 -0.89916) (xy 0.0635 -0.889) (xy 0.09144 -0.87376) (xy 0.11684 -0.85344) (xy 0.13716 -0.82804)
						(xy 0.1524 -0.8001) (xy 0.16256 -0.76835) (xy 0.1651 -0.7366) (xy 0.1651 -0.19685) (xy 0.17272 -0.18923)
						(xy 0.17907 -0.18034) (xy 0.18669 -0.17145) (xy 0.19177 -0.16256) (xy 0.19812 -0.15367) (xy 0.20828 -0.13335)
						(xy 0.21971 -0.10287) (xy 0.22225 -0.09271) (xy 0.22479 -0.08128) (xy 0.22606 -0.07112) (xy 0.2286 -0.05969)
						(xy 0.2286 -0.01651) (xy 0.22606 -0.00508) (xy 0.22479 0.00508) (xy 0.22225 0.01651) (xy 0.21971 0.02667)
						(xy 0.20828 0.05715) (xy 0.19812 0.07747) (xy 0.19177 0.08636) (xy 0.18669 0.09525) (xy 0.17907 0.10414)
						(xy 0.17272 0.11303) (xy 0.1651 0.12065) (xy 0.1651 0.7366) (xy 0.16256 0.76835) (xy 0.1524 0.8001)
						(xy 0.13716 0.82804) (xy 0.11684 0.85344) (xy 0.09144 0.87376) (xy 0.0635 0.889) (xy 0.03175 0.89916)
					)
					(width 0)
					(fill yes)
				)
			)
		)
		(pad "196" smd custom
			(at 29.249878 -4.106672 180)
			(size 0.1143 0.1143)
			(layers "F.Cu" "F.Mask" "F.Paste")
			(net "GND")
			(options
				(clearance outline)
				(anchor circle)
			)
			(primitives
				(gr_poly
					(pts
						(xy 0 0.9017) (xy -0.03175 0.89916) (xy -0.0635 0.889) (xy -0.09144 0.87376) (xy -0.11684 0.85344)
						(xy -0.13716 0.82804) (xy -0.1524 0.8001) (xy -0.16256 0.76835) (xy -0.1651 0.7366) (xy -0.1651 0.19685)
						(xy -0.17272 0.18923) (xy -0.17907 0.18034) (xy -0.18669 0.17145) (xy -0.19177 0.16256) (xy -0.19812 0.15367)
						(xy -0.20828 0.13335) (xy -0.21971 0.10287) (xy -0.22225 0.09271) (xy -0.22479 0.08128) (xy -0.22606 0.07112)
						(xy -0.2286 0.05969) (xy -0.2286 0.01651) (xy -0.22606 0.00508) (xy -0.22479 -0.00508) (xy -0.22225 -0.01651)
						(xy -0.21971 -0.02667) (xy -0.20828 -0.05715) (xy -0.19812 -0.07747) (xy -0.19177 -0.08636) (xy -0.18669 -0.09525)
						(xy -0.17907 -0.10414) (xy -0.17272 -0.11303) (xy -0.1651 -0.12065) (xy -0.1651 -0.7366) (xy -0.16256 -0.76835)
						(xy -0.1524 -0.8001) (xy -0.13716 -0.82804) (xy -0.11684 -0.85344) (xy -0.09144 -0.87376) (xy -0.0635 -0.889)
						(xy -0.03175 -0.89916) (xy 0 -0.9017) (xy 0.03175 -0.89916) (xy 0.0635 -0.889) (xy 0.09144 -0.87376)
						(xy 0.11684 -0.85344) (xy 0.13716 -0.82804) (xy 0.1524 -0.8001) (xy 0.16256 -0.76835) (xy 0.1651 -0.7366)
						(xy 0.1651 -0.11938) (xy 0.17272 -0.11176) (xy 0.19812 -0.0762) (xy 0.2032 -0.06604) (xy 0.20701 -0.05715)
						(xy 0.21209 -0.04699) (xy 0.2159 -0.03683) (xy 0.21844 -0.02667) (xy 0.22225 -0.01524) (xy 0.22352 -0.00508)
						(xy 0.22606 0.00508) (xy 0.22733 0.01651) (xy 0.22733 0.02667) (xy 0.2286 0.0381) (xy 0.22733 0.04953)
						(xy 0.22733 0.05969) (xy 0.22606 0.07112) (xy 0.22352 0.08128) (xy 0.22225 0.09144) (xy 0.21844 0.10287)
						(xy 0.2159 0.11303) (xy 0.21209 0.12319) (xy 0.20701 0.13335) (xy 0.2032 0.14224) (xy 0.19812 0.1524)
						(xy 0.17272 0.18796) (xy 0.1651 0.19558) (xy 0.1651 0.7366) (xy 0.16256 0.76835) (xy 0.1524 0.8001)
						(xy 0.13716 0.82804) (xy 0.11684 0.85344) (xy 0.09144 0.87376) (xy 0.0635 0.889) (xy 0.03175 0.89916)
					)
					(width 0)
					(fill yes)
				)
			)
		)
		(pad "197" smd custom
			(at 29.550106 4.106672 180)
			(size 0.1143 0.1143)
			(layers "F.Cu" "F.Mask" "F.Paste")
			(net "CHA_1_SA0")
			(options
				(clearance outline)
				(anchor circle)
			)
			(primitives
				(gr_poly
					(pts
						(xy 0 0.9017) (xy -0.03175 0.89916) (xy -0.0635 0.889) (xy -0.09144 0.87376) (xy -0.11684 0.85344)
						(xy -0.13716 0.82804) (xy -0.1524 0.8001) (xy -0.16256 0.76835) (xy -0.1651 0.7366) (xy -0.1651 -0.13462)
						(xy -0.17272 -0.14224) (xy -0.19812 -0.1778) (xy -0.2032 -0.18796) (xy -0.20701 -0.19685) (xy -0.21209 -0.20701)
						(xy -0.2159 -0.21717) (xy -0.21844 -0.22733) (xy -0.22225 -0.23876) (xy -0.22352 -0.24892) (xy -0.22606 -0.25908)
						(xy -0.22733 -0.27051) (xy -0.22733 -0.28067) (xy -0.2286 -0.2921) (xy -0.22733 -0.30353) (xy -0.22733 -0.31369)
						(xy -0.22606 -0.32512) (xy -0.22352 -0.33528) (xy -0.22225 -0.34544) (xy -0.21844 -0.35687) (xy -0.2159 -0.36703)
						(xy -0.21209 -0.37719) (xy -0.20701 -0.38735) (xy -0.2032 -0.39624) (xy -0.19812 -0.4064) (xy -0.17272 -0.44196)
						(xy -0.1651 -0.44958) (xy -0.1651 -0.7366) (xy -0.16256 -0.76835) (xy -0.1524 -0.8001) (xy -0.13716 -0.82804)
						(xy -0.11684 -0.85344) (xy -0.09144 -0.87376) (xy -0.0635 -0.889) (xy -0.03175 -0.89916) (xy 0 -0.9017)
						(xy 0.03175 -0.89916) (xy 0.0635 -0.889) (xy 0.09144 -0.87376) (xy 0.11684 -0.85344) (xy 0.13716 -0.82804)
						(xy 0.1524 -0.8001) (xy 0.16256 -0.76835) (xy 0.1651 -0.7366) (xy 0.1651 -0.44958) (xy 0.17272 -0.44196)
						(xy 0.19812 -0.4064) (xy 0.2032 -0.39624) (xy 0.20701 -0.38735) (xy 0.21209 -0.37719) (xy 0.2159 -0.36703)
						(xy 0.21844 -0.35687) (xy 0.22225 -0.34544) (xy 0.22352 -0.33528) (xy 0.22606 -0.32512) (xy 0.22733 -0.31369)
						(xy 0.22733 -0.30353) (xy 0.2286 -0.2921) (xy 0.22733 -0.28067) (xy 0.22733 -0.27051) (xy 0.22606 -0.25908)
						(xy 0.22352 -0.24892) (xy 0.22225 -0.23876) (xy 0.21844 -0.22733) (xy 0.2159 -0.21717) (xy 0.21209 -0.20701)
						(xy 0.20701 -0.19685) (xy 0.2032 -0.18796) (xy 0.19812 -0.1778) (xy 0.17272 -0.14224) (xy 0.1651 -0.13462)
						(xy 0.1651 0.7366) (xy 0.16256 0.76835) (xy 0.1524 0.8001) (xy 0.13716 0.82804) (xy 0.11684 0.85344)
						(xy 0.09144 0.87376) (xy 0.0635 0.889) (xy 0.03175 0.89916)
					)
					(width 0)
					(fill yes)
				)
			)
		)
		(pad "198" smd custom
			(at 29.85008 -4.106672 180)
			(size 0.1143 0.1143)
			(layers "F.Cu" "F.Mask" "F.Paste")
			(net "MEMORY_HOT_LV_R#")
			(options
				(clearance outline)
				(anchor circle)
			)
			(primitives
				(gr_poly
					(pts
						(xy 0 0.9017) (xy -0.03175 0.89916) (xy -0.0635 0.889) (xy -0.09144 0.87376) (xy -0.11684 0.85344)
						(xy -0.13716 0.82804) (xy -0.1524 0.8001) (xy -0.16256 0.76835) (xy -0.1651 0.7366) (xy -0.1651 0.44958)
						(xy -0.17272 0.44196) (xy -0.19812 0.4064) (xy -0.2032 0.39624) (xy -0.20701 0.38735) (xy -0.21209 0.37719)
						(xy -0.2159 0.36703) (xy -0.21844 0.35687) (xy -0.22225 0.34544) (xy -0.22352 0.33528) (xy -0.22606 0.32512)
						(xy -0.22733 0.31369) (xy -0.22733 0.30353) (xy -0.2286 0.2921) (xy -0.22733 0.28067) (xy -0.22733 0.27051)
						(xy -0.22606 0.25908) (xy -0.22352 0.24892) (xy -0.22225 0.23876) (xy -0.21844 0.22733) (xy -0.2159 0.21717)
						(xy -0.21209 0.20701) (xy -0.20701 0.19685) (xy -0.2032 0.18796) (xy -0.19812 0.1778) (xy -0.17272 0.14224)
						(xy -0.1651 0.13462) (xy -0.1651 -0.7366) (xy -0.16256 -0.76835) (xy -0.1524 -0.8001) (xy -0.13716 -0.82804)
						(xy -0.11684 -0.85344) (xy -0.09144 -0.87376) (xy -0.0635 -0.889) (xy -0.03175 -0.89916) (xy 0 -0.9017)
						(xy 0.03175 -0.89916) (xy 0.0635 -0.889) (xy 0.09144 -0.87376) (xy 0.11684 -0.85344) (xy 0.13716 -0.82804)
						(xy 0.1524 -0.8001) (xy 0.16256 -0.76835) (xy 0.1651 -0.7366) (xy 0.1651 0.13462) (xy 0.17272 0.14224)
						(xy 0.19812 0.1778) (xy 0.2032 0.18796) (xy 0.20701 0.19685) (xy 0.21209 0.20701) (xy 0.2159 0.21717)
						(xy 0.21844 0.22733) (xy 0.22225 0.23876) (xy 0.22352 0.24892) (xy 0.22606 0.25908) (xy 0.22733 0.27051)
						(xy 0.22733 0.28067) (xy 0.2286 0.2921) (xy 0.22733 0.30353) (xy 0.22733 0.31369) (xy 0.22606 0.32512)
						(xy 0.22352 0.33528) (xy 0.22225 0.34544) (xy 0.21844 0.35687) (xy 0.2159 0.36703) (xy 0.21209 0.37719)
						(xy 0.20701 0.38735) (xy 0.2032 0.39624) (xy 0.19812 0.4064) (xy 0.17272 0.44196) (xy 0.1651 0.44958)
						(xy 0.1651 0.7366) (xy 0.16256 0.76835) (xy 0.1524 0.8001) (xy 0.13716 0.82804) (xy 0.11684 0.85344)
						(xy 0.09144 0.87376) (xy 0.0635 0.889) (xy 0.03175 0.89916)
					)
					(width 0)
					(fill yes)
				)
			)
		)
		(pad "199" smd custom
			(at 30.150054 4.106672 180)
			(size 0.1143 0.1143)
			(layers "F.Cu" "F.Mask" "F.Paste")
			(net "P3V3_STBY")
			(options
				(clearance outline)
				(anchor circle)
			)
			(primitives
				(gr_poly
					(pts
						(xy 0 0.9017) (xy -0.03175 0.89916) (xy -0.0635 0.889) (xy -0.09144 0.87376) (xy -0.11684 0.85344)
						(xy -0.13716 0.82804) (xy -0.1524 0.8001) (xy -0.16256 0.76835) (xy -0.1651 0.7366) (xy -0.1651 0.11938)
						(xy -0.17272 0.11176) (xy -0.19812 0.0762) (xy -0.2032 0.06604) (xy -0.20701 0.05715) (xy -0.21209 0.04699)
						(xy -0.2159 0.03683) (xy -0.21844 0.02667) (xy -0.22225 0.01524) (xy -0.22352 0.00508) (xy -0.22606 -0.00508)
						(xy -0.22733 -0.01651) (xy -0.22733 -0.02667) (xy -0.2286 -0.0381) (xy -0.22733 -0.04953) (xy -0.22733 -0.05969)
						(xy -0.22606 -0.07112) (xy -0.22352 -0.08128) (xy -0.22225 -0.09144) (xy -0.21844 -0.10287) (xy -0.2159 -0.11303)
						(xy -0.21209 -0.12319) (xy -0.20701 -0.13335) (xy -0.2032 -0.14224) (xy -0.19812 -0.1524) (xy -0.17272 -0.18796)
						(xy -0.1651 -0.19558) (xy -0.1651 -0.7366) (xy -0.16256 -0.76835) (xy -0.1524 -0.8001) (xy -0.13716 -0.82804)
						(xy -0.11684 -0.85344) (xy -0.09144 -0.87376) (xy -0.0635 -0.889) (xy -0.03175 -0.89916) (xy 0 -0.9017)
						(xy 0.03175 -0.89916) (xy 0.0635 -0.889) (xy 0.09144 -0.87376) (xy 0.11684 -0.85344) (xy 0.13716 -0.82804)
						(xy 0.1524 -0.8001) (xy 0.16256 -0.76835) (xy 0.1651 -0.7366) (xy 0.1651 -0.19685) (xy 0.17272 -0.18923)
						(xy 0.17907 -0.18034) (xy 0.18669 -0.17145) (xy 0.19177 -0.16256) (xy 0.19812 -0.15367) (xy 0.20828 -0.13335)
						(xy 0.21971 -0.10287) (xy 0.22225 -0.09271) (xy 0.22479 -0.08128) (xy 0.22606 -0.07112) (xy 0.2286 -0.05969)
						(xy 0.2286 -0.01651) (xy 0.22606 -0.00508) (xy 0.22479 0.00508) (xy 0.22225 0.01651) (xy 0.21971 0.02667)
						(xy 0.20828 0.05715) (xy 0.19812 0.07747) (xy 0.19177 0.08636) (xy 0.18669 0.09525) (xy 0.17907 0.10414)
						(xy 0.17272 0.11303) (xy 0.1651 0.12065) (xy 0.1651 0.7366) (xy 0.16256 0.76835) (xy 0.1524 0.8001)
						(xy 0.13716 0.82804) (xy 0.11684 0.85344) (xy 0.09144 0.87376) (xy 0.0635 0.889) (xy 0.03175 0.89916)
					)
					(width 0)
					(fill yes)
				)
			)
		)
		(pad "200" smd custom
			(at 30.450028 -4.106672 180)
			(size 0.1143 0.1143)
			(layers "F.Cu" "F.Mask" "F.Paste")
			(net "SMB_M_A1_R_DATA")
			(options
				(clearance outline)
				(anchor circle)
			)
			(primitives
				(gr_poly
					(pts
						(xy 0 0.9017) (xy -0.03175 0.89916) (xy -0.0635 0.889) (xy -0.09144 0.87376) (xy -0.11684 0.85344)
						(xy -0.13716 0.82804) (xy -0.1524 0.8001) (xy -0.16256 0.76835) (xy -0.1651 0.7366) (xy -0.1651 0.19685)
						(xy -0.17272 0.18923) (xy -0.17907 0.18034) (xy -0.18669 0.17145) (xy -0.19177 0.16256) (xy -0.19812 0.15367)
						(xy -0.20828 0.13335) (xy -0.21971 0.10287) (xy -0.22225 0.09271) (xy -0.22479 0.08128) (xy -0.22606 0.07112)
						(xy -0.2286 0.05969) (xy -0.2286 0.01651) (xy -0.22606 0.00508) (xy -0.22479 -0.00508) (xy -0.22225 -0.01651)
						(xy -0.21971 -0.02667) (xy -0.20828 -0.05715) (xy -0.19812 -0.07747) (xy -0.19177 -0.08636) (xy -0.18669 -0.09525)
						(xy -0.17907 -0.10414) (xy -0.17272 -0.11303) (xy -0.1651 -0.12065) (xy -0.1651 -0.7366) (xy -0.16256 -0.76835)
						(xy -0.1524 -0.8001) (xy -0.13716 -0.82804) (xy -0.11684 -0.85344) (xy -0.09144 -0.87376) (xy -0.0635 -0.889)
						(xy -0.03175 -0.89916) (xy 0 -0.9017) (xy 0.03175 -0.89916) (xy 0.0635 -0.889) (xy 0.09144 -0.87376)
						(xy 0.11684 -0.85344) (xy 0.13716 -0.82804) (xy 0.1524 -0.8001) (xy 0.16256 -0.76835) (xy 0.1651 -0.7366)
						(xy 0.1651 -0.11938) (xy 0.17272 -0.11176) (xy 0.19812 -0.0762) (xy 0.2032 -0.06604) (xy 0.20701 -0.05715)
						(xy 0.21209 -0.04699) (xy 0.2159 -0.03683) (xy 0.21844 -0.02667) (xy 0.22225 -0.01524) (xy 0.22352 -0.00508)
						(xy 0.22606 0.00508) (xy 0.22733 0.01651) (xy 0.22733 0.02667) (xy 0.2286 0.0381) (xy 0.22733 0.04953)
						(xy 0.22733 0.05969) (xy 0.22606 0.07112) (xy 0.22352 0.08128) (xy 0.22225 0.09144) (xy 0.21844 0.10287)
						(xy 0.2159 0.11303) (xy 0.21209 0.12319) (xy 0.20701 0.13335) (xy 0.2032 0.14224) (xy 0.19812 0.1524)
						(xy 0.17272 0.18796) (xy 0.1651 0.19558) (xy 0.1651 0.7366) (xy 0.16256 0.76835) (xy 0.1524 0.8001)
						(xy 0.13716 0.82804) (xy 0.11684 0.85344) (xy 0.09144 0.87376) (xy 0.0635 0.889) (xy 0.03175 0.89916)
					)
					(width 0)
					(fill yes)
				)
			)
		)
		(pad "201" smd custom
			(at 30.750002 4.106672 180)
			(size 0.1143 0.1143)
			(layers "F.Cu" "F.Mask" "F.Paste")
			(net "CHA_1_SA1")
			(options
				(clearance outline)
				(anchor circle)
			)
			(primitives
				(gr_poly
					(pts
						(xy 0 0.9017) (xy -0.03175 0.89916) (xy -0.0635 0.889) (xy -0.09144 0.87376) (xy -0.11684 0.85344)
						(xy -0.13716 0.82804) (xy -0.1524 0.8001) (xy -0.16256 0.76835) (xy -0.1651 0.7366) (xy -0.1651 -0.13462)
						(xy -0.17272 -0.14224) (xy -0.19812 -0.1778) (xy -0.2032 -0.18796) (xy -0.20701 -0.19685) (xy -0.21209 -0.20701)
						(xy -0.2159 -0.21717) (xy -0.21844 -0.22733) (xy -0.22225 -0.23876) (xy -0.22352 -0.24892) (xy -0.22606 -0.25908)
						(xy -0.22733 -0.27051) (xy -0.22733 -0.28067) (xy -0.2286 -0.2921) (xy -0.22733 -0.30353) (xy -0.22733 -0.31369)
						(xy -0.22606 -0.32512) (xy -0.22352 -0.33528) (xy -0.22225 -0.34544) (xy -0.21844 -0.35687) (xy -0.2159 -0.36703)
						(xy -0.21209 -0.37719) (xy -0.20701 -0.38735) (xy -0.2032 -0.39624) (xy -0.19812 -0.4064) (xy -0.17272 -0.44196)
						(xy -0.1651 -0.44958) (xy -0.1651 -0.7366) (xy -0.16256 -0.76835) (xy -0.1524 -0.8001) (xy -0.13716 -0.82804)
						(xy -0.11684 -0.85344) (xy -0.09144 -0.87376) (xy -0.0635 -0.889) (xy -0.03175 -0.89916) (xy 0 -0.9017)
						(xy 0.03175 -0.89916) (xy 0.0635 -0.889) (xy 0.09144 -0.87376) (xy 0.11684 -0.85344) (xy 0.13716 -0.82804)
						(xy 0.1524 -0.8001) (xy 0.16256 -0.76835) (xy 0.1651 -0.7366) (xy 0.1651 -0.44958) (xy 0.17272 -0.44196)
						(xy 0.19812 -0.4064) (xy 0.2032 -0.39624) (xy 0.20701 -0.38735) (xy 0.21209 -0.37719) (xy 0.2159 -0.36703)
						(xy 0.21844 -0.35687) (xy 0.22225 -0.34544) (xy 0.22352 -0.33528) (xy 0.22606 -0.32512) (xy 0.22733 -0.31369)
						(xy 0.22733 -0.30353) (xy 0.2286 -0.2921) (xy 0.22733 -0.28067) (xy 0.22733 -0.27051) (xy 0.22606 -0.25908)
						(xy 0.22352 -0.24892) (xy 0.22225 -0.23876) (xy 0.21844 -0.22733) (xy 0.2159 -0.21717) (xy 0.21209 -0.20701)
						(xy 0.20701 -0.19685) (xy 0.2032 -0.18796) (xy 0.19812 -0.1778) (xy 0.17272 -0.14224) (xy 0.1651 -0.13462)
						(xy 0.1651 0.7366) (xy 0.16256 0.76835) (xy 0.1524 0.8001) (xy 0.13716 0.82804) (xy 0.11684 0.85344)
						(xy 0.09144 0.87376) (xy 0.0635 0.889) (xy 0.03175 0.89916)
					)
					(width 0)
					(fill yes)
				)
			)
		)
		(pad "202" smd custom
			(at 31.049976 -4.106672 180)
			(size 0.1143 0.1143)
			(layers "F.Cu" "F.Mask" "F.Paste")
			(net "SMB_M_A1_R_CLK")
			(options
				(clearance outline)
				(anchor circle)
			)
			(primitives
				(gr_poly
					(pts
						(xy 0 0.9017) (xy -0.03175 0.89916) (xy -0.0635 0.889) (xy -0.09144 0.87376) (xy -0.11684 0.85344)
						(xy -0.13716 0.82804) (xy -0.1524 0.8001) (xy -0.16256 0.76835) (xy -0.1651 0.7366) (xy -0.1651 0.44958)
						(xy -0.17272 0.44196) (xy -0.19812 0.4064) (xy -0.2032 0.39624) (xy -0.20701 0.38735) (xy -0.21209 0.37719)
						(xy -0.2159 0.36703) (xy -0.21844 0.35687) (xy -0.22225 0.34544) (xy -0.22352 0.33528) (xy -0.22606 0.32512)
						(xy -0.22733 0.31369) (xy -0.22733 0.30353) (xy -0.2286 0.2921) (xy -0.22733 0.28067) (xy -0.22733 0.27051)
						(xy -0.22606 0.25908) (xy -0.22352 0.24892) (xy -0.22225 0.23876) (xy -0.21844 0.22733) (xy -0.2159 0.21717)
						(xy -0.21209 0.20701) (xy -0.20701 0.19685) (xy -0.2032 0.18796) (xy -0.19812 0.1778) (xy -0.17272 0.14224)
						(xy -0.1651 0.13462) (xy -0.1651 -0.7366) (xy -0.16256 -0.76835) (xy -0.1524 -0.8001) (xy -0.13716 -0.82804)
						(xy -0.11684 -0.85344) (xy -0.09144 -0.87376) (xy -0.0635 -0.889) (xy -0.03175 -0.89916) (xy 0 -0.9017)
						(xy 0.03175 -0.89916) (xy 0.0635 -0.889) (xy 0.09144 -0.87376) (xy 0.11684 -0.85344) (xy 0.13716 -0.82804)
						(xy 0.1524 -0.8001) (xy 0.16256 -0.76835) (xy 0.1651 -0.7366) (xy 0.1651 0.13462) (xy 0.17272 0.14224)
						(xy 0.19812 0.1778) (xy 0.2032 0.18796) (xy 0.20701 0.19685) (xy 0.21209 0.20701) (xy 0.2159 0.21717)
						(xy 0.21844 0.22733) (xy 0.22225 0.23876) (xy 0.22352 0.24892) (xy 0.22606 0.25908) (xy 0.22733 0.27051)
						(xy 0.22733 0.28067) (xy 0.2286 0.2921) (xy 0.22733 0.30353) (xy 0.22733 0.31369) (xy 0.22606 0.32512)
						(xy 0.22352 0.33528) (xy 0.22225 0.34544) (xy 0.21844 0.35687) (xy 0.2159 0.36703) (xy 0.21209 0.37719)
						(xy 0.20701 0.38735) (xy 0.2032 0.39624) (xy 0.19812 0.4064) (xy 0.17272 0.44196) (xy 0.1651 0.44958)
						(xy 0.1651 0.7366) (xy 0.16256 0.76835) (xy 0.1524 0.8001) (xy 0.13716 0.82804) (xy 0.11684 0.85344)
						(xy 0.09144 0.87376) (xy 0.0635 0.889) (xy 0.03175 0.89916)
					)
					(width 0)
					(fill yes)
				)
			)
		)
		(pad "203" smd custom
			(at 31.34995 4.106672 180)
			(size 0.1143 0.1143)
			(layers "F.Cu" "F.Mask" "F.Paste")
			(net "PV_VTT_DDR_A")
			(options
				(clearance outline)
				(anchor circle)
			)
			(primitives
				(gr_poly
					(pts
						(xy 0 0.9017) (xy -0.03175 0.89916) (xy -0.0635 0.889) (xy -0.09144 0.87376) (xy -0.11684 0.85344)
						(xy -0.13716 0.82804) (xy -0.1524 0.8001) (xy -0.16256 0.76835) (xy -0.1651 0.7366) (xy -0.1651 0.11938)
						(xy -0.17272 0.11176) (xy -0.19812 0.0762) (xy -0.2032 0.06604) (xy -0.20701 0.05715) (xy -0.21209 0.04699)
						(xy -0.2159 0.03683) (xy -0.21844 0.02667) (xy -0.22225 0.01524) (xy -0.22352 0.00508) (xy -0.22606 -0.00508)
						(xy -0.22733 -0.01651) (xy -0.22733 -0.02667) (xy -0.2286 -0.0381) (xy -0.22733 -0.04953) (xy -0.22733 -0.05969)
						(xy -0.22606 -0.07112) (xy -0.22352 -0.08128) (xy -0.22225 -0.09144) (xy -0.21844 -0.10287) (xy -0.2159 -0.11303)
						(xy -0.21209 -0.12319) (xy -0.20701 -0.13335) (xy -0.2032 -0.14224) (xy -0.19812 -0.1524) (xy -0.17272 -0.18796)
						(xy -0.1651 -0.19558) (xy -0.1651 -0.7366) (xy -0.16256 -0.76835) (xy -0.1524 -0.8001) (xy -0.13716 -0.82804)
						(xy -0.11684 -0.85344) (xy -0.09144 -0.87376) (xy -0.0635 -0.889) (xy -0.03175 -0.89916) (xy 0 -0.9017)
						(xy 0.03175 -0.89916) (xy 0.0635 -0.889) (xy 0.09144 -0.87376) (xy 0.11684 -0.85344) (xy 0.13716 -0.82804)
						(xy 0.1524 -0.8001) (xy 0.16256 -0.76835) (xy 0.1651 -0.7366) (xy 0.1651 -0.19685) (xy 0.17272 -0.18923)
						(xy 0.17907 -0.18034) (xy 0.18669 -0.17145) (xy 0.19177 -0.16256) (xy 0.19812 -0.15367) (xy 0.20828 -0.13335)
						(xy 0.21971 -0.10287) (xy 0.22225 -0.09271) (xy 0.22479 -0.08128) (xy 0.22606 -0.07112) (xy 0.2286 -0.05969)
						(xy 0.2286 -0.01651) (xy 0.22606 -0.00508) (xy 0.22479 0.00508) (xy 0.22225 0.01651) (xy 0.21971 0.02667)
						(xy 0.20828 0.05715) (xy 0.19812 0.07747) (xy 0.19177 0.08636) (xy 0.18669 0.09525) (xy 0.17907 0.10414)
						(xy 0.17272 0.11303) (xy 0.1651 0.12065) (xy 0.1651 0.7366) (xy 0.16256 0.76835) (xy 0.1524 0.8001)
						(xy 0.13716 0.82804) (xy 0.11684 0.85344) (xy 0.09144 0.87376) (xy 0.0635 0.889) (xy 0.03175 0.89916)
					)
					(width 0)
					(fill yes)
				)
			)
		)
		(pad "204" smd custom
			(at 31.649924 -4.106672 180)
			(size 0.1143 0.1143)
			(layers "F.Cu" "F.Mask" "F.Paste")
			(net "PV_VTT_DDR_A")
			(options
				(clearance outline)
				(anchor circle)
			)
			(primitives
				(gr_poly
					(pts
						(xy 0 0.9017) (xy -0.03175 0.89916) (xy -0.0635 0.889) (xy -0.09144 0.87376) (xy -0.11684 0.85344)
						(xy -0.13716 0.82804) (xy -0.1524 0.8001) (xy -0.16256 0.76835) (xy -0.1651 0.7366) (xy -0.1651 0.19685)
						(xy -0.17272 0.18923) (xy -0.17907 0.18034) (xy -0.18669 0.17145) (xy -0.19177 0.16256) (xy -0.19812 0.15367)
						(xy -0.20828 0.13335) (xy -0.21971 0.10287) (xy -0.22225 0.09271) (xy -0.22479 0.08128) (xy -0.22606 0.07112)
						(xy -0.2286 0.05969) (xy -0.2286 0.01651) (xy -0.22606 0.00508) (xy -0.22479 -0.00508) (xy -0.22225 -0.01651)
						(xy -0.21971 -0.02667) (xy -0.20828 -0.05715) (xy -0.19812 -0.07747) (xy -0.19177 -0.08636) (xy -0.18669 -0.09525)
						(xy -0.17907 -0.10414) (xy -0.17272 -0.11303) (xy -0.1651 -0.12065) (xy -0.1651 -0.7366) (xy -0.16256 -0.76835)
						(xy -0.1524 -0.8001) (xy -0.13716 -0.82804) (xy -0.11684 -0.85344) (xy -0.09144 -0.87376) (xy -0.0635 -0.889)
						(xy -0.03175 -0.89916) (xy 0 -0.9017) (xy 0.03175 -0.89916) (xy 0.0635 -0.889) (xy 0.09144 -0.87376)
						(xy 0.11684 -0.85344) (xy 0.13716 -0.82804) (xy 0.1524 -0.8001) (xy 0.16256 -0.76835) (xy 0.1651 -0.7366)
						(xy 0.1651 -0.11938) (xy 0.17272 -0.11176) (xy 0.19812 -0.0762) (xy 0.2032 -0.06604) (xy 0.20701 -0.05715)
						(xy 0.21209 -0.04699) (xy 0.2159 -0.03683) (xy 0.21844 -0.02667) (xy 0.22225 -0.01524) (xy 0.22352 -0.00508)
						(xy 0.22606 0.00508) (xy 0.22733 0.01651) (xy 0.22733 0.02667) (xy 0.2286 0.0381) (xy 0.22733 0.04953)
						(xy 0.22733 0.05969) (xy 0.22606 0.07112) (xy 0.22352 0.08128) (xy 0.22225 0.09144) (xy 0.21844 0.10287)
						(xy 0.2159 0.11303) (xy 0.21209 0.12319) (xy 0.20701 0.13335) (xy 0.2032 0.14224) (xy 0.19812 0.1524)
						(xy 0.17272 0.18796) (xy 0.1651 0.19558) (xy 0.1651 0.7366) (xy 0.16256 0.76835) (xy 0.1524 0.8001)
						(xy 0.13716 0.82804) (xy 0.11684 0.85344) (xy 0.09144 0.87376) (xy 0.0635 0.889) (xy 0.03175 0.89916)
					)
					(width 0)
					(fill yes)
				)
			)
		)
		(pad "205" smd rect
			(at -37.349938 -11.299952 180)
			(size 4.699 6.8072)
			(layers "F.Cu" "F.Mask" "F.Paste")
			(net "GND")
		)
		(pad "206" smd rect
			(at 37.349938 -11.299952 180)
			(size 4.699 6.8072)
			(layers "F.Cu" "F.Mask" "F.Paste")
			(net "GND")
		)
		(pad "207" smd rect
			(at -32.800036 -11.999976 180)
			(size 3.5052 4.5974)
			(layers "F.Cu" "F.Mask" "F.Paste")
			(net "GND")
		)
		(pad "208" smd rect
			(at 32.800036 -11.999976 180)
			(size 3.5052 4.5974)
			(layers "F.Cu" "F.Mask" "F.Paste")
			(net "GND")
		)
		(zone
			(layer "F.Cu")
			(hatch none 0.5)
			(connect_pads
				(clearance 0)
			)
			(min_thickness 0.25)
			(keepout
				(tracks allowed)
				(vias not_allowed)
				(pads allowed)
				(copperpour not_allowed)
				(footprints allowed)
			)
			(placement
				(enabled no)
				(sheetname "")
			)
			(fill
				(thermal_gap 0.5)
				(thermal_bridge_width 0.5)
				(island_removal_mode 0)
			)
			(polygon
				(pts
					(xy 166.074598 -63.49492) (xy 126.625858 -63.49492) (xy 126.625858 -63.79972) (xy 166.074598 -63.79972)
				)
			)
		)
		(zone
			(layer "F.Cu")
			(hatch none 0.5)
			(connect_pads
				(clearance 0)
			)
			(min_thickness 0.25)
			(keepout
				(tracks allowed)
				(vias not_allowed)
				(pads allowed)
				(copperpour not_allowed)
				(footprints allowed)
			)
			(placement
				(enabled no)
				(sheetname "")
			)
			(fill
				(thermal_gap 0.5)
				(thermal_bridge_width 0.5)
				(island_removal_mode 0)
			)
			(polygon
				(pts
					(xy 166.419784 -69.600064) (xy 126.897384 -69.600064) (xy 126.897384 -69.904864) (xy 166.419784 -69.904864)
				)
			)
		)
		(zone
			(layer "F.Cu")
			(hatch none 0.5)
			(connect_pads
				(clearance 0)
			)
			(min_thickness 0.25)
			(keepout
				(tracks allowed)
				(vias not_allowed)
				(pads allowed)
				(copperpour not_allowed)
				(footprints allowed)
			)
			(placement
				(enabled no)
				(sheetname "")
			)
			(fill
				(thermal_gap 0.5)
				(thermal_bridge_width 0.5)
				(island_removal_mode 0)
			)
			(polygon
				(pts
					(xy 190.046864 -63.495428) (xy 168.647364 -63.495428) (xy 168.647364 -63.800228) (xy 190.046864 -63.800228)
				)
			)
		)
		(zone
			(layer "F.Cu")
			(hatch none 0.5)
			(connect_pads
				(clearance 0)
			)
			(min_thickness 0.25)
			(keepout
				(tracks allowed)
				(vias not_allowed)
				(pads allowed)
				(copperpour not_allowed)
				(footprints allowed)
			)
			(placement
				(enabled no)
				(sheetname "")
			)
			(fill
				(thermal_gap 0.5)
				(thermal_bridge_width 0.5)
				(island_removal_mode 0)
			)
			(polygon
				(pts
					(xy 190.392304 -69.599556) (xy 168.906444 -69.599556) (xy 168.906444 -69.904356) (xy 190.392304 -69.904356)
				)
			)
		)
		(zone
			(layers "F.Cu" "B.Cu" "In1.Cu" "In2.Cu" "In3.Cu" "In4.Cu" "In5.Cu" "In6.Cu"
				"In7.Cu" "In8.Cu" "In9.Cu" "In10.Cu"
			)
			(hatch none 0.5)
			(connect_pads
				(clearance 0)
			)
			(min_thickness 0.25)
			(keepout
				(tracks not_allowed)
				(vias allowed)
				(pads allowed)
				(copperpour not_allowed)
				(footprints allowed)
			)
			(placement
				(enabled no)
				(sheetname "")
			)
			(fill
				(thermal_gap 0.5)
				(thermal_bridge_width 0.5)
				(island_removal_mode 0)
			)
			(polygon
				(pts
					(arc
						(start 125.96368 -66.699892)
						(mid 124.23648 -66.699892)
						(end 125.96368 -66.699892)
					)
				)
			)
		)
		(zone
			(layers "F.Cu" "B.Cu" "In1.Cu" "In2.Cu" "In3.Cu" "In4.Cu" "In5.Cu" "In6.Cu"
				"In7.Cu" "In8.Cu" "In9.Cu" "In10.Cu"
			)
			(hatch none 0.5)
			(connect_pads
				(clearance 0)
			)
			(min_thickness 0.25)
			(keepout
				(tracks not_allowed)
				(vias allowed)
				(pads allowed)
				(copperpour not_allowed)
				(footprints allowed)
			)
			(placement
				(enabled no)
				(sheetname "")
			)
			(fill
				(thermal_gap 0.5)
				(thermal_bridge_width 0.5)
				(island_removal_mode 0)
			)
			(polygon
				(pts
					(arc
						(start 193.004948 -66.699892)
						(mid 190.795148 -66.699892)
						(end 193.004948 -66.699892)
					)
				)
			)
		)
	)
	(footprint ""
		(layer "F.Cu")
		(at 56.9722 -22.8346 90)
		(property "Reference" "C76"
			(at 0 0 90)
			(layer "F.SilkS")
			(hide yes)
			(effects
				(font
					(size 1.27 1.27)
				)
			)
		)
		(property "Value" "SC1U10V2KX-1GP"
			(at 1.1811 -2.7051 90)
			(unlocked yes)
			(layer "F.Fab")
			(hide yes)
			(effects
				(font
					(size 1.016 1.016)
					(thickness 0.1524)
				)
			)
		)
		(property "Device Type" "C402H22"
			(at 1.1811 -4.2291 90)
			(unlocked yes)
			(layer "F.Fab")
			(hide yes)
			(effects
				(font
					(size 1.016 1.016)
					(thickness 0.1524)
				)
			)
		)
		(duplicate_pad_numbers_are_jumpers no)
		(fp_rect
			(start -0.381 0.7366)
			(end 0.381 -0.7366)
			(stroke
				(width 0)
				(type default)
			)
			(fill no)
			(layer "F.CrtYd")
		)
		(fp_rect
			(start -0.381 0.7366)
			(end 0.381 -0.7366)
			(stroke
				(width 0)
				(type default)
			)
			(fill no)
			(layer "F.Fab")
		)
		(pad "1" smd custom
			(at 0 -0.4572 90)
			(size 0.1143 0.1143)
			(layers "F.Cu" "F.Mask" "F.Paste")
			(net "P3V3_CPU")
			(options
				(clearance outline)
				(anchor circle)
			)
			(primitives
				(gr_poly
					(pts
						(arc
							(start -0.254 -0.1778)
							(mid -0.239121 -0.213721)
							(end -0.2032 -0.2286)
						)
						(arc
							(start 0.2032 -0.2286)
							(mid 0.239121 -0.213721)
							(end 0.254 -0.1778)
						)
						(arc
							(start 0.254 0.1778)
							(mid 0.239121 0.213721)
							(end 0.2032 0.2286)
						)
						(arc
							(start -0.2032 0.2286)
							(mid -0.239121 0.213721)
							(end -0.254 0.1778)
						)
					)
					(width 0)
					(fill yes)
				)
			)
		)
		(pad "2" smd custom
			(at 0 0.4572 90)
			(size 0.1143 0.1143)
			(layers "F.Cu" "F.Mask" "F.Paste")
			(net "GND")
			(options
				(clearance outline)
				(anchor circle)
			)
			(primitives
				(gr_poly
					(pts
						(arc
							(start -0.254 -0.1778)
							(mid -0.239121 -0.213721)
							(end -0.2032 -0.2286)
						)
						(arc
							(start 0.2032 -0.2286)
							(mid 0.239121 -0.213721)
							(end 0.254 -0.1778)
						)
						(arc
							(start 0.254 0.1778)
							(mid 0.239121 0.213721)
							(end 0.2032 0.2286)
						)
						(arc
							(start -0.2032 0.2286)
							(mid -0.239121 0.213721)
							(end -0.254 0.1778)
						)
					)
					(width 0)
					(fill yes)
				)
			)
		)
	)
	(footprint ""
		(layer "F.Cu")
		(at 142.748 -34.544)
		(property "Reference" "U14"
			(at 0 0 0)
			(layer "F.SilkS")
			(hide yes)
			(effects
				(font
					(size 1.27 1.27)
				)
			)
		)
		(property "Value" "EP4CE6E22C8N-GP"
			(at 13.9065 9.4361 0)
			(unlocked yes)
			(layer "F.Fab")
			(hide yes)
			(effects
				(font
					(size 1.016 1.016)
					(thickness 0.1524)
				)
			)
		)
		(property "Device Type" "TQFP144-G6H65"
			(at 13.9065 7.9121 0)
			(unlocked yes)
			(layer "F.Fab")
			(hide yes)
			(effects
				(font
					(size 1.016 1.016)
					(thickness 0.1524)
				)
			)
		)
		(duplicate_pad_numbers_are_jumpers no)
		(fp_poly
			(pts
				(xy 8.750554 -11.380724) (xy 9.385554 -12.015724) (xy 8.115554 -12.015724)
			)
			(stroke
				(width 0)
				(type default)
			)
			(fill yes)
			(layer "F.SilkS")
		)
		(fp_poly
			(pts
				(xy -2.9972 -0.3302) (xy -0.3302 -0.3302) (xy -0.3302 -2.9972) (xy -2.9972 -2.9972)
			)
			(stroke
				(width 0)
				(type default)
			)
			(fill yes)
			(layer "F.Paste")
		)
		(fp_poly
			(pts
				(xy -2.9972 2.9972) (xy -0.3302 2.9972) (xy -0.3302 0.3302) (xy -2.9972 0.3302)
			)
			(stroke
				(width 0)
				(type default)
			)
			(fill yes)
			(layer "F.Paste")
		)
		(fp_poly
			(pts
				(xy 0.3302 -0.3302) (xy 2.9972 -0.3302) (xy 2.9972 -2.9972) (xy 0.3302 -2.9972)
			)
			(stroke
				(width 0)
				(type default)
			)
			(fill yes)
			(layer "F.Paste")
		)
		(fp_poly
			(pts
				(xy 0.3302 2.9972) (xy 2.9972 2.9972) (xy 2.9972 0.3302) (xy 0.3302 0.3302)
			)
			(stroke
				(width 0)
				(type default)
			)
			(fill yes)
			(layer "F.Paste")
		)
		(fp_rect
			(start -11.3792 11.3792)
			(end 11.3792 -11.3792)
			(stroke
				(width 0)
				(type default)
			)
			(fill no)
			(layer "F.CrtYd")
		)
		(fp_rect
			(start -11.3792 11.3792)
			(end 11.3792 -11.3792)
			(stroke
				(width 0)
				(type default)
			)
			(fill no)
			(layer "F.Fab")
		)
		(pad "1" smd rect
			(at 8.7503 -10.6172)
			(size 0.3048 1.27)
			(layers "F.Cu" "F.Mask" "F.Paste")
			(net "BMC_I2C_DATA")
		)
		(pad "2" smd rect
			(at 8.24992 -10.6172)
			(size 0.3048 1.27)
			(layers "F.Cu" "F.Mask" "F.Paste")
			(net "BMC_I2C_CLK")
		)
		(pad "3" smd rect
			(at 7.74954 -10.6172)
			(size 0.3048 1.27)
			(layers "F.Cu" "F.Mask" "F.Paste")
			(net "BMC_I2C_ALERT#")
		)
		(pad "4" smd rect
			(at 7.25043 -10.6172)
			(size 0.3048 1.27)
			(layers "F.Cu" "F.Mask" "F.Paste")
			(net "GND")
		)
		(pad "5" smd rect
			(at 6.75005 -10.6172)
			(size 0.3048 1.27)
			(layers "F.Cu" "F.Mask" "F.Paste")
			(net "P1V2_FPGA_D")
		)
		(pad "6" smd rect
			(at 6.24967 -10.6172)
			(size 0.3048 1.27)
			(layers "F.Cu" "F.Mask" "F.Paste")
			(net "FPGA_ASDO")
		)
		(pad "7" smd rect
			(at 5.75056 -10.6172)
			(size 0.3048 1.27)
			(layers "F.Cu" "F.Mask" "F.Paste")
			(net "Net_342")
		)
		(pad "8" smd rect
			(at 5.25018 -10.6172)
			(size 0.3048 1.27)
			(layers "F.Cu" "F.Mask" "F.Paste")
			(net "FPGA_CSO#")
		)
		(pad "9" smd rect
			(at 4.7498 -10.6172)
			(size 0.3048 1.27)
			(layers "F.Cu" "F.Mask" "F.Paste")
			(net "C_NSTATUS#")
		)
		(pad "10" smd rect
			(at 4.24942 -10.6172)
			(size 0.3048 1.27)
			(layers "F.Cu" "F.Mask" "F.Paste")
			(net "TEMP_1_ALERT#")
		)
		(pad "11" smd rect
			(at 3.75031 -10.6172)
			(size 0.3048 1.27)
			(layers "F.Cu" "F.Mask" "F.Paste")
			(net "Net_333")
		)
		(pad "12" smd rect
			(at 3.24993 -10.6172)
			(size 0.3048 1.27)
			(layers "F.Cu" "F.Mask" "F.Paste")
			(net "FPGA_DCLK")
		)
		(pad "13" smd rect
			(at 2.74955 -10.6172)
			(size 0.3048 1.27)
			(layers "F.Cu" "F.Mask" "F.Paste")
			(net "FPGA_DATA0")
		)
		(pad "14" smd rect
			(at 2.25044 -10.6172)
			(size 0.3048 1.27)
			(layers "F.Cu" "F.Mask" "F.Paste")
			(net "C_NCONFIG#")
		)
		(pad "15" smd rect
			(at 1.75006 -10.6172)
			(size 0.3048 1.27)
			(layers "F.Cu" "F.Mask" "F.Paste")
			(net "JTAG_PLD_TDI")
		)
		(pad "16" smd rect
			(at 1.24968 -10.6172)
			(size 0.3048 1.27)
			(layers "F.Cu" "F.Mask" "F.Paste")
			(net "JTAG_PLD_TCK")
		)
		(pad "17" smd rect
			(at 0.75057 -10.6172)
			(size 0.3048 1.27)
			(layers "F.Cu" "F.Mask" "F.Paste")
			(net "P3V3_STBY")
		)
		(pad "18" smd rect
			(at 0.25019 -10.6172)
			(size 0.3048 1.27)
			(layers "F.Cu" "F.Mask" "F.Paste")
			(net "JTAG_PLD_TMS")
		)
		(pad "19" smd rect
			(at -0.25019 -10.6172)
			(size 0.3048 1.27)
			(layers "F.Cu" "F.Mask" "F.Paste")
			(net "GND")
		)
		(pad "20" smd rect
			(at -0.75057 -10.6172)
			(size 0.3048 1.27)
			(layers "F.Cu" "F.Mask" "F.Paste")
			(net "JTAG_PLD_TDO")
		)
		(pad "21" smd rect
			(at -1.24968 -10.6172)
			(size 0.3048 1.27)
			(layers "F.Cu" "F.Mask" "F.Paste")
			(net "C_NCE#")
		)
		(pad "22" smd rect
			(at -1.75006 -10.6172)
			(size 0.3048 1.27)
			(layers "F.Cu" "F.Mask" "F.Paste")
			(net "GND")
		)
		(pad "23" smd rect
			(at -2.25044 -10.6172)
			(size 0.3048 1.27)
			(layers "F.Cu" "F.Mask" "F.Paste")
			(net "Net_340")
		)
		(pad "24" smd rect
			(at -2.74955 -10.6172)
			(size 0.3048 1.27)
			(layers "F.Cu" "F.Mask" "F.Paste")
			(net "FPGA_CLK_DP")
		)
		(pad "25" smd rect
			(at -3.24993 -10.6172)
			(size 0.3048 1.27)
			(layers "F.Cu" "F.Mask" "F.Paste")
			(net "Net_341")
		)
		(pad "26" smd rect
			(at -3.75031 -10.6172)
			(size 0.3048 1.27)
			(layers "F.Cu" "F.Mask" "F.Paste")
			(net "P3V3_STBY")
		)
		(pad "27" smd rect
			(at -4.24942 -10.6172)
			(size 0.3048 1.27)
			(layers "F.Cu" "F.Mask" "F.Paste")
			(net "GND")
		)
		(pad "28" smd rect
			(at -4.7498 -10.6172)
			(size 0.3048 1.27)
			(layers "F.Cu" "F.Mask" "F.Paste")
			(net "REV_CPU_FPGA_R_IO0")
		)
		(pad "29" smd rect
			(at -5.25018 -10.6172)
			(size 0.3048 1.27)
			(layers "F.Cu" "F.Mask" "F.Paste")
			(net "P1V2_FPGA_D")
		)
		(pad "30" smd rect
			(at -5.75056 -10.6172)
			(size 0.3048 1.27)
			(layers "F.Cu" "F.Mask" "F.Paste")
			(net "REV_CPU_FPGA_R_IO1")
		)
		(pad "31" smd rect
			(at -6.24967 -10.6172)
			(size 0.3048 1.27)
			(layers "F.Cu" "F.Mask" "F.Paste")
			(net "SLOT_ID3")
		)
		(pad "32" smd rect
			(at -6.75005 -10.6172)
			(size 0.3048 1.27)
			(layers "F.Cu" "F.Mask" "F.Paste")
			(net "SLOT_ID2")
		)
		(pad "33" smd rect
			(at -7.25043 -10.6172)
			(size 0.3048 1.27)
			(layers "F.Cu" "F.Mask" "F.Paste")
			(net "SLOT_ID1")
		)
		(pad "34" smd rect
			(at -7.74954 -10.6172)
			(size 0.3048 1.27)
			(layers "F.Cu" "F.Mask" "F.Paste")
			(net "SLOT_ID0")
		)
		(pad "35" smd rect
			(at -8.24992 -10.6172)
			(size 0.3048 1.27)
			(layers "F.Cu" "F.Mask" "F.Paste")
			(net "P2V5_STBY")
		)
		(pad "36" smd rect
			(at -8.7503 -10.6172)
			(size 0.3048 1.27)
			(layers "F.Cu" "F.Mask" "F.Paste")
			(net "GND")
		)
		(pad "37" smd rect
			(at -10.6172 -8.7503)
			(size 1.27 0.3048)
			(layers "F.Cu" "F.Mask" "F.Paste")
			(net "P1V2_FPGA_A")
		)
		(pad "38" smd rect
			(at -10.6172 -8.24992)
			(size 1.27 0.3048)
			(layers "F.Cu" "F.Mask" "F.Paste")
			(net "Net_348")
		)
		(pad "39" smd rect
			(at -10.6172 -7.74954)
			(size 1.27 0.3048)
			(layers "F.Cu" "F.Mask" "F.Paste")
			(net "Net_347")
		)
		(pad "40" smd rect
			(at -10.6172 -7.25043)
			(size 1.27 0.3048)
			(layers "F.Cu" "F.Mask" "F.Paste")
			(net "P3V3_STBY")
		)
		(pad "41" smd rect
			(at -10.6172 -6.75005)
			(size 1.27 0.3048)
			(layers "F.Cu" "F.Mask" "F.Paste")
			(net "GND")
		)
		(pad "42" smd rect
			(at -10.6172 -6.24967)
			(size 1.27 0.3048)
			(layers "F.Cu" "F.Mask" "F.Paste")
			(net "Net_332")
		)
		(pad "43" smd rect
			(at -10.6172 -5.75056)
			(size 1.27 0.3048)
			(layers "F.Cu" "F.Mask" "F.Paste")
			(net "LPC_CPU_CLKOUT0")
		)
		(pad "44" smd rect
			(at -10.6172 -5.25018)
			(size 1.27 0.3048)
			(layers "F.Cu" "F.Mask" "F.Paste")
			(net "Net_331")
		)
		(pad "45" smd rect
			(at -10.6172 -4.7498)
			(size 1.27 0.3048)
			(layers "F.Cu" "F.Mask" "F.Paste")
			(net "P1V2_FPGA_D")
		)
		(pad "46" smd rect
			(at -10.6172 -4.24942)
			(size 1.27 0.3048)
			(layers "F.Cu" "F.Mask" "F.Paste")
			(net "LPC_CPU_CLKRUN#")
		)
		(pad "47" smd rect
			(at -10.6172 -3.75031)
			(size 1.27 0.3048)
			(layers "F.Cu" "F.Mask" "F.Paste")
			(net "P3V3_STBY")
		)
		(pad "48" smd rect
			(at -10.6172 -3.24993)
			(size 1.27 0.3048)
			(layers "F.Cu" "F.Mask" "F.Paste")
			(net "GND")
		)
		(pad "49" smd rect
			(at -10.6172 -2.74955)
			(size 1.27 0.3048)
			(layers "F.Cu" "F.Mask" "F.Paste")
			(net "LPC_CPU_FRAME#")
		)
		(pad "50" smd rect
			(at -10.6172 -2.25044)
			(size 1.27 0.3048)
			(layers "F.Cu" "F.Mask" "F.Paste")
			(net "LPC_AD_3")
		)
		(pad "51" smd rect
			(at -10.6172 -1.75006)
			(size 1.27 0.3048)
			(layers "F.Cu" "F.Mask" "F.Paste")
			(net "LPC_AD_2")
		)
		(pad "52" smd rect
			(at -10.6172 -1.24968)
			(size 1.27 0.3048)
			(layers "F.Cu" "F.Mask" "F.Paste")
			(net "LPC_AD_1")
		)
		(pad "53" smd rect
			(at -10.6172 -0.75057)
			(size 1.27 0.3048)
			(layers "F.Cu" "F.Mask" "F.Paste")
			(net "LPC_AD_0")
		)
		(pad "54" smd rect
			(at -10.6172 -0.25019)
			(size 1.27 0.3048)
			(layers "F.Cu" "F.Mask" "F.Paste")
			(net "SMB_PECI_LV_DATA")
		)
		(pad "55" smd rect
			(at -10.6172 0.25019)
			(size 1.27 0.3048)
			(layers "F.Cu" "F.Mask" "F.Paste")
			(net "SMB_PECI_LV_CLK")
		)
		(pad "56" smd rect
			(at -10.6172 0.75057)
			(size 1.27 0.3048)
			(layers "F.Cu" "F.Mask" "F.Paste")
			(net "P3V3_STBY")
		)
		(pad "57" smd rect
			(at -10.6172 1.24968)
			(size 1.27 0.3048)
			(layers "F.Cu" "F.Mask" "F.Paste")
			(net "GND")
		)
		(pad "58" smd rect
			(at -10.6172 1.75006)
			(size 1.27 0.3048)
			(layers "F.Cu" "F.Mask" "F.Paste")
			(net "IRQ_CPU_LV_IERR#")
		)
		(pad "59" smd rect
			(at -10.6172 2.25044)
			(size 1.27 0.3048)
			(layers "F.Cu" "F.Mask" "F.Paste")
			(net "IRQ_CPU_SERIAL")
		)
		(pad "60" smd rect
			(at -10.6172 2.74955)
			(size 1.27 0.3048)
			(layers "F.Cu" "F.Mask" "F.Paste")
			(net "CPU_ERR_N0")
		)
		(pad "61" smd rect
			(at -10.6172 3.24993)
			(size 1.27 0.3048)
			(layers "F.Cu" "F.Mask" "F.Paste")
			(net "P1V2_FPGA_D")
		)
		(pad "62" smd rect
			(at -10.6172 3.75031)
			(size 1.27 0.3048)
			(layers "F.Cu" "F.Mask" "F.Paste")
			(net "P3V3_STBY")
		)
		(pad "63" smd rect
			(at -10.6172 4.24942)
			(size 1.27 0.3048)
			(layers "F.Cu" "F.Mask" "F.Paste")
			(net "GND")
		)
		(pad "64" smd rect
			(at -10.6172 4.7498)
			(size 1.27 0.3048)
			(layers "F.Cu" "F.Mask" "F.Paste")
			(net "CPU_ERR_N1")
		)
		(pad "65" smd rect
			(at -10.6172 5.25018)
			(size 1.27 0.3048)
			(layers "F.Cu" "F.Mask" "F.Paste")
			(net "CPU_ERR_N2")
		)
		(pad "66" smd rect
			(at -10.6172 5.75056)
			(size 1.27 0.3048)
			(layers "F.Cu" "F.Mask" "F.Paste")
			(net "IRQ_LV_MCERR#")
		)
		(pad "67" smd rect
			(at -10.6172 6.24967)
			(size 1.27 0.3048)
			(layers "F.Cu" "F.Mask" "F.Paste")
			(net "MEMORY_FPGA_HOT#")
		)
		(pad "68" smd rect
			(at -10.6172 6.75005)
			(size 1.27 0.3048)
			(layers "F.Cu" "F.Mask" "F.Paste")
			(net "IRQ_NMI")
		)
		(pad "69" smd rect
			(at -10.6172 7.25043)
			(size 1.27 0.3048)
			(layers "F.Cu" "F.Mask" "F.Paste")
			(net "PROCESSOR_HOT_LVC#")
		)
		(pad "70" smd rect
			(at -10.6172 7.74954)
			(size 1.27 0.3048)
			(layers "F.Cu" "F.Mask" "F.Paste")
			(net "PMU_SLP_R_S45#")
		)
		(pad "71" smd rect
			(at -10.6172 8.24992)
			(size 1.27 0.3048)
			(layers "F.Cu" "F.Mask" "F.Paste")
			(net "PMU_PLD_R_PLTRST#")
		)
		(pad "72" smd rect
			(at -10.6172 8.7503)
			(size 1.27 0.3048)
			(layers "F.Cu" "F.Mask" "F.Paste")
			(net "PVCCP_PVNN_VRHOT#")
		)
		(pad "73" smd rect
			(at -8.7503 10.6172)
			(size 0.3048 1.27)
			(layers "F.Cu" "F.Mask" "F.Paste")
			(net "CPU_THERMTRIP_LVC#")
		)
		(pad "74" smd rect
			(at -8.24992 10.6172)
			(size 0.3048 1.27)
			(layers "F.Cu" "F.Mask" "F.Paste")
			(net "BIOS_POST_COMPLETE_R")
		)
		(pad "75" smd rect
			(at -7.74954 10.6172)
			(size 0.3048 1.27)
			(layers "F.Cu" "F.Mask" "F.Paste")
			(net "POWER_GOOD_R")
		)
		(pad "76" smd rect
			(at -7.25043 10.6172)
			(size 0.3048 1.27)
			(layers "F.Cu" "F.Mask" "F.Paste")
			(net "POWER_CONTROL")
		)
		(pad "77" smd rect
			(at -6.75005 10.6172)
			(size 0.3048 1.27)
			(layers "F.Cu" "F.Mask" "F.Paste")
			(net "HOST_RSTBTN#")
		)
		(pad "78" smd rect
			(at -6.24967 10.6172)
			(size 0.3048 1.27)
			(layers "F.Cu" "F.Mask" "F.Paste")
			(net "P1V2_FPGA_D")
		)
		(pad "79" smd rect
			(at -5.75056 10.6172)
			(size 0.3048 1.27)
			(layers "F.Cu" "F.Mask" "F.Paste")
			(net "GND")
		)
		(pad "80" smd rect
			(at -5.25018 10.6172)
			(size 0.3048 1.27)
			(layers "F.Cu" "F.Mask" "F.Paste")
			(net "Net_343")
		)
		(pad "81" smd rect
			(at -4.7498 10.6172)
			(size 0.3048 1.27)
			(layers "F.Cu" "F.Mask" "F.Paste")
			(net "P3V3_STBY")
		)
		(pad "82" smd rect
			(at -4.24942 10.6172)
			(size 0.3048 1.27)
			(layers "F.Cu" "F.Mask" "F.Paste")
			(net "GND")
		)
		(pad "83" smd rect
			(at -3.75031 10.6172)
			(size 0.3048 1.27)
			(layers "F.Cu" "F.Mask" "F.Paste")
			(net "TP_FPGA_P84")
		)
		(pad "84" smd rect
			(at -3.24993 10.6172)
			(size 0.3048 1.27)
			(layers "F.Cu" "F.Mask" "F.Paste")
			(net "TP_FPGA_P85")
		)
		(pad "85" smd rect
			(at -2.74955 10.6172)
			(size 0.3048 1.27)
			(layers "F.Cu" "F.Mask" "F.Paste")
			(net "Net_346")
		)
		(pad "86" smd rect
			(at -2.25044 10.6172)
			(size 0.3048 1.27)
			(layers "F.Cu" "F.Mask" "F.Paste")
			(net "Net_339")
		)
		(pad "87" smd rect
			(at -1.75006 10.6172)
			(size 0.3048 1.27)
			(layers "F.Cu" "F.Mask" "F.Paste")
			(net "GND")
		)
		(pad "88" smd rect
			(at -1.24968 10.6172)
			(size 0.3048 1.27)
			(layers "F.Cu" "F.Mask" "F.Paste")
			(net "Net_97")
		)
		(pad "89" smd rect
			(at -0.75057 10.6172)
			(size 0.3048 1.27)
			(layers "F.Cu" "F.Mask" "F.Paste")
			(net "Net_98")
		)
		(pad "90" smd rect
			(at -0.25019 10.6172)
			(size 0.3048 1.27)
			(layers "F.Cu" "F.Mask" "F.Paste")
			(net "GND")
		)
		(pad "91" smd rect
			(at 0.25019 10.6172)
			(size 0.3048 1.27)
			(layers "F.Cu" "F.Mask" "F.Paste")
			(net "Net_336")
		)
		(pad "92" smd rect
			(at 0.75057 10.6172)
			(size 0.3048 1.27)
			(layers "F.Cu" "F.Mask" "F.Paste")
			(net "C_CONF_DONE")
		)
		(pad "93" smd rect
			(at 1.24968 10.6172)
			(size 0.3048 1.27)
			(layers "F.Cu" "F.Mask" "F.Paste")
			(net "P3V3_STBY")
		)
		(pad "94" smd rect
			(at 1.75006 10.6172)
			(size 0.3048 1.27)
			(layers "F.Cu" "F.Mask" "F.Paste")
			(net "MSEL0")
		)
		(pad "95" smd rect
			(at 2.25044 10.6172)
			(size 0.3048 1.27)
			(layers "F.Cu" "F.Mask" "F.Paste")
			(net "GND")
		)
		(pad "96" smd rect
			(at 2.74955 10.6172)
			(size 0.3048 1.27)
			(layers "F.Cu" "F.Mask" "F.Paste")
			(net "MSEL1")
		)
		(pad "97" smd rect
			(at 3.24993 10.6172)
			(size 0.3048 1.27)
			(layers "F.Cu" "F.Mask" "F.Paste")
			(net "MSEL2")
		)
		(pad "98" smd rect
			(at 3.75031 10.6172)
			(size 0.3048 1.27)
			(layers "F.Cu" "F.Mask" "F.Paste")
			(net "Net_338")
		)
		(pad "99" smd rect
			(at 4.24942 10.6172)
			(size 0.3048 1.27)
			(layers "F.Cu" "F.Mask" "F.Paste")
			(net "Net_337")
		)
		(pad "100" smd rect
			(at 4.7498 10.6172)
			(size 0.3048 1.27)
			(layers "F.Cu" "F.Mask" "F.Paste")
			(net "TP_FPGA_P100")
		)
		(pad "101" smd rect
			(at 5.25018 10.6172)
			(size 0.3048 1.27)
			(layers "F.Cu" "F.Mask" "F.Paste")
			(net "C_CEO#")
		)
		(pad "102" smd rect
			(at 5.75056 10.6172)
			(size 0.3048 1.27)
			(layers "F.Cu" "F.Mask" "F.Paste")
			(net "P1V2_FPGA_D")
		)
		(pad "103" smd rect
			(at 6.24967 10.6172)
			(size 0.3048 1.27)
			(layers "F.Cu" "F.Mask" "F.Paste")
			(net "Net_335")
		)
		(pad "104" smd rect
			(at 6.75005 10.6172)
			(size 0.3048 1.27)
			(layers "F.Cu" "F.Mask" "F.Paste")
			(net "Net_323")
		)
		(pad "105" smd rect
			(at 7.25043 10.6172)
			(size 0.3048 1.27)
			(layers "F.Cu" "F.Mask" "F.Paste")
			(net "Net_344")
		)
		(pad "106" smd rect
			(at 7.74954 10.6172)
			(size 0.3048 1.27)
			(layers "F.Cu" "F.Mask" "F.Paste")
			(net "Net_324")
		)
		(pad "107" smd rect
			(at 8.24992 10.6172)
			(size 0.3048 1.27)
			(layers "F.Cu" "F.Mask" "F.Paste")
			(net "P2V5_STBY")
		)
		(pad "108" smd rect
			(at 8.7503 10.6172)
			(size 0.3048 1.27)
			(layers "F.Cu" "F.Mask" "F.Paste")
			(net "GND")
		)
		(pad "109" smd rect
			(at 10.6172 8.7503)
			(size 1.27 0.3048)
			(layers "F.Cu" "F.Mask" "F.Paste")
			(net "P1V2_FPGA_A")
		)
		(pad "110" smd rect
			(at 10.6172 8.24992)
			(size 1.27 0.3048)
			(layers "F.Cu" "F.Mask" "F.Paste")
			(net "TP_FPGA_P110")
		)
		(pad "111" smd rect
			(at 10.6172 7.74954)
			(size 1.27 0.3048)
			(layers "F.Cu" "F.Mask" "F.Paste")
			(net "TP_FPGA_P111")
		)
		(pad "112" smd rect
			(at 10.6172 7.25043)
			(size 1.27 0.3048)
			(layers "F.Cu" "F.Mask" "F.Paste")
			(net "TP_FPGA_P112")
		)
		(pad "113" smd rect
			(at 10.6172 6.75005)
			(size 1.27 0.3048)
			(layers "F.Cu" "F.Mask" "F.Paste")
			(net "TP_FPGA_P113")
		)
		(pad "114" smd rect
			(at 10.6172 6.24967)
			(size 1.27 0.3048)
			(layers "F.Cu" "F.Mask" "F.Paste")
			(net "Net_326")
		)
		(pad "115" smd rect
			(at 10.6172 5.75056)
			(size 1.27 0.3048)
			(layers "F.Cu" "F.Mask" "F.Paste")
			(net "Net_325")
		)
		(pad "116" smd rect
			(at 10.6172 5.25018)
			(size 1.27 0.3048)
			(layers "F.Cu" "F.Mask" "F.Paste")
			(net "P1V2_FPGA_D")
		)
		(pad "117" smd rect
			(at 10.6172 4.7498)
			(size 1.27 0.3048)
			(layers "F.Cu" "F.Mask" "F.Paste")
			(net "P3V3_STBY")
		)
		(pad "118" smd rect
			(at 10.6172 4.24942)
			(size 1.27 0.3048)
			(layers "F.Cu" "F.Mask" "F.Paste")
			(net "GND")
		)
		(pad "119" smd rect
			(at 10.6172 3.75031)
			(size 1.27 0.3048)
			(layers "F.Cu" "F.Mask" "F.Paste")
			(net "Net_345")
		)
		(pad "120" smd rect
			(at 10.6172 3.24993)
			(size 1.27 0.3048)
			(layers "F.Cu" "F.Mask" "F.Paste")
			(net "FPGA_SMB_HOST_CLK")
		)
		(pad "121" smd rect
			(at 10.6172 2.74955)
			(size 1.27 0.3048)
			(layers "F.Cu" "F.Mask" "F.Paste")
			(net "FPGA_SMB_HOST_DATA")
		)
		(pad "122" smd rect
			(at 10.6172 2.25044)
			(size 1.27 0.3048)
			(layers "F.Cu" "F.Mask" "F.Paste")
			(net "P3V3_STBY")
		)
		(pad "123" smd rect
			(at 10.6172 1.75006)
			(size 1.27 0.3048)
			(layers "F.Cu" "F.Mask" "F.Paste")
			(net "GND")
		)
		(pad "124" smd rect
			(at 10.6172 1.24968)
			(size 1.27 0.3048)
			(layers "F.Cu" "F.Mask" "F.Paste")
			(net "Net_327")
		)
		(pad "125" smd rect
			(at 10.6172 0.75057)
			(size 1.27 0.3048)
			(layers "F.Cu" "F.Mask" "F.Paste")
			(net "READY_R#")
		)
		(pad "126" smd rect
			(at 10.6172 0.25019)
			(size 1.27 0.3048)
			(layers "F.Cu" "F.Mask" "F.Paste")
			(net "Net_329")
		)
		(pad "127" smd rect
			(at 10.6172 -0.25019)
			(size 1.27 0.3048)
			(layers "F.Cu" "F.Mask" "F.Paste")
			(net "Net_328")
		)
		(pad "128" smd rect
			(at 10.6172 -0.75057)
			(size 1.27 0.3048)
			(layers "F.Cu" "F.Mask" "F.Paste")
			(net "HEARTBEAT_LED")
		)
		(pad "129" smd rect
			(at 10.6172 -1.24968)
			(size 1.27 0.3048)
			(layers "F.Cu" "F.Mask" "F.Paste")
			(net "Net_330")
		)
		(pad "130" smd rect
			(at 10.6172 -1.75006)
			(size 1.27 0.3048)
			(layers "F.Cu" "F.Mask" "F.Paste")
			(net "P3V3_STBY")
		)
		(pad "131" smd rect
			(at 10.6172 -2.25044)
			(size 1.27 0.3048)
			(layers "F.Cu" "F.Mask" "F.Paste")
			(net "GND")
		)
		(pad "132" smd rect
			(at 10.6172 -2.74955)
			(size 1.27 0.3048)
			(layers "F.Cu" "F.Mask" "F.Paste")
			(net "Net_334")
		)
		(pad "133" smd rect
			(at 10.6172 -3.24993)
			(size 1.27 0.3048)
			(layers "F.Cu" "F.Mask" "F.Paste")
			(net "DISABLE")
		)
		(pad "134" smd rect
			(at 10.6172 -3.75031)
			(size 1.27 0.3048)
			(layers "F.Cu" "F.Mask" "F.Paste")
			(net "P1V2_FPGA_D")
		)
		(pad "135" smd rect
			(at 10.6172 -4.24942)
			(size 1.27 0.3048)
			(layers "F.Cu" "F.Mask" "F.Paste")
			(net "PORT80_BIT0")
		)
		(pad "136" smd rect
			(at 10.6172 -4.7498)
			(size 1.27 0.3048)
			(layers "F.Cu" "F.Mask" "F.Paste")
			(net "PORT80_BIT1")
		)
		(pad "137" smd rect
			(at 10.6172 -5.25018)
			(size 1.27 0.3048)
			(layers "F.Cu" "F.Mask" "F.Paste")
			(net "PORT80_BIT2")
		)
		(pad "138" smd rect
			(at 10.6172 -5.75056)
			(size 1.27 0.3048)
			(layers "F.Cu" "F.Mask" "F.Paste")
			(net "PORT80_BIT3")
		)
		(pad "139" smd rect
			(at 10.6172 -6.24967)
			(size 1.27 0.3048)
			(layers "F.Cu" "F.Mask" "F.Paste")
			(net "P3V3_STBY")
		)
		(pad "140" smd rect
			(at 10.6172 -6.75005)
			(size 1.27 0.3048)
			(layers "F.Cu" "F.Mask" "F.Paste")
			(net "GND")
		)
		(pad "141" smd rect
			(at 10.6172 -7.25043)
			(size 1.27 0.3048)
			(layers "F.Cu" "F.Mask" "F.Paste")
			(net "PORT80_BIT4")
		)
		(pad "142" smd rect
			(at 10.6172 -7.74954)
			(size 1.27 0.3048)
			(layers "F.Cu" "F.Mask" "F.Paste")
			(net "PORT80_BIT5")
		)
		(pad "143" smd rect
			(at 10.6172 -8.24992)
			(size 1.27 0.3048)
			(layers "F.Cu" "F.Mask" "F.Paste")
			(net "PORT80_BIT6")
		)
		(pad "144" smd rect
			(at 10.6172 -8.7503)
			(size 1.27 0.3048)
			(layers "F.Cu" "F.Mask" "F.Paste")
			(net "PORT80_BIT7")
		)
		(pad "145" smd rect
			(at 0 0)
			(size 5.9944 5.9944)
			(layers "F.Cu" "F.Mask" "F.Paste")
			(net "GND")
		)
	)
	(footprint ""
		(layer "F.Cu")
		(at 45.4152 -51.3334)
		(property "Reference" "C51"
			(at 0 0 0)
			(layer "F.SilkS")
			(hide yes)
			(effects
				(font
					(size 1.27 1.27)
				)
			)
		)
		(property "Value" "SCD1U10V2KX-5GP"
			(at 1.8923 -1.2065 0)
			(unlocked yes)
			(layer "F.Fab")
			(hide yes)
			(effects
				(font
					(size 1.016 1.016)
					(thickness 0.1524)
				)
			)
		)
		(property "Device Type" "C402H22"
			(at 1.8923 -2.7305 0)
			(unlocked yes)
			(layer "F.Fab")
			(hide yes)
			(effects
				(font
					(size 1.016 1.016)
					(thickness 0.1524)
				)
			)
		)
		(duplicate_pad_numbers_are_jumpers no)
		(fp_rect
			(start -0.381 0.7366)
			(end 0.381 -0.7366)
			(stroke
				(width 0)
				(type default)
			)
			(fill no)
			(layer "F.CrtYd")
		)
		(fp_rect
			(start -0.381 0.7366)
			(end 0.381 -0.7366)
			(stroke
				(width 0)
				(type default)
			)
			(fill no)
			(layer "F.Fab")
		)
		(pad "1" smd custom
			(at 0 -0.4572)
			(size 0.1143 0.1143)
			(layers "F.Cu" "F.Mask" "F.Paste")
			(net "P3V3_CLK_VDD25")
			(options
				(clearance outline)
				(anchor circle)
			)
			(primitives
				(gr_poly
					(pts
						(arc
							(start -0.254 -0.1778)
							(mid -0.239121 -0.213721)
							(end -0.2032 -0.2286)
						)
						(arc
							(start 0.2032 -0.2286)
							(mid 0.239121 -0.213721)
							(end 0.254 -0.1778)
						)
						(arc
							(start 0.254 0.1778)
							(mid 0.239121 0.213721)
							(end 0.2032 0.2286)
						)
						(arc
							(start -0.2032 0.2286)
							(mid -0.239121 0.213721)
							(end -0.254 0.1778)
						)
					)
					(width 0)
					(fill yes)
				)
			)
		)
		(pad "2" smd custom
			(at 0 0.4572)
			(size 0.1143 0.1143)
			(layers "F.Cu" "F.Mask" "F.Paste")
			(net "GND")
			(options
				(clearance outline)
				(anchor circle)
			)
			(primitives
				(gr_poly
					(pts
						(arc
							(start -0.254 -0.1778)
							(mid -0.239121 -0.213721)
							(end -0.2032 -0.2286)
						)
						(arc
							(start 0.2032 -0.2286)
							(mid 0.239121 -0.213721)
							(end 0.254 -0.1778)
						)
						(arc
							(start 0.254 0.1778)
							(mid 0.239121 0.213721)
							(end 0.2032 0.2286)
						)
						(arc
							(start -0.2032 0.2286)
							(mid -0.239121 0.213721)
							(end -0.254 0.1778)
						)
					)
					(width 0)
					(fill yes)
				)
			)
		)
	)
	(footprint ""
		(layer "F.Cu")
		(at 198.12 -5.588 -90)
		(property "Reference" "R390"
			(at 0 0 270)
			(layer "F.SilkS")
			(hide yes)
			(effects
				(font
					(size 1.27 1.27)
				)
			)
		)
		(property "Value" "4K7R2F-GP"
			(at 0.064008 -3.993896 270)
			(unlocked yes)
			(layer "F.Fab")
			(hide yes)
			(effects
				(font
					(size 1.016 1.016)
					(thickness 0.1524)
				)
			)
		)
		(property "Device Type" "R402H16"
			(at 0.064008 -5.517896 270)
			(unlocked yes)
			(layer "F.Fab")
			(hide yes)
			(effects
				(font
					(size 1.016 1.016)
					(thickness 0.1524)
				)
			)
		)
		(duplicate_pad_numbers_are_jumpers no)
		(fp_rect
			(start -0.381 0.8382)
			(end 0.381 -0.8382)
			(stroke
				(width 0)
				(type default)
			)
			(fill no)
			(layer "F.CrtYd")
		)
		(fp_rect
			(start -0.381 0.8382)
			(end 0.381 -0.8382)
			(stroke
				(width 0)
				(type default)
			)
			(fill no)
			(layer "F.Fab")
		)
		(pad "1" smd custom
			(at 0 -0.4318 270)
			(size 0.127 0.127)
			(layers "F.Cu" "F.Mask" "F.Paste")
			(net "P3V3_STBY")
			(options
				(clearance outline)
				(anchor circle)
			)
			(primitives
				(gr_poly
					(pts
						(arc
							(start -0.2032 -0.2794)
							(mid -0.239121 -0.264521)
							(end -0.254 -0.2286)
						)
						(arc
							(start -0.254 0.2286)
							(mid -0.239121 0.264521)
							(end -0.2032 0.2794)
						)
						(arc
							(start 0.2032 0.2794)
							(mid 0.239121 0.264521)
							(end 0.254 0.2286)
						)
						(arc
							(start 0.254 -0.2286)
							(mid 0.239121 -0.264521)
							(end 0.2032 -0.2794)
						)
					)
					(width 0)
					(fill yes)
				)
			)
		)
		(pad "2" smd custom
			(at 0 0.4318 270)
			(size 0.127 0.127)
			(layers "F.Cu" "F.Mask" "F.Paste")
			(net "CHB_1_SA1")
			(options
				(clearance outline)
				(anchor circle)
			)
			(primitives
				(gr_poly
					(pts
						(arc
							(start -0.2032 -0.2794)
							(mid -0.239121 -0.264521)
							(end -0.254 -0.2286)
						)
						(arc
							(start -0.254 0.2286)
							(mid -0.239121 0.264521)
							(end -0.2032 0.2794)
						)
						(arc
							(start 0.2032 0.2794)
							(mid 0.239121 0.264521)
							(end 0.254 0.2286)
						)
						(arc
							(start 0.254 -0.2286)
							(mid 0.239121 -0.264521)
							(end 0.2032 -0.2794)
						)
					)
					(width 0)
					(fill yes)
				)
			)
		)
	)
	(footprint ""
		(layer "F.Cu")
		(at 60.9854 -29.0322 90)
		(property "Reference" "Q8"
			(at 0 0 90)
			(layer "F.SilkS")
			(hide yes)
			(effects
				(font
					(size 1.27 1.27)
				)
			)
		)
		(property "Value" "FDN359BN-GP-U"
			(at -3.175 0.254 90)
			(unlocked yes)
			(layer "F.Fab")
			(hide yes)
			(effects
				(font
					(size 1.016 1.016)
					(thickness 0.1524)
				)
			)
		)
		(property "Device Type" "SOT23DGS2D6H45"
			(at -3.175 -1.27 90)
			(unlocked yes)
			(layer "F.Fab")
			(hide yes)
			(effects
				(font
					(size 1.016 1.016)
					(thickness 0.1524)
				)
			)
		)
		(duplicate_pad_numbers_are_jumpers no)
		(fp_line
			(start 1.7145 -0.2794)
			(end -1.7145 -0.2794)
			(stroke
				(width 0.1524)
				(type default)
			)
			(layer "F.SilkS")
		)
		(fp_line
			(start -1.7145 -0.2794)
			(end -1.7145 0.2794)
			(stroke
				(width 0.1524)
				(type default)
			)
			(layer "F.SilkS")
		)
		(fp_line
			(start 1.7145 0.2794)
			(end 1.7145 -0.2794)
			(stroke
				(width 0.1524)
				(type default)
			)
			(layer "F.SilkS")
		)
		(fp_line
			(start -1.7145 0.2794)
			(end 1.7145 0.2794)
			(stroke
				(width 0.1524)
				(type default)
			)
			(layer "F.SilkS")
		)
		(fp_rect
			(start -1.7145 1.651)
			(end 1.7145 -1.651)
			(stroke
				(width 0)
				(type default)
			)
			(fill no)
			(layer "F.CrtYd")
		)
		(fp_rect
			(start -1.7145 1.651)
			(end 1.7145 -1.651)
			(stroke
				(width 0)
				(type default)
			)
			(fill no)
			(layer "F.Fab")
		)
		(pad "D" smd custom
			(at 0 -1.016 90)
			(size 0.1651 0.1651)
			(layers "F.Cu" "F.Mask" "F.Paste")
			(net "P1V8_STBY")
			(options
				(clearance outline)
				(anchor circle)
			)
			(primitives
				(gr_poly
					(pts
						(arc
							(start -0.127 0.508)
							(mid -0.270684 0.448484)
							(end -0.3302 0.3048)
						)
						(arc
							(start -0.3302 -0.3048)
							(mid -0.270684 -0.448484)
							(end -0.127 -0.508)
						)
						(arc
							(start 0.127 -0.508)
							(mid 0.270684 -0.448484)
							(end 0.3302 -0.3048)
						)
						(arc
							(start 0.3302 0.3048)
							(mid 0.270684 0.448484)
							(end 0.127 0.508)
						)
					)
					(width 0)
					(fill yes)
				)
			)
		)
		(pad "G" smd custom
			(at -0.94996 1.016 90)
			(size 0.1651 0.1651)
			(layers "F.Cu" "F.Mask" "F.Paste")
			(net "SW_P1V8_EN_LV")
			(options
				(clearance outline)
				(anchor circle)
			)
			(primitives
				(gr_poly
					(pts
						(arc
							(start -0.127 0.508)
							(mid -0.270684 0.448484)
							(end -0.3302 0.3048)
						)
						(arc
							(start -0.3302 -0.3048)
							(mid -0.270684 -0.448484)
							(end -0.127 -0.508)
						)
						(arc
							(start 0.127 -0.508)
							(mid 0.270684 -0.448484)
							(end 0.3302 -0.3048)
						)
						(arc
							(start 0.3302 0.3048)
							(mid 0.270684 0.448484)
							(end 0.127 0.508)
						)
					)
					(width 0)
					(fill yes)
				)
			)
		)
		(pad "S" smd custom
			(at 0.94996 1.016 90)
			(size 0.1651 0.1651)
			(layers "F.Cu" "F.Mask" "F.Paste")
			(net "P1V8")
			(options
				(clearance outline)
				(anchor circle)
			)
			(primitives
				(gr_poly
					(pts
						(arc
							(start -0.127 0.508)
							(mid -0.270684 0.448484)
							(end -0.3302 0.3048)
						)
						(arc
							(start -0.3302 -0.3048)
							(mid -0.270684 -0.448484)
							(end -0.127 -0.508)
						)
						(arc
							(start 0.127 -0.508)
							(mid 0.270684 -0.448484)
							(end 0.3302 -0.3048)
						)
						(arc
							(start 0.3302 0.3048)
							(mid 0.270684 0.448484)
							(end 0.127 0.508)
						)
					)
					(width 0)
					(fill yes)
				)
			)
		)
	)
	(footprint ""
		(layer "F.Cu")
		(at 140.843 -59.944 90)
		(property "Reference" "PC40"
			(at 0 0 90)
			(layer "F.SilkS")
			(hide yes)
			(effects
				(font
					(size 1.27 1.27)
				)
			)
		)
		(property "Value" "SC4D7U10V3KX-GP"
			(at 0 -2.8194 90)
			(unlocked yes)
			(layer "F.Fab")
			(hide yes)
			(effects
				(font
					(size 1.016 1.016)
					(thickness 0.1524)
				)
			)
		)
		(property "Device Type" "C603H36"
			(at 0 -4.3434 90)
			(unlocked yes)
			(layer "F.Fab")
			(hide yes)
			(effects
				(font
					(size 1.016 1.016)
					(thickness 0.1524)
				)
			)
		)
		(duplicate_pad_numbers_are_jumpers no)
		(fp_line
			(start -0.4064 0)
			(end 0.4064 0)
			(stroke
				(width 0.2286)
				(type default)
			)
			(layer "F.SilkS")
		)
		(fp_rect
			(start -0.635 1.1811)
			(end 0.635 -1.1811)
			(stroke
				(width 0)
				(type default)
			)
			(fill no)
			(layer "F.CrtYd")
		)
		(fp_rect
			(start -0.635 1.1811)
			(end 0.635 -1.1811)
			(stroke
				(width 0)
				(type default)
			)
			(fill no)
			(layer "F.Fab")
		)
		(pad "1" smd custom
			(at 0 -0.6604 90)
			(size 0.19685 0.19685)
			(layers "F.Cu" "F.Mask" "F.Paste")
			(net "PV_VTT_DDR_VIN")
			(options
				(clearance outline)
				(anchor circle)
			)
			(primitives
				(gr_poly
					(pts
						(arc
							(start 0.508 -0.2921)
							(mid 0.478242 -0.363942)
							(end 0.4064 -0.3937)
						)
						(arc
							(start -0.4064 -0.3937)
							(mid -0.478242 -0.363942)
							(end -0.508 -0.2921)
						)
						(arc
							(start -0.508 0.2921)
							(mid -0.478242 0.363942)
							(end -0.4064 0.3937)
						)
						(arc
							(start 0.4064 0.3937)
							(mid 0.478242 0.363942)
							(end 0.508 0.2921)
						)
					)
					(width 0)
					(fill yes)
				)
			)
		)
		(pad "2" smd custom
			(at 0 0.6604 90)
			(size 0.19685 0.19685)
			(layers "F.Cu" "F.Mask" "F.Paste")
			(net "GND")
			(options
				(clearance outline)
				(anchor circle)
			)
			(primitives
				(gr_poly
					(pts
						(arc
							(start 0.508 -0.2921)
							(mid 0.478242 -0.363942)
							(end 0.4064 -0.3937)
						)
						(arc
							(start -0.4064 -0.3937)
							(mid -0.478242 -0.363942)
							(end -0.508 -0.2921)
						)
						(arc
							(start -0.508 0.2921)
							(mid -0.478242 0.363942)
							(end -0.4064 0.3937)
						)
						(arc
							(start 0.4064 0.3937)
							(mid 0.478242 0.363942)
							(end 0.508 0.2921)
						)
					)
					(width 0)
					(fill yes)
				)
			)
		)
	)
	(footprint ""
		(layer "F.Cu")
		(at 189.611 -39.497 90)
		(property "Reference" "PC87"
			(at 0 0 90)
			(layer "F.SilkS")
			(hide yes)
			(effects
				(font
					(size 1.27 1.27)
				)
			)
		)
		(property "Value" "SC1000P50V-N8-GP"
			(at 1.8923 -1.2065 90)
			(unlocked yes)
			(layer "F.Fab")
			(hide yes)
			(effects
				(font
					(size 1.016 1.016)
					(thickness 0.1524)
				)
			)
		)
		(property "Device Type" "C402H22"
			(at 1.8923 -2.7305 90)
			(unlocked yes)
			(layer "F.Fab")
			(hide yes)
			(effects
				(font
					(size 1.016 1.016)
					(thickness 0.1524)
				)
			)
		)
		(duplicate_pad_numbers_are_jumpers no)
		(fp_rect
			(start -0.381 0.7366)
			(end 0.381 -0.7366)
			(stroke
				(width 0)
				(type default)
			)
			(fill no)
			(layer "F.CrtYd")
		)
		(fp_rect
			(start -0.381 0.7366)
			(end 0.381 -0.7366)
			(stroke
				(width 0)
				(type default)
			)
			(fill no)
			(layer "F.Fab")
		)
		(pad "1" smd custom
			(at 0 -0.4572 90)
			(size 0.1143 0.1143)
			(layers "F.Cu" "F.Mask" "F.Paste")
			(net "VR_PVDDR_A_VAUTO")
			(options
				(clearance outline)
				(anchor circle)
			)
			(primitives
				(gr_poly
					(pts
						(arc
							(start -0.254 -0.1778)
							(mid -0.239121 -0.213721)
							(end -0.2032 -0.2286)
						)
						(arc
							(start 0.2032 -0.2286)
							(mid 0.239121 -0.213721)
							(end 0.254 -0.1778)
						)
						(arc
							(start 0.254 0.1778)
							(mid 0.239121 0.213721)
							(end 0.2032 0.2286)
						)
						(arc
							(start -0.2032 0.2286)
							(mid -0.239121 0.213721)
							(end -0.254 0.1778)
						)
					)
					(width 0)
					(fill yes)
				)
			)
		)
		(pad "2" smd custom
			(at 0 0.4572 90)
			(size 0.1143 0.1143)
			(layers "F.Cu" "F.Mask" "F.Paste")
			(net "GND")
			(options
				(clearance outline)
				(anchor circle)
			)
			(primitives
				(gr_poly
					(pts
						(arc
							(start -0.254 -0.1778)
							(mid -0.239121 -0.213721)
							(end -0.2032 -0.2286)
						)
						(arc
							(start 0.2032 -0.2286)
							(mid 0.239121 -0.213721)
							(end 0.254 -0.1778)
						)
						(arc
							(start 0.254 0.1778)
							(mid 0.239121 0.213721)
							(end 0.2032 0.2286)
						)
						(arc
							(start -0.2032 0.2286)
							(mid -0.239121 0.213721)
							(end -0.254 0.1778)
						)
					)
					(width 0)
					(fill yes)
				)
			)
		)
	)
	(footprint ""
		(layer "F.Cu")
		(at 49.085754 -53.3781 -90)
		(property "Reference" "L12"
			(at 0 0 270)
			(layer "F.SilkS")
			(hide yes)
			(effects
				(font
					(size 1.27 1.27)
				)
			)
		)
		(property "Value" "BLM18PG330SN1D-GP"
			(at -0.0254 -2.0193 270)
			(unlocked yes)
			(layer "F.Fab")
			(hide yes)
			(effects
				(font
					(size 1.016 1.016)
					(thickness 0.1524)
				)
			)
		)
		(property "Device Type" "L1608-UH38"
			(at -0.0254 -3.5433 270)
			(unlocked yes)
			(layer "F.Fab")
			(hide yes)
			(effects
				(font
					(size 1.016 1.016)
					(thickness 0.1524)
				)
			)
		)
		(duplicate_pad_numbers_are_jumpers no)
		(fp_line
			(start -0.4064 0)
			(end 0.4064 0)
			(stroke
				(width 0.2032)
				(type default)
			)
			(layer "F.SilkS")
		)
		(fp_rect
			(start -0.635 1.1811)
			(end 0.635 -1.1811)
			(stroke
				(width 0)
				(type default)
			)
			(fill no)
			(layer "F.CrtYd")
		)
		(fp_rect
			(start -0.635 1.1811)
			(end 0.635 -1.1811)
			(stroke
				(width 0)
				(type default)
			)
			(fill no)
			(layer "F.Fab")
		)
		(pad "1" smd custom
			(at 0 -0.6604 270)
			(size 0.19685 0.19685)
			(layers "F.Cu" "F.Mask" "F.Paste")
			(net "P1V5_STBY")
			(options
				(clearance outline)
				(anchor circle)
			)
			(primitives
				(gr_poly
					(pts
						(arc
							(start 0.508 -0.2921)
							(mid 0.478242 -0.363942)
							(end 0.4064 -0.3937)
						)
						(arc
							(start -0.4064 -0.3937)
							(mid -0.478242 -0.363942)
							(end -0.508 -0.2921)
						)
						(arc
							(start -0.508 0.2921)
							(mid -0.478242 0.363942)
							(end -0.4064 0.3937)
						)
						(arc
							(start 0.4064 0.3937)
							(mid 0.478242 0.363942)
							(end 0.508 0.2921)
						)
					)
					(width 0)
					(fill yes)
				)
			)
		)
		(pad "2" smd custom
			(at 0 0.6604 270)
			(size 0.19685 0.19685)
			(layers "F.Cu" "F.Mask" "F.Paste")
			(net "P1V5_CLK_VDD_CORE")
			(options
				(clearance outline)
				(anchor circle)
			)
			(primitives
				(gr_poly
					(pts
						(arc
							(start 0.508 -0.2921)
							(mid 0.478242 -0.363942)
							(end 0.4064 -0.3937)
						)
						(arc
							(start -0.4064 -0.3937)
							(mid -0.478242 -0.363942)
							(end -0.508 -0.2921)
						)
						(arc
							(start -0.508 0.2921)
							(mid -0.478242 0.363942)
							(end -0.4064 0.3937)
						)
						(arc
							(start 0.4064 0.3937)
							(mid 0.478242 0.363942)
							(end 0.508 0.2921)
						)
					)
					(width 0)
					(fill yes)
				)
			)
		)
	)
	(footprint ""
		(layer "F.Cu")
		(at 187.579 -45.974)
		(property "Reference" "R221"
			(at 0 0 0)
			(layer "F.SilkS")
			(hide yes)
			(effects
				(font
					(size 1.27 1.27)
				)
			)
		)
		(property "Value" "2D2R2J-GP"
			(at 0.064008 -3.993896 0)
			(unlocked yes)
			(layer "F.Fab")
			(hide yes)
			(effects
				(font
					(size 1.016 1.016)
					(thickness 0.1524)
				)
			)
		)
		(property "Device Type" "R402H16"
			(at 0.064008 -5.517896 0)
			(unlocked yes)
			(layer "F.Fab")
			(hide yes)
			(effects
				(font
					(size 1.016 1.016)
					(thickness 0.1524)
				)
			)
		)
		(duplicate_pad_numbers_are_jumpers no)
		(fp_rect
			(start -0.381 0.8382)
			(end 0.381 -0.8382)
			(stroke
				(width 0)
				(type default)
			)
			(fill no)
			(layer "F.CrtYd")
		)
		(fp_rect
			(start -0.381 0.8382)
			(end 0.381 -0.8382)
			(stroke
				(width 0)
				(type default)
			)
			(fill no)
			(layer "F.Fab")
		)
		(pad "1" smd custom
			(at 0 -0.4318)
			(size 0.127 0.127)
			(layers "F.Cu" "F.Mask" "F.Paste")
			(net "PV_VDDR_VREF_B_FB")
			(options
				(clearance outline)
				(anchor circle)
			)
			(primitives
				(gr_poly
					(pts
						(arc
							(start -0.2032 -0.2794)
							(mid -0.239121 -0.264521)
							(end -0.254 -0.2286)
						)
						(arc
							(start -0.254 0.2286)
							(mid -0.239121 0.264521)
							(end -0.2032 0.2794)
						)
						(arc
							(start 0.2032 0.2794)
							(mid 0.239121 0.264521)
							(end 0.254 0.2286)
						)
						(arc
							(start 0.254 -0.2286)
							(mid 0.239121 -0.264521)
							(end 0.2032 -0.2794)
						)
					)
					(width 0)
					(fill yes)
				)
			)
		)
		(pad "2" smd custom
			(at 0 0.4318)
			(size 0.127 0.127)
			(layers "F.Cu" "F.Mask" "F.Paste")
			(net "PV_VDDR_VREF_B")
			(options
				(clearance outline)
				(anchor circle)
			)
			(primitives
				(gr_poly
					(pts
						(arc
							(start -0.2032 -0.2794)
							(mid -0.239121 -0.264521)
							(end -0.254 -0.2286)
						)
						(arc
							(start -0.254 0.2286)
							(mid -0.239121 0.264521)
							(end -0.2032 0.2794)
						)
						(arc
							(start 0.2032 0.2794)
							(mid 0.239121 0.264521)
							(end 0.254 0.2286)
						)
						(arc
							(start 0.254 -0.2286)
							(mid 0.239121 -0.264521)
							(end 0.2032 -0.2794)
						)
					)
					(width 0)
					(fill yes)
				)
			)
		)
	)
	(footprint ""
		(layer "F.Cu")
		(at 15.0114 -65.786 90)
		(property "Reference" "C159"
			(at 0 0 90)
			(layer "F.SilkS")
			(hide yes)
			(effects
				(font
					(size 1.27 1.27)
				)
			)
		)
		(property "Value" "SC10U6D3V5KX-4GP"
			(at 0 -4.9022 90)
			(unlocked yes)
			(layer "F.Fab")
			(hide yes)
			(effects
				(font
					(size 1.016 1.016)
					(thickness 0.1524)
				)
			)
		)
		(property "Device Type" "C805H58"
			(at 0 -6.8072 90)
			(unlocked yes)
			(layer "F.Fab")
			(hide yes)
			(effects
				(font
					(size 1.016 1.016)
					(thickness 0.1524)
				)
			)
		)
		(duplicate_pad_numbers_are_jumpers no)
		(fp_line
			(start 0.6096 0)
			(end -0.6096 0)
			(stroke
				(width 0.3048)
				(type default)
			)
			(layer "F.SilkS")
		)
		(fp_poly
			(pts
				(xy -0.9017 1.4351) (xy 0.9017 1.4351) (xy 0.9017 -1.4351) (xy -0.9017 -1.4351)
			)
			(stroke
				(width 0)
				(type default)
			)
			(fill no)
			(layer "F.CrtYd")
		)
		(fp_poly
			(pts
				(xy 0.9017 1.4351) (xy 0.9017 -1.4351) (xy -0.9017 -1.4351) (xy -0.9017 1.4351)
			)
			(stroke
				(width 0)
				(type default)
			)
			(fill no)
			(layer "F.Fab")
		)
		(pad "1" smd rect
			(at 0 -0.8382 90)
			(size 1.5494 0.9398)
			(layers "F.Cu" "F.Mask" "F.Paste")
			(net "P3V3")
		)
		(pad "2" smd rect
			(at 0 0.8382 90)
			(size 1.5494 0.9398)
			(layers "F.Cu" "F.Mask" "F.Paste")
			(net "GND")
		)
	)
	(footprint ""
		(layer "F.Cu")
		(at 140.081 -47.625 180)
		(property "Reference" "TP37"
			(at 0 0 180)
			(layer "F.SilkS")
			(hide yes)
			(effects
				(font
					(size 1.27 1.27)
				)
			)
		)
		(property "Value" "TPAD32-GP"
			(at 0 -3.166364 180)
			(unlocked yes)
			(layer "F.Fab")
			(hide yes)
			(effects
				(font
					(size 1.016 1.016)
					(thickness 0.1524)
				)
			)
		)
		(property "Device Type" "TPAD32"
			(at 0 -4.690618 180)
			(unlocked yes)
			(layer "F.Fab")
			(hide yes)
			(effects
				(font
					(size 1.016 1.016)
					(thickness 0.1524)
				)
			)
		)
		(duplicate_pad_numbers_are_jumpers no)
		(fp_poly
			(pts
				(arc
					(start -0.7112 0)
					(mid 0.7112 0)
					(end -0.7112 0)
				)
			)
			(stroke
				(width 0)
				(type default)
			)
			(fill no)
			(layer "F.CrtYd")
		)
		(fp_poly
			(pts
				(arc
					(start -0.7112 0)
					(mid 0.7112 0)
					(end -0.7112 0)
				)
			)
			(stroke
				(width 0)
				(type default)
			)
			(fill no)
			(layer "F.Fab")
		)
		(pad "1" smd circle
			(at 0 0 180)
			(size 0.8128 0.8128)
			(layers "F.Cu" "F.Mask" "F.Paste")
			(net "C_NCE#")
		)
	)
	(footprint ""
		(layer "F.Cu")
		(at 26.7462 -60.833 -90)
		(property "Reference" "PR38"
			(at 0 0 270)
			(layer "F.SilkS")
			(hide yes)
			(effects
				(font
					(size 1.27 1.27)
				)
			)
		)
		(property "Value" "0R2J-2-GP"
			(at 1.7907 -1.1176 270)
			(unlocked yes)
			(layer "F.Fab")
			(hide yes)
			(effects
				(font
					(size 1.016 1.016)
					(thickness 0.1524)
				)
			)
		)
		(property "Device Type" "R402H16"
			(at 1.7907 -2.6416 270)
			(unlocked yes)
			(layer "F.Fab")
			(hide yes)
			(effects
				(font
					(size 1.016 1.016)
					(thickness 0.1524)
				)
			)
		)
		(duplicate_pad_numbers_are_jumpers no)
		(fp_rect
			(start -0.381 0.8382)
			(end 0.381 -0.8382)
			(stroke
				(width 0)
				(type default)
			)
			(fill no)
			(layer "F.CrtYd")
		)
		(fp_rect
			(start -0.381 0.8382)
			(end 0.381 -0.8382)
			(stroke
				(width 0)
				(type default)
			)
			(fill no)
			(layer "F.Fab")
		)
		(pad "1" smd custom
			(at 0 -0.4318 270)
			(size 0.127 0.127)
			(layers "F.Cu" "F.Mask" "F.Paste")
			(net "VCCP_5VBIAS")
			(options
				(clearance outline)
				(anchor circle)
			)
			(primitives
				(gr_poly
					(pts
						(arc
							(start -0.2032 -0.2794)
							(mid -0.239121 -0.264521)
							(end -0.254 -0.2286)
						)
						(arc
							(start -0.254 0.2286)
							(mid -0.239121 0.264521)
							(end -0.2032 0.2794)
						)
						(arc
							(start 0.2032 0.2794)
							(mid 0.239121 0.264521)
							(end 0.254 0.2286)
						)
						(arc
							(start 0.254 -0.2286)
							(mid 0.239121 -0.264521)
							(end 0.2032 -0.2794)
						)
					)
					(width 0)
					(fill yes)
				)
			)
		)
		(pad "2" smd custom
			(at 0 0.4318 270)
			(size 0.127 0.127)
			(layers "F.Cu" "F.Mask" "F.Paste")
			(net "VR_PVCCP_PVNN_VCCP")
			(options
				(clearance outline)
				(anchor circle)
			)
			(primitives
				(gr_poly
					(pts
						(arc
							(start -0.2032 -0.2794)
							(mid -0.239121 -0.264521)
							(end -0.254 -0.2286)
						)
						(arc
							(start -0.254 0.2286)
							(mid -0.239121 0.264521)
							(end -0.2032 0.2794)
						)
						(arc
							(start 0.2032 0.2794)
							(mid 0.239121 0.264521)
							(end 0.254 0.2286)
						)
						(arc
							(start 0.254 -0.2286)
							(mid 0.239121 -0.264521)
							(end 0.2032 -0.2794)
						)
					)
					(width 0)
					(fill yes)
				)
			)
		)
	)
	(footprint ""
		(layer "F.Cu")
		(at 63.119 -29.972 180)
		(property "Reference" "C113"
			(at 0 0 180)
			(layer "F.SilkS")
			(hide yes)
			(effects
				(font
					(size 1.27 1.27)
				)
			)
		)
		(property "Value" "SCD47U25V2KX-GP"
			(at 1.8923 -1.2065 180)
			(unlocked yes)
			(layer "F.Fab")
			(hide yes)
			(effects
				(font
					(size 1.016 1.016)
					(thickness 0.1524)
				)
			)
		)
		(property "Device Type" "C402H24"
			(at 1.8923 -2.7305 180)
			(unlocked yes)
			(layer "F.Fab")
			(hide yes)
			(effects
				(font
					(size 1.016 1.016)
					(thickness 0.1524)
				)
			)
		)
		(duplicate_pad_numbers_are_jumpers no)
		(fp_rect
			(start -0.381 0.7366)
			(end 0.381 -0.7366)
			(stroke
				(width 0)
				(type default)
			)
			(fill no)
			(layer "F.CrtYd")
		)
		(fp_rect
			(start -0.381 0.7366)
			(end 0.381 -0.7366)
			(stroke
				(width 0)
				(type default)
			)
			(fill no)
			(layer "F.Fab")
		)
		(pad "1" smd custom
			(at 0 -0.4572 180)
			(size 0.1143 0.1143)
			(layers "F.Cu" "F.Mask" "F.Paste")
			(net "SW_P1V8_EN_LV")
			(options
				(clearance outline)
				(anchor circle)
			)
			(primitives
				(gr_poly
					(pts
						(arc
							(start -0.254 -0.1778)
							(mid -0.239121 -0.213721)
							(end -0.2032 -0.2286)
						)
						(arc
							(start 0.2032 -0.2286)
							(mid 0.239121 -0.213721)
							(end 0.254 -0.1778)
						)
						(arc
							(start 0.254 0.1778)
							(mid 0.239121 0.213721)
							(end 0.2032 0.2286)
						)
						(arc
							(start -0.2032 0.2286)
							(mid -0.239121 0.213721)
							(end -0.254 0.1778)
						)
					)
					(width 0)
					(fill yes)
				)
			)
		)
		(pad "2" smd custom
			(at 0 0.4572 180)
			(size 0.1143 0.1143)
			(layers "F.Cu" "F.Mask" "F.Paste")
			(net "P1V8")
			(options
				(clearance outline)
				(anchor circle)
			)
			(primitives
				(gr_poly
					(pts
						(arc
							(start -0.254 -0.1778)
							(mid -0.239121 -0.213721)
							(end -0.2032 -0.2286)
						)
						(arc
							(start 0.2032 -0.2286)
							(mid 0.239121 -0.213721)
							(end 0.254 -0.1778)
						)
						(arc
							(start 0.254 0.1778)
							(mid 0.239121 0.213721)
							(end 0.2032 0.2286)
						)
						(arc
							(start -0.2032 0.2286)
							(mid -0.239121 0.213721)
							(end -0.254 0.1778)
						)
					)
					(width 0)
					(fill yes)
				)
			)
		)
	)
	(footprint ""
		(layer "F.Cu")
		(at 197.993 -37.338 180)
		(property "Reference" "PR91"
			(at 0 0 180)
			(layer "F.SilkS")
			(hide yes)
			(effects
				(font
					(size 1.27 1.27)
				)
			)
		)
		(property "Value" "10KR2F-2-GP"
			(at 1.7907 -1.1176 180)
			(unlocked yes)
			(layer "F.Fab")
			(hide yes)
			(effects
				(font
					(size 1.016 1.016)
					(thickness 0.1524)
				)
			)
		)
		(property "Device Type" "R402H16"
			(at 1.7907 -2.6416 180)
			(unlocked yes)
			(layer "F.Fab")
			(hide yes)
			(effects
				(font
					(size 1.016 1.016)
					(thickness 0.1524)
				)
			)
		)
		(duplicate_pad_numbers_are_jumpers no)
		(fp_rect
			(start -0.381 0.8382)
			(end 0.381 -0.8382)
			(stroke
				(width 0)
				(type default)
			)
			(fill no)
			(layer "F.CrtYd")
		)
		(fp_rect
			(start -0.381 0.8382)
			(end 0.381 -0.8382)
			(stroke
				(width 0)
				(type default)
			)
			(fill no)
			(layer "F.Fab")
		)
		(pad "1" smd custom
			(at 0 -0.4318 180)
			(size 0.127 0.127)
			(layers "F.Cu" "F.Mask" "F.Paste")
			(net "GND")
			(options
				(clearance outline)
				(anchor circle)
			)
			(primitives
				(gr_poly
					(pts
						(arc
							(start -0.2032 -0.2794)
							(mid -0.239121 -0.264521)
							(end -0.254 -0.2286)
						)
						(arc
							(start -0.254 0.2286)
							(mid -0.239121 0.264521)
							(end -0.2032 0.2794)
						)
						(arc
							(start 0.2032 0.2794)
							(mid 0.239121 0.264521)
							(end 0.254 0.2286)
						)
						(arc
							(start 0.254 -0.2286)
							(mid 0.239121 -0.264521)
							(end 0.2032 -0.2794)
						)
					)
					(width 0)
					(fill yes)
				)
			)
		)
		(pad "2" smd custom
			(at 0 0.4318 180)
			(size 0.127 0.127)
			(layers "F.Cu" "F.Mask" "F.Paste")
			(net "VR_PVDDR_A_GL1_BG")
			(options
				(clearance outline)
				(anchor circle)
			)
			(primitives
				(gr_poly
					(pts
						(arc
							(start -0.2032 -0.2794)
							(mid -0.239121 -0.264521)
							(end -0.254 -0.2286)
						)
						(arc
							(start -0.254 0.2286)
							(mid -0.239121 0.264521)
							(end -0.2032 0.2794)
						)
						(arc
							(start 0.2032 0.2794)
							(mid 0.239121 0.264521)
							(end 0.254 0.2286)
						)
						(arc
							(start 0.254 -0.2286)
							(mid 0.239121 -0.264521)
							(end 0.2032 -0.2794)
						)
					)
					(width 0)
					(fill yes)
				)
			)
		)
	)
	(footprint ""
		(layer "F.Cu")
		(at 184.912 -22.8854)
		(property "Reference" "PR165"
			(at 0 0 0)
			(layer "F.SilkS")
			(hide yes)
			(effects
				(font
					(size 1.27 1.27)
				)
			)
		)
		(property "Value" "0R2J-2-GP"
			(at 0.064008 -3.993896 0)
			(unlocked yes)
			(layer "F.Fab")
			(hide yes)
			(effects
				(font
					(size 1.016 1.016)
					(thickness 0.1524)
				)
			)
		)
		(property "Device Type" "R402H16"
			(at 0.064008 -5.517896 0)
			(unlocked yes)
			(layer "F.Fab")
			(hide yes)
			(effects
				(font
					(size 1.016 1.016)
					(thickness 0.1524)
				)
			)
		)
		(duplicate_pad_numbers_are_jumpers no)
		(fp_rect
			(start -0.381 0.8382)
			(end 0.381 -0.8382)
			(stroke
				(width 0)
				(type default)
			)
			(fill no)
			(layer "F.CrtYd")
		)
		(fp_rect
			(start -0.381 0.8382)
			(end 0.381 -0.8382)
			(stroke
				(width 0)
				(type default)
			)
			(fill no)
			(layer "F.Fab")
		)
		(pad "1" smd custom
			(at 0 -0.4318)
			(size 0.127 0.127)
			(layers "F.Cu" "F.Mask" "F.Paste")
			(net "PWRGD_PVTT_PG")
			(options
				(clearance outline)
				(anchor circle)
			)
			(primitives
				(gr_poly
					(pts
						(arc
							(start -0.2032 -0.2794)
							(mid -0.239121 -0.264521)
							(end -0.254 -0.2286)
						)
						(arc
							(start -0.254 0.2286)
							(mid -0.239121 0.264521)
							(end -0.2032 0.2794)
						)
						(arc
							(start 0.2032 0.2794)
							(mid 0.239121 0.264521)
							(end 0.254 0.2286)
						)
						(arc
							(start 0.254 -0.2286)
							(mid 0.239121 -0.264521)
							(end 0.2032 -0.2794)
						)
					)
					(width 0)
					(fill yes)
				)
			)
		)
		(pad "2" smd custom
			(at 0 0.4318)
			(size 0.127 0.127)
			(layers "F.Cu" "F.Mask" "F.Paste")
			(net "PV_VTT_DDR_B_R_PG")
			(options
				(clearance outline)
				(anchor circle)
			)
			(primitives
				(gr_poly
					(pts
						(arc
							(start -0.2032 -0.2794)
							(mid -0.239121 -0.264521)
							(end -0.254 -0.2286)
						)
						(arc
							(start -0.254 0.2286)
							(mid -0.239121 0.264521)
							(end -0.2032 0.2794)
						)
						(arc
							(start 0.2032 0.2794)
							(mid 0.239121 0.264521)
							(end 0.254 0.2286)
						)
						(arc
							(start 0.254 -0.2286)
							(mid 0.239121 -0.264521)
							(end 0.2032 -0.2794)
						)
					)
					(width 0)
					(fill yes)
				)
			)
		)
	)
	(footprint ""
		(layer "F.Cu")
		(at 175.7426 -46.5074)
		(property "Reference" "R184"
			(at 0 0 0)
			(layer "F.SilkS")
			(hide yes)
			(effects
				(font
					(size 1.27 1.27)
				)
			)
		)
		(property "Value" "0R2J-2-GP"
			(at 0.064008 -3.993896 0)
			(unlocked yes)
			(layer "F.Fab")
			(hide yes)
			(effects
				(font
					(size 1.016 1.016)
					(thickness 0.1524)
				)
			)
		)
		(property "Device Type" "R402H16"
			(at 0.064008 -5.517896 0)
			(unlocked yes)
			(layer "F.Fab")
			(hide yes)
			(effects
				(font
					(size 1.016 1.016)
					(thickness 0.1524)
				)
			)
		)
		(duplicate_pad_numbers_are_jumpers no)
		(fp_rect
			(start -0.381 0.8382)
			(end 0.381 -0.8382)
			(stroke
				(width 0)
				(type default)
			)
			(fill no)
			(layer "F.CrtYd")
		)
		(fp_rect
			(start -0.381 0.8382)
			(end 0.381 -0.8382)
			(stroke
				(width 0)
				(type default)
			)
			(fill no)
			(layer "F.Fab")
		)
		(pad "1" smd custom
			(at 0 -0.4318)
			(size 0.127 0.127)
			(layers "F.Cu" "F.Mask" "F.Paste")
			(net "EEPROM_CLK")
			(options
				(clearance outline)
				(anchor circle)
			)
			(primitives
				(gr_poly
					(pts
						(arc
							(start -0.2032 -0.2794)
							(mid -0.239121 -0.264521)
							(end -0.254 -0.2286)
						)
						(arc
							(start -0.254 0.2286)
							(mid -0.239121 0.264521)
							(end -0.2032 0.2794)
						)
						(arc
							(start 0.2032 0.2794)
							(mid 0.239121 0.264521)
							(end 0.254 0.2286)
						)
						(arc
							(start 0.254 -0.2286)
							(mid 0.239121 -0.264521)
							(end 0.2032 -0.2794)
						)
					)
					(width 0)
					(fill yes)
				)
			)
		)
		(pad "2" smd custom
			(at 0 0.4318)
			(size 0.127 0.127)
			(layers "F.Cu" "F.Mask" "F.Paste")
			(net "BMC_I2C_CLK")
			(options
				(clearance outline)
				(anchor circle)
			)
			(primitives
				(gr_poly
					(pts
						(arc
							(start -0.2032 -0.2794)
							(mid -0.239121 -0.264521)
							(end -0.254 -0.2286)
						)
						(arc
							(start -0.254 0.2286)
							(mid -0.239121 0.264521)
							(end -0.2032 0.2794)
						)
						(arc
							(start 0.2032 0.2794)
							(mid 0.239121 0.264521)
							(end 0.254 0.2286)
						)
						(arc
							(start 0.254 -0.2286)
							(mid 0.239121 -0.264521)
							(end 0.2032 -0.2794)
						)
					)
					(width 0)
					(fill yes)
				)
			)
		)
	)
	(footprint ""
		(layer "F.Cu")
		(at 50.8 -59.436 90)
		(property "Reference" "PL4"
			(at 0 0 90)
			(layer "F.SilkS")
			(hide yes)
			(effects
				(font
					(size 1.27 1.27)
				)
			)
		)
		(property "Value" "IND-300NH-8-GP"
			(at -4.9403 -2.921 90)
			(unlocked yes)
			(layer "F.Fab")
			(hide yes)
			(effects
				(font
					(size 1.016 1.016)
					(thickness 0.1524)
				)
			)
		)
		(property "Device Type" "L102078-254224H296"
			(at -4.9403 -4.445 90)
			(unlocked yes)
			(layer "F.Fab")
			(hide yes)
			(effects
				(font
					(size 1.016 1.016)
					(thickness 0.1524)
				)
			)
		)
		(duplicate_pad_numbers_are_jumpers no)
		(fp_rect
			(start -4.1529 5.6134)
			(end 4.1529 -5.6134)
			(stroke
				(width 0)
				(type default)
			)
			(fill no)
			(layer "F.CrtYd")
		)
		(fp_rect
			(start -4.1529 5.6134)
			(end 4.1529 -5.6134)
			(stroke
				(width 0)
				(type default)
			)
			(fill no)
			(layer "F.Fab")
		)
		(pad "1" smd rect
			(at 0 -3.893566 90)
			(size 2.4892 3.175)
			(layers "F.Cu" "F.Mask" "F.Paste")
			(net "VR_PVCCP_PWM_OUT")
		)
		(pad "2" smd rect
			(at 0 3.893566 90)
			(size 2.4892 3.175)
			(layers "F.Cu" "F.Mask" "F.Paste")
			(net "PVCCP")
		)
	)
	(footprint ""
		(layer "F.Cu")
		(at 163.957 -60.325 90)
		(property "Reference" "R237"
			(at 0 0 90)
			(layer "F.SilkS")
			(hide yes)
			(effects
				(font
					(size 1.27 1.27)
				)
			)
		)
		(property "Value" "100R2F-L1-GP-U"
			(at 0.064008 -3.993896 90)
			(unlocked yes)
			(layer "F.Fab")
			(hide yes)
			(effects
				(font
					(size 1.016 1.016)
					(thickness 0.1524)
				)
			)
		)
		(property "Device Type" "R402H14"
			(at 0.064008 -5.517896 90)
			(unlocked yes)
			(layer "F.Fab")
			(hide yes)
			(effects
				(font
					(size 1.016 1.016)
					(thickness 0.1524)
				)
			)
		)
		(duplicate_pad_numbers_are_jumpers no)
		(fp_rect
			(start -0.381 0.8382)
			(end 0.381 -0.8382)
			(stroke
				(width 0)
				(type default)
			)
			(fill no)
			(layer "F.CrtYd")
		)
		(fp_rect
			(start -0.381 0.8382)
			(end 0.381 -0.8382)
			(stroke
				(width 0)
				(type default)
			)
			(fill no)
			(layer "F.Fab")
		)
		(pad "1" smd custom
			(at 0 -0.4318 90)
			(size 0.127 0.127)
			(layers "F.Cu" "F.Mask" "F.Paste")
			(net "DDR3_M_A_VREF_CA")
			(options
				(clearance outline)
				(anchor circle)
			)
			(primitives
				(gr_poly
					(pts
						(arc
							(start -0.2032 -0.2794)
							(mid -0.239121 -0.264521)
							(end -0.254 -0.2286)
						)
						(arc
							(start -0.254 0.2286)
							(mid -0.239121 0.264521)
							(end -0.2032 0.2794)
						)
						(arc
							(start 0.2032 0.2794)
							(mid 0.239121 0.264521)
							(end 0.254 0.2286)
						)
						(arc
							(start 0.254 -0.2286)
							(mid 0.239121 -0.264521)
							(end 0.2032 -0.2794)
						)
					)
					(width 0)
					(fill yes)
				)
			)
		)
		(pad "2" smd custom
			(at 0 0.4318 90)
			(size 0.127 0.127)
			(layers "F.Cu" "F.Mask" "F.Paste")
			(net "GND")
			(options
				(clearance outline)
				(anchor circle)
			)
			(primitives
				(gr_poly
					(pts
						(arc
							(start -0.2032 -0.2794)
							(mid -0.239121 -0.264521)
							(end -0.254 -0.2286)
						)
						(arc
							(start -0.254 0.2286)
							(mid -0.239121 0.264521)
							(end -0.2032 0.2794)
						)
						(arc
							(start 0.2032 0.2794)
							(mid 0.239121 0.264521)
							(end 0.254 0.2286)
						)
						(arc
							(start 0.254 -0.2286)
							(mid 0.239121 -0.264521)
							(end 0.2032 -0.2794)
						)
					)
					(width 0)
					(fill yes)
				)
			)
		)
	)
	(footprint ""
		(layer "F.Cu")
		(at 169.7228 -45.847 -90)
		(property "Reference" "R199"
			(at 0 0 270)
			(layer "F.SilkS")
			(hide yes)
			(effects
				(font
					(size 1.27 1.27)
				)
			)
		)
		(property "Value" "0R2J-2-GP"
			(at 1.7907 -1.1176 270)
			(unlocked yes)
			(layer "F.Fab")
			(hide yes)
			(effects
				(font
					(size 1.016 1.016)
					(thickness 0.1524)
				)
			)
		)
		(property "Device Type" "R402H16"
			(at 1.7907 -2.6416 270)
			(unlocked yes)
			(layer "F.Fab")
			(hide yes)
			(effects
				(font
					(size 1.016 1.016)
					(thickness 0.1524)
				)
			)
		)
		(duplicate_pad_numbers_are_jumpers no)
		(fp_rect
			(start -0.381 0.8382)
			(end 0.381 -0.8382)
			(stroke
				(width 0)
				(type default)
			)
			(fill no)
			(layer "F.CrtYd")
		)
		(fp_rect
			(start -0.381 0.8382)
			(end 0.381 -0.8382)
			(stroke
				(width 0)
				(type default)
			)
			(fill no)
			(layer "F.Fab")
		)
		(pad "1" smd custom
			(at 0 -0.4318 270)
			(size 0.127 0.127)
			(layers "F.Cu" "F.Mask" "F.Paste")
			(net "XDP_SOC_CPU_TDI")
			(options
				(clearance outline)
				(anchor circle)
			)
			(primitives
				(gr_poly
					(pts
						(arc
							(start -0.2032 -0.2794)
							(mid -0.239121 -0.264521)
							(end -0.254 -0.2286)
						)
						(arc
							(start -0.254 0.2286)
							(mid -0.239121 0.264521)
							(end -0.2032 0.2794)
						)
						(arc
							(start 0.2032 0.2794)
							(mid 0.239121 0.264521)
							(end 0.254 0.2286)
						)
						(arc
							(start 0.254 -0.2286)
							(mid 0.239121 -0.264521)
							(end 0.2032 -0.2794)
						)
					)
					(width 0)
					(fill yes)
				)
			)
		)
		(pad "2" smd custom
			(at 0 0.4318 270)
			(size 0.127 0.127)
			(layers "F.Cu" "F.Mask" "F.Paste")
			(net "XDP_SOC_CPU_TDI_S")
			(options
				(clearance outline)
				(anchor circle)
			)
			(primitives
				(gr_poly
					(pts
						(arc
							(start -0.2032 -0.2794)
							(mid -0.239121 -0.264521)
							(end -0.254 -0.2286)
						)
						(arc
							(start -0.254 0.2286)
							(mid -0.239121 0.264521)
							(end -0.2032 0.2794)
						)
						(arc
							(start 0.2032 0.2794)
							(mid 0.239121 0.264521)
							(end 0.254 0.2286)
						)
						(arc
							(start 0.254 -0.2286)
							(mid 0.239121 -0.264521)
							(end 0.2032 -0.2794)
						)
					)
					(width 0)
					(fill yes)
				)
			)
		)
	)
	(footprint ""
		(layer "F.Cu")
		(at 139.7 -21.717)
		(property "Reference" "TP13"
			(at 0 0 0)
			(layer "F.SilkS")
			(hide yes)
			(effects
				(font
					(size 1.27 1.27)
				)
			)
		)
		(property "Value" "TPAD28-1-GP-U"
			(at 0.0508 -1.9304 0)
			(unlocked yes)
			(layer "F.Fab")
			(hide yes)
			(effects
				(font
					(size 1.016 1.016)
					(thickness 0.1524)
				)
			)
		)
		(property "Device Type" "TPAD28-1-U"
			(at 0.0508 -3.4544 0)
			(unlocked yes)
			(layer "F.Fab")
			(hide yes)
			(effects
				(font
					(size 1.016 1.016)
					(thickness 0.1524)
				)
			)
		)
		(duplicate_pad_numbers_are_jumpers no)
		(fp_poly
			(pts
				(arc
					(start 0.3556 0)
					(mid -0.3556 0)
					(end 0.3556 0)
				)
			)
			(stroke
				(width 0)
				(type default)
			)
			(fill no)
			(layer "F.CrtYd")
		)
		(fp_poly
			(pts
				(arc
					(start 0.9525 0)
					(mid -0.9525 0)
					(end 0.9525 0)
				)
			)
			(stroke
				(width 0)
				(type default)
			)
			(fill no)
			(layer "F.Fab")
		)
		(pad "1" smd circle
			(at 0 0)
			(size 0.7112 0.7112)
			(layers "F.Cu" "F.Mask" "F.Paste")
			(net "TP_FPGA_P85")
		)
	)
	(footprint ""
		(layer "F.Cu")
		(at 204.7748 -23.114 90)
		(property "Reference" "TP15"
			(at 0 0 90)
			(layer "F.SilkS")
			(hide yes)
			(effects
				(font
					(size 1.27 1.27)
				)
			)
		)
		(property "Value" "TPAD32-GP"
			(at 0 -3.166364 90)
			(unlocked yes)
			(layer "F.Fab")
			(hide yes)
			(effects
				(font
					(size 1.016 1.016)
					(thickness 0.1524)
				)
			)
		)
		(property "Device Type" "TPAD32"
			(at 0 -4.690618 90)
			(unlocked yes)
			(layer "F.Fab")
			(hide yes)
			(effects
				(font
					(size 1.016 1.016)
					(thickness 0.1524)
				)
			)
		)
		(duplicate_pad_numbers_are_jumpers no)
		(fp_poly
			(pts
				(arc
					(start 0 0.7112)
					(mid 0 -0.7112)
					(end 0 0.7112)
				)
			)
			(stroke
				(width 0)
				(type default)
			)
			(fill no)
			(layer "F.CrtYd")
		)
		(fp_poly
			(pts
				(arc
					(start 0 0.7112)
					(mid 0 -0.7112)
					(end 0 0.7112)
				)
			)
			(stroke
				(width 0)
				(type default)
			)
			(fill no)
			(layer "F.Fab")
		)
		(pad "1" smd circle
			(at 0 0 90)
			(size 0.8128 0.8128)
			(layers "F.Cu" "F.Mask" "F.Paste")
			(net "JTAG_PLD_TMS")
		)
	)
	(footprint ""
		(layer "F.Cu")
		(at 6.7818 -51.7652 -90)
		(property "Reference" "R7"
			(at 0 0 270)
			(layer "F.SilkS")
			(hide yes)
			(effects
				(font
					(size 1.27 1.27)
				)
			)
		)
		(property "Value" "4K7R2F-GP"
			(at 0.064008 -3.993896 270)
			(unlocked yes)
			(layer "F.Fab")
			(hide yes)
			(effects
				(font
					(size 1.016 1.016)
					(thickness 0.1524)
				)
			)
		)
		(property "Device Type" "R402H16"
			(at 0.064008 -5.517896 270)
			(unlocked yes)
			(layer "F.Fab")
			(hide yes)
			(effects
				(font
					(size 1.016 1.016)
					(thickness 0.1524)
				)
			)
		)
		(duplicate_pad_numbers_are_jumpers no)
		(fp_rect
			(start -0.381 0.8382)
			(end 0.381 -0.8382)
			(stroke
				(width 0)
				(type default)
			)
			(fill no)
			(layer "F.CrtYd")
		)
		(fp_rect
			(start -0.381 0.8382)
			(end 0.381 -0.8382)
			(stroke
				(width 0)
				(type default)
			)
			(fill no)
			(layer "F.Fab")
		)
		(pad "1" smd custom
			(at 0 -0.4318 270)
			(size 0.127 0.127)
			(layers "F.Cu" "F.Mask" "F.Paste")
			(net "TEMP_1_A1")
			(options
				(clearance outline)
				(anchor circle)
			)
			(primitives
				(gr_poly
					(pts
						(arc
							(start -0.2032 -0.2794)
							(mid -0.239121 -0.264521)
							(end -0.254 -0.2286)
						)
						(arc
							(start -0.254 0.2286)
							(mid -0.239121 0.264521)
							(end -0.2032 0.2794)
						)
						(arc
							(start 0.2032 0.2794)
							(mid 0.239121 0.264521)
							(end 0.254 0.2286)
						)
						(arc
							(start 0.254 -0.2286)
							(mid 0.239121 -0.264521)
							(end 0.2032 -0.2794)
						)
					)
					(width 0)
					(fill yes)
				)
			)
		)
		(pad "2" smd custom
			(at 0 0.4318 270)
			(size 0.127 0.127)
			(layers "F.Cu" "F.Mask" "F.Paste")
			(net "GND")
			(options
				(clearance outline)
				(anchor circle)
			)
			(primitives
				(gr_poly
					(pts
						(arc
							(start -0.2032 -0.2794)
							(mid -0.239121 -0.264521)
							(end -0.254 -0.2286)
						)
						(arc
							(start -0.254 0.2286)
							(mid -0.239121 0.264521)
							(end -0.2032 0.2794)
						)
						(arc
							(start 0.2032 0.2794)
							(mid 0.239121 0.264521)
							(end 0.254 0.2286)
						)
						(arc
							(start 0.254 -0.2286)
							(mid 0.239121 -0.264521)
							(end 0.2032 -0.2794)
						)
					)
					(width 0)
					(fill yes)
				)
			)
		)
	)
	(footprint ""
		(layer "F.Cu")
		(at 8.509 -60.071 90)
		(property "Reference" "C37"
			(at 0 0 90)
			(layer "F.SilkS")
			(hide yes)
			(effects
				(font
					(size 1.27 1.27)
				)
			)
		)
		(property "Value" "SCD1U16V2KX-3GP"
			(at 1.1811 -2.7051 90)
			(unlocked yes)
			(layer "F.Fab")
			(hide yes)
			(effects
				(font
					(size 1.016 1.016)
					(thickness 0.1524)
				)
			)
		)
		(property "Device Type" "C402H22"
			(at 1.1811 -4.2291 90)
			(unlocked yes)
			(layer "F.Fab")
			(hide yes)
			(effects
				(font
					(size 1.016 1.016)
					(thickness 0.1524)
				)
			)
		)
		(duplicate_pad_numbers_are_jumpers no)
		(fp_rect
			(start -0.381 0.7366)
			(end 0.381 -0.7366)
			(stroke
				(width 0)
				(type default)
			)
			(fill no)
			(layer "F.CrtYd")
		)
		(fp_rect
			(start -0.381 0.7366)
			(end 0.381 -0.7366)
			(stroke
				(width 0)
				(type default)
			)
			(fill no)
			(layer "F.Fab")
		)
		(pad "1" smd custom
			(at 0 -0.4572 90)
			(size 0.1143 0.1143)
			(layers "F.Cu" "F.Mask" "F.Paste")
			(net "P2E_CPU_NGFF_TX_DN14")
			(options
				(clearance outline)
				(anchor circle)
			)
			(primitives
				(gr_poly
					(pts
						(arc
							(start -0.254 -0.1778)
							(mid -0.239121 -0.213721)
							(end -0.2032 -0.2286)
						)
						(arc
							(start 0.2032 -0.2286)
							(mid 0.239121 -0.213721)
							(end 0.254 -0.1778)
						)
						(arc
							(start 0.254 0.1778)
							(mid 0.239121 0.213721)
							(end 0.2032 0.2286)
						)
						(arc
							(start -0.2032 0.2286)
							(mid -0.239121 0.213721)
							(end -0.254 0.1778)
						)
					)
					(width 0)
					(fill yes)
				)
			)
		)
		(pad "2" smd custom
			(at 0 0.4572 90)
			(size 0.1143 0.1143)
			(layers "F.Cu" "F.Mask" "F.Paste")
			(net "P2E_CPU_NGFF_C_TX_DN14")
			(options
				(clearance outline)
				(anchor circle)
			)
			(primitives
				(gr_poly
					(pts
						(arc
							(start -0.254 -0.1778)
							(mid -0.239121 -0.213721)
							(end -0.2032 -0.2286)
						)
						(arc
							(start 0.2032 -0.2286)
							(mid 0.239121 -0.213721)
							(end 0.254 -0.1778)
						)
						(arc
							(start 0.254 0.1778)
							(mid 0.239121 0.213721)
							(end 0.2032 0.2286)
						)
						(arc
							(start -0.2032 0.2286)
							(mid -0.239121 0.213721)
							(end -0.254 0.1778)
						)
					)
					(width 0)
					(fill yes)
				)
			)
		)
	)
	(footprint ""
		(layer "F.Cu")
		(at 18.4404 -64.1604 -90)
		(property "Reference" "PC22"
			(at 0 0 270)
			(layer "F.SilkS")
			(hide yes)
			(effects
				(font
					(size 1.27 1.27)
				)
			)
		)
		(property "Value" "SC1KP50V2KX-1GP"
			(at 1.8923 -1.2065 270)
			(unlocked yes)
			(layer "F.Fab")
			(hide yes)
			(effects
				(font
					(size 1.016 1.016)
					(thickness 0.1524)
				)
			)
		)
		(property "Device Type" "C402H22"
			(at 1.8923 -2.7305 270)
			(unlocked yes)
			(layer "F.Fab")
			(hide yes)
			(effects
				(font
					(size 1.016 1.016)
					(thickness 0.1524)
				)
			)
		)
		(duplicate_pad_numbers_are_jumpers no)
		(fp_rect
			(start -0.381 0.7366)
			(end 0.381 -0.7366)
			(stroke
				(width 0)
				(type default)
			)
			(fill no)
			(layer "F.CrtYd")
		)
		(fp_rect
			(start -0.381 0.7366)
			(end 0.381 -0.7366)
			(stroke
				(width 0)
				(type default)
			)
			(fill no)
			(layer "F.Fab")
		)
		(pad "1" smd custom
			(at 0 -0.4572 270)
			(size 0.1143 0.1143)
			(layers "F.Cu" "F.Mask" "F.Paste")
			(net "VR_PVNN_COMP")
			(options
				(clearance outline)
				(anchor circle)
			)
			(primitives
				(gr_poly
					(pts
						(arc
							(start -0.254 -0.1778)
							(mid -0.239121 -0.213721)
							(end -0.2032 -0.2286)
						)
						(arc
							(start 0.2032 -0.2286)
							(mid 0.239121 -0.213721)
							(end 0.254 -0.1778)
						)
						(arc
							(start 0.254 0.1778)
							(mid 0.239121 0.213721)
							(end 0.2032 0.2286)
						)
						(arc
							(start -0.2032 0.2286)
							(mid -0.239121 0.213721)
							(end -0.254 0.1778)
						)
					)
					(width 0)
					(fill yes)
				)
			)
		)
		(pad "2" smd custom
			(at 0 0.4572 270)
			(size 0.1143 0.1143)
			(layers "F.Cu" "F.Mask" "F.Paste")
			(net "VR_PVNN_VW")
			(options
				(clearance outline)
				(anchor circle)
			)
			(primitives
				(gr_poly
					(pts
						(arc
							(start -0.254 -0.1778)
							(mid -0.239121 -0.213721)
							(end -0.2032 -0.2286)
						)
						(arc
							(start 0.2032 -0.2286)
							(mid 0.239121 -0.213721)
							(end 0.254 -0.1778)
						)
						(arc
							(start 0.254 0.1778)
							(mid 0.239121 0.213721)
							(end 0.2032 0.2286)
						)
						(arc
							(start -0.2032 0.2286)
							(mid -0.239121 0.213721)
							(end -0.254 0.1778)
						)
					)
					(width 0)
					(fill yes)
				)
			)
		)
	)
	(footprint ""
		(layer "F.Cu")
		(at 62.484 -48.641 180)
		(property "Reference" "R35"
			(at 0 0 180)
			(layer "F.SilkS")
			(hide yes)
			(effects
				(font
					(size 1.27 1.27)
				)
			)
		)
		(property "Value" "0R2J-2-GP"
			(at 0.064008 -3.993896 180)
			(unlocked yes)
			(layer "F.Fab")
			(hide yes)
			(effects
				(font
					(size 1.016 1.016)
					(thickness 0.1524)
				)
			)
		)
		(property "Device Type" "R402H16"
			(at 0.064008 -5.517896 180)
			(unlocked yes)
			(layer "F.Fab")
			(hide yes)
			(effects
				(font
					(size 1.016 1.016)
					(thickness 0.1524)
				)
			)
		)
		(duplicate_pad_numbers_are_jumpers no)
		(fp_rect
			(start -0.381 0.8382)
			(end 0.381 -0.8382)
			(stroke
				(width 0)
				(type default)
			)
			(fill no)
			(layer "F.CrtYd")
		)
		(fp_rect
			(start -0.381 0.8382)
			(end 0.381 -0.8382)
			(stroke
				(width 0)
				(type default)
			)
			(fill no)
			(layer "F.Fab")
		)
		(pad "1" smd custom
			(at 0 -0.4318 180)
			(size 0.127 0.127)
			(layers "F.Cu" "F.Mask" "F.Paste")
			(net "SMB_HOST_LV_R_CLK")
			(options
				(clearance outline)
				(anchor circle)
			)
			(primitives
				(gr_poly
					(pts
						(arc
							(start -0.2032 -0.2794)
							(mid -0.239121 -0.264521)
							(end -0.254 -0.2286)
						)
						(arc
							(start -0.254 0.2286)
							(mid -0.239121 0.264521)
							(end -0.2032 0.2794)
						)
						(arc
							(start 0.2032 0.2794)
							(mid 0.239121 0.264521)
							(end 0.254 0.2286)
						)
						(arc
							(start 0.254 -0.2286)
							(mid 0.239121 -0.264521)
							(end 0.2032 -0.2794)
						)
					)
					(width 0)
					(fill yes)
				)
			)
		)
		(pad "2" smd custom
			(at 0 0.4318 180)
			(size 0.127 0.127)
			(layers "F.Cu" "F.Mask" "F.Paste")
			(net "SMB_HOST_LV_CLK")
			(options
				(clearance outline)
				(anchor circle)
			)
			(primitives
				(gr_poly
					(pts
						(arc
							(start -0.2032 -0.2794)
							(mid -0.239121 -0.264521)
							(end -0.254 -0.2286)
						)
						(arc
							(start -0.254 0.2286)
							(mid -0.239121 0.264521)
							(end -0.2032 0.2794)
						)
						(arc
							(start 0.2032 0.2794)
							(mid 0.239121 0.264521)
							(end 0.254 0.2286)
						)
						(arc
							(start 0.254 -0.2286)
							(mid 0.239121 -0.264521)
							(end 0.2032 -0.2794)
						)
					)
					(width 0)
					(fill yes)
				)
			)
		)
	)
	(footprint ""
		(layer "F.Cu")
		(at 48.768 -65.151)
		(property "Reference" "PC28"
			(at 0 0 0)
			(layer "F.SilkS")
			(hide yes)
			(effects
				(font
					(size 1.27 1.27)
				)
			)
		)
		(property "Value" "SC47U6D3V5MX-1-GP"
			(at 0 -4.9022 0)
			(unlocked yes)
			(layer "F.Fab")
			(hide yes)
			(effects
				(font
					(size 1.016 1.016)
					(thickness 0.1524)
				)
			)
		)
		(property "Device Type" "C805H54"
			(at 0 -6.8072 0)
			(unlocked yes)
			(layer "F.Fab")
			(hide yes)
			(effects
				(font
					(size 1.016 1.016)
					(thickness 0.1524)
				)
			)
		)
		(duplicate_pad_numbers_are_jumpers no)
		(fp_line
			(start 0.6096 0)
			(end -0.6096 0)
			(stroke
				(width 0.3048)
				(type default)
			)
			(layer "F.SilkS")
		)
		(fp_poly
			(pts
				(xy -0.9017 1.4351) (xy 0.9017 1.4351) (xy 0.9017 -1.4351) (xy -0.9017 -1.4351)
			)
			(stroke
				(width 0)
				(type default)
			)
			(fill no)
			(layer "F.CrtYd")
		)
		(fp_poly
			(pts
				(xy 0.9017 1.4351) (xy 0.9017 -1.4351) (xy -0.9017 -1.4351) (xy -0.9017 1.4351)
			)
			(stroke
				(width 0)
				(type default)
			)
			(fill no)
			(layer "F.Fab")
		)
		(pad "1" smd rect
			(at 0 -0.8382)
			(size 1.5494 0.9398)
			(layers "F.Cu" "F.Mask" "F.Paste")
			(net "PVNN")
		)
		(pad "2" smd rect
			(at 0 0.8382)
			(size 1.5494 0.9398)
			(layers "F.Cu" "F.Mask" "F.Paste")
			(net "GND")
		)
	)
	(footprint ""
		(layer "F.Cu")
		(at 166.37 -46.355 -90)
		(property "Reference" "U24"
			(at 0 0 270)
			(layer "F.SilkS")
			(hide yes)
			(effects
				(font
					(size 1.27 1.27)
				)
			)
		)
		(property "Value" "2N7002DW-7F-GP"
			(at -2.5654 1.1049 270)
			(unlocked yes)
			(layer "F.Fab")
			(hide yes)
			(effects
				(font
					(size 1.016 1.016)
					(thickness 0.1524)
				)
			)
		)
		(property "Device Type" "SOT-363H44"
			(at -2.5654 -0.4191 270)
			(unlocked yes)
			(layer "F.Fab")
			(hide yes)
			(effects
				(font
					(size 1.016 1.016)
					(thickness 0.1524)
				)
			)
		)
		(duplicate_pad_numbers_are_jumpers no)
		(fp_poly
			(pts
				(xy -0.6731 1.4351) (xy -0.9779 1.7399) (xy -0.381 1.7399) (xy -0.3683 1.7399) (xy -0.381 1.7272)
			)
			(stroke
				(width 0)
				(type default)
			)
			(fill yes)
			(layer "F.SilkS")
		)
		(fp_poly
			(pts
				(xy 1.2573 0.8763) (xy 1.2573 -0.8763) (xy 0.9525 -0.8763) (xy 0.9525 -1.4351) (xy -0.9525 -1.4351)
				(xy -0.9525 -0.8763) (xy -1.2573 -0.8763) (xy -1.2573 0.8763) (xy -0.9525 0.8763) (xy -0.9525 1.4351)
				(xy 0.9525 1.4351) (xy 0.9525 0.8763)
			)
			(stroke
				(width 0)
				(type default)
			)
			(fill no)
			(layer "F.CrtYd")
		)
		(fp_poly
			(pts
				(xy 1.2573 0.8763) (xy 1.2573 -0.8763) (xy 0.9525 -0.8763) (xy 0.9525 -1.4351) (xy -0.9525 -1.4351)
				(xy -0.9525 -0.8763) (xy -1.2573 -0.8763) (xy -1.2573 0.8763) (xy -0.9525 0.8763) (xy -0.9525 1.4351)
				(xy 0.9525 1.4351) (xy 0.9525 0.8763)
			)
			(stroke
				(width 0)
				(type default)
			)
			(fill no)
			(layer "F.Fab")
		)
		(pad "1" smd rect
			(at -0.65024 0.8255 270)
			(size 0.3556 0.9652)
			(layers "F.Cu" "F.Mask" "F.Paste")
			(net "XDP_SOC_CPU_TRST#_S")
		)
		(pad "2" smd rect
			(at 0 0.8255 270)
			(size 0.3556 0.9652)
			(layers "F.Cu" "F.Mask" "F.Paste")
			(net "JTAG_CHAIN_EN")
		)
		(pad "3" smd rect
			(at 0.65024 0.8255 270)
			(size 0.3556 0.9652)
			(layers "F.Cu" "F.Mask" "F.Paste")
			(net "JTAG_PLD_TDO_D")
		)
		(pad "4" smd rect
			(at 0.65024 -0.8255 270)
			(size 0.3556 0.9652)
			(layers "F.Cu" "F.Mask" "F.Paste")
			(net "XDP_SOC_CPU_TDI_S")
		)
		(pad "5" smd rect
			(at 0 -0.8255 270)
			(size 0.3556 0.9652)
			(layers "F.Cu" "F.Mask" "F.Paste")
			(net "JTAG_CHAIN_EN")
		)
		(pad "6" smd rect
			(at -0.65024 -0.8255 270)
			(size 0.3556 0.9652)
			(layers "F.Cu" "F.Mask" "F.Paste")
			(net "JTAG_RST_D#")
		)
	)
	(footprint ""
		(layer "F.Cu")
		(at 201.3712 -46.7614 -90)
		(property "Reference" "PG3"
			(at 0 0 270)
			(layer "F.SilkS")
			(hide yes)
			(effects
				(font
					(size 1.27 1.27)
				)
			)
		)
		(property "Value" "GAP-CLOSE-PWR-4-GP"
			(at -2.4638 -0.5461 270)
			(unlocked yes)
			(layer "F.Fab")
			(hide yes)
			(effects
				(font
					(size 1.016 1.016)
					(thickness 0.1524)
				)
			)
		)
		(property "Device Type" "GAP-CLOSE-PWR-4"
			(at -2.4638 -2.0701 270)
			(unlocked yes)
			(layer "F.Fab")
			(hide yes)
			(effects
				(font
					(size 1.016 1.016)
					(thickness 0.1524)
				)
			)
		)
		(duplicate_pad_numbers_are_jumpers no)
		(fp_rect
			(start -0.2794 0.254)
			(end 0.2794 -0.254)
			(stroke
				(width 0)
				(type default)
			)
			(fill no)
			(layer "F.CrtYd")
		)
		(fp_rect
			(start -0.2794 0.254)
			(end 0.2794 -0.254)
			(stroke
				(width 0)
				(type default)
			)
			(fill no)
			(layer "F.Fab")
		)
		(pad "1" smd rect
			(at -0.0635 0 270)
			(size 0.1778 0.254)
			(layers "F.Cu" "F.Mask" "F.Paste")
			(net "PV_VDDR")
		)
		(pad "2" smd rect
			(at 0.0635 0 270)
			(size 0.1778 0.254)
			(layers "F.Cu" "F.Mask" "F.Paste")
			(net "VR_PVDDRA_R_ISUMN1")
		)
	)
	(footprint ""
		(layer "F.Cu")
		(at 74.041 -47.117 -90)
		(property "Reference" "R84"
			(at 0 0 270)
			(layer "F.SilkS")
			(hide yes)
			(effects
				(font
					(size 1.27 1.27)
				)
			)
		)
		(property "Value" "0R2J-2-GP"
			(at 0.064008 -3.993896 270)
			(unlocked yes)
			(layer "F.Fab")
			(hide yes)
			(effects
				(font
					(size 1.016 1.016)
					(thickness 0.1524)
				)
			)
		)
		(property "Device Type" "R402H16"
			(at 0.064008 -5.517896 270)
			(unlocked yes)
			(layer "F.Fab")
			(hide yes)
			(effects
				(font
					(size 1.016 1.016)
					(thickness 0.1524)
				)
			)
		)
		(duplicate_pad_numbers_are_jumpers no)
		(fp_rect
			(start -0.381 0.8382)
			(end 0.381 -0.8382)
			(stroke
				(width 0)
				(type default)
			)
			(fill no)
			(layer "F.CrtYd")
		)
		(fp_rect
			(start -0.381 0.8382)
			(end 0.381 -0.8382)
			(stroke
				(width 0)
				(type default)
			)
			(fill no)
			(layer "F.Fab")
		)
		(pad "1" smd custom
			(at 0 -0.4318 270)
			(size 0.127 0.127)
			(layers "F.Cu" "F.Mask" "F.Paste")
			(net "SMB_CLK1_SPKR")
			(options
				(clearance outline)
				(anchor circle)
			)
			(primitives
				(gr_poly
					(pts
						(arc
							(start -0.2032 -0.2794)
							(mid -0.239121 -0.264521)
							(end -0.254 -0.2286)
						)
						(arc
							(start -0.254 0.2286)
							(mid -0.239121 0.264521)
							(end -0.2032 0.2794)
						)
						(arc
							(start 0.2032 0.2794)
							(mid 0.239121 0.264521)
							(end 0.254 0.2286)
						)
						(arc
							(start 0.254 -0.2286)
							(mid 0.239121 -0.264521)
							(end 0.2032 -0.2794)
						)
					)
					(width 0)
					(fill yes)
				)
			)
		)
		(pad "2" smd custom
			(at 0 0.4318 270)
			(size 0.127 0.127)
			(layers "F.Cu" "F.Mask" "F.Paste")
			(net "CPU_BEEP_LED")
			(options
				(clearance outline)
				(anchor circle)
			)
			(primitives
				(gr_poly
					(pts
						(arc
							(start -0.2032 -0.2794)
							(mid -0.239121 -0.264521)
							(end -0.254 -0.2286)
						)
						(arc
							(start -0.254 0.2286)
							(mid -0.239121 0.264521)
							(end -0.2032 0.2794)
						)
						(arc
							(start 0.2032 0.2794)
							(mid 0.239121 0.264521)
							(end 0.254 0.2286)
						)
						(arc
							(start 0.254 -0.2286)
							(mid 0.239121 -0.264521)
							(end 0.2032 -0.2794)
						)
					)
					(width 0)
					(fill yes)
				)
			)
		)
	)
	(footprint ""
		(layer "F.Cu")
		(at 155.575 -55.372)
		(property "Reference" "R290"
			(at 0 0 0)
			(layer "F.SilkS")
			(hide yes)
			(effects
				(font
					(size 1.27 1.27)
				)
			)
		)
		(property "Value" "33R2F-3-GP"
			(at 1.7907 -1.1176 0)
			(unlocked yes)
			(layer "F.Fab")
			(hide yes)
			(effects
				(font
					(size 1.016 1.016)
					(thickness 0.1524)
				)
			)
		)
		(property "Device Type" "R402H16"
			(at 1.7907 -2.6416 0)
			(unlocked yes)
			(layer "F.Fab")
			(hide yes)
			(effects
				(font
					(size 1.016 1.016)
					(thickness 0.1524)
				)
			)
		)
		(duplicate_pad_numbers_are_jumpers no)
		(fp_rect
			(start -0.381 0.8382)
			(end 0.381 -0.8382)
			(stroke
				(width 0)
				(type default)
			)
			(fill no)
			(layer "F.CrtYd")
		)
		(fp_rect
			(start -0.381 0.8382)
			(end 0.381 -0.8382)
			(stroke
				(width 0)
				(type default)
			)
			(fill no)
			(layer "F.Fab")
		)
		(pad "1" smd custom
			(at 0 -0.4318)
			(size 0.127 0.127)
			(layers "F.Cu" "F.Mask" "F.Paste")
			(net "C_R_ASDO")
			(options
				(clearance outline)
				(anchor circle)
			)
			(primitives
				(gr_poly
					(pts
						(arc
							(start -0.2032 -0.2794)
							(mid -0.239121 -0.264521)
							(end -0.254 -0.2286)
						)
						(arc
							(start -0.254 0.2286)
							(mid -0.239121 0.264521)
							(end -0.2032 0.2794)
						)
						(arc
							(start 0.2032 0.2794)
							(mid 0.239121 0.264521)
							(end 0.254 0.2286)
						)
						(arc
							(start 0.254 -0.2286)
							(mid 0.239121 -0.264521)
							(end 0.2032 -0.2794)
						)
					)
					(width 0)
					(fill yes)
				)
			)
		)
		(pad "2" smd custom
			(at 0 0.4318)
			(size 0.127 0.127)
			(layers "F.Cu" "F.Mask" "F.Paste")
			(net "C_ASDO")
			(options
				(clearance outline)
				(anchor circle)
			)
			(primitives
				(gr_poly
					(pts
						(arc
							(start -0.2032 -0.2794)
							(mid -0.239121 -0.264521)
							(end -0.254 -0.2286)
						)
						(arc
							(start -0.254 0.2286)
							(mid -0.239121 0.264521)
							(end -0.2032 0.2794)
						)
						(arc
							(start 0.2032 0.2794)
							(mid 0.239121 0.264521)
							(end 0.254 0.2286)
						)
						(arc
							(start 0.254 -0.2286)
							(mid 0.239121 -0.264521)
							(end 0.2032 -0.2794)
						)
					)
					(width 0)
					(fill yes)
				)
			)
		)
	)
	(footprint ""
		(layer "F.Cu")
		(at 31.0896 -60.9346 -90)
		(property "Reference" "PC6"
			(at 0 0 270)
			(layer "F.SilkS")
			(hide yes)
			(effects
				(font
					(size 1.27 1.27)
				)
			)
		)
		(property "Value" "SC47U16V0MX-GP"
			(at -2.3368 -3.5052 270)
			(unlocked yes)
			(layer "F.Fab")
			(hide yes)
			(effects
				(font
					(size 1.016 1.016)
					(thickness 0.1524)
				)
			)
		)
		(property "Device Type" "C1210H107"
			(at -2.3368 -5.0292 270)
			(unlocked yes)
			(layer "F.Fab")
			(hide yes)
			(effects
				(font
					(size 1.016 1.016)
					(thickness 0.1524)
				)
			)
		)
		(duplicate_pad_numbers_are_jumpers no)
		(fp_rect
			(start -1.4986 1.9685)
			(end 1.4986 -1.9685)
			(stroke
				(width 0)
				(type default)
			)
			(fill no)
			(layer "F.CrtYd")
		)
		(fp_rect
			(start -1.4986 1.9685)
			(end 1.4986 -1.9685)
			(stroke
				(width 0)
				(type default)
			)
			(fill no)
			(layer "F.Fab")
		)
		(pad "1" smd rect
			(at 0 -1.2446 270)
			(size 2.7432 1.1938)
			(layers "F.Cu" "F.Mask" "F.Paste")
			(net "VR_FET_SW_P12V_PVCCP_PVNN")
		)
		(pad "2" smd rect
			(at 0 1.2446 270)
			(size 2.7432 1.1938)
			(layers "F.Cu" "F.Mask" "F.Paste")
			(net "GND")
		)
	)
	(footprint ""
		(layer "F.Cu")
		(at 71.882 -19.939 90)
		(property "Reference" "U32"
			(at 0 0 90)
			(layer "F.SilkS")
			(hide yes)
			(effects
				(font
					(size 1.27 1.27)
				)
			)
		)
		(property "Value" "2N7002DW-7F-GP"
			(at -2.5654 1.1049 90)
			(unlocked yes)
			(layer "F.Fab")
			(hide yes)
			(effects
				(font
					(size 1.016 1.016)
					(thickness 0.1524)
				)
			)
		)
		(property "Device Type" "SOT-363H44"
			(at -2.5654 -0.4191 90)
			(unlocked yes)
			(layer "F.Fab")
			(hide yes)
			(effects
				(font
					(size 1.016 1.016)
					(thickness 0.1524)
				)
			)
		)
		(duplicate_pad_numbers_are_jumpers no)
		(fp_poly
			(pts
				(xy -0.6731 1.4351) (xy -0.9779 1.7399) (xy -0.381 1.7399) (xy -0.3683 1.7399) (xy -0.381 1.7272)
			)
			(stroke
				(width 0)
				(type default)
			)
			(fill yes)
			(layer "F.SilkS")
		)
		(fp_poly
			(pts
				(xy 1.2573 0.8763) (xy 1.2573 -0.8763) (xy 0.9525 -0.8763) (xy 0.9525 -1.4351) (xy -0.9525 -1.4351)
				(xy -0.9525 -0.8763) (xy -1.2573 -0.8763) (xy -1.2573 0.8763) (xy -0.9525 0.8763) (xy -0.9525 1.4351)
				(xy 0.9525 1.4351) (xy 0.9525 0.8763)
			)
			(stroke
				(width 0)
				(type default)
			)
			(fill no)
			(layer "F.CrtYd")
		)
		(fp_poly
			(pts
				(xy 1.2573 0.8763) (xy 1.2573 -0.8763) (xy 0.9525 -0.8763) (xy 0.9525 -1.4351) (xy -0.9525 -1.4351)
				(xy -0.9525 -0.8763) (xy -1.2573 -0.8763) (xy -1.2573 0.8763) (xy -0.9525 0.8763) (xy -0.9525 1.4351)
				(xy 0.9525 1.4351) (xy 0.9525 0.8763)
			)
			(stroke
				(width 0)
				(type default)
			)
			(fill no)
			(layer "F.Fab")
		)
		(pad "1" smd rect
			(at -0.65024 0.8255 90)
			(size 0.3556 0.9652)
			(layers "F.Cu" "F.Mask" "F.Paste")
			(net "CPU_TXD")
		)
		(pad "2" smd rect
			(at 0 0.8255 90)
			(size 0.3556 0.9652)
			(layers "F.Cu" "F.Mask" "F.Paste")
			(net "PMU_BUF_PLTRST#")
		)
		(pad "3" smd rect
			(at 0.65024 0.8255 90)
			(size 0.3556 0.9652)
			(layers "F.Cu" "F.Mask" "F.Paste")
			(net "GF_CPU_RXD")
		)
		(pad "4" smd rect
			(at 0.65024 -0.8255 90)
			(size 0.3556 0.9652)
			(layers "F.Cu" "F.Mask" "F.Paste")
			(net "CPU_RXD")
		)
		(pad "5" smd rect
			(at 0 -0.8255 90)
			(size 0.3556 0.9652)
			(layers "F.Cu" "F.Mask" "F.Paste")
			(net "PMU_BUF_PLTRST#")
		)
		(pad "6" smd rect
			(at -0.65024 -0.8255 90)
			(size 0.3556 0.9652)
			(layers "F.Cu" "F.Mask" "F.Paste")
			(net "GF_CPU_TXD")
		)
	)
	(footprint ""
		(layer "F.Cu")
		(at 15.8496 -56.8452 -90)
		(property "Reference" "PR57"
			(at 0 0 270)
			(layer "F.SilkS")
			(hide yes)
			(effects
				(font
					(size 1.27 1.27)
				)
			)
		)
		(property "Value" "10KR2F-2-GP"
			(at 1.7907 -1.1176 270)
			(unlocked yes)
			(layer "F.Fab")
			(hide yes)
			(effects
				(font
					(size 1.016 1.016)
					(thickness 0.1524)
				)
			)
		)
		(property "Device Type" "R402H16"
			(at 1.7907 -2.6416 270)
			(unlocked yes)
			(layer "F.Fab")
			(hide yes)
			(effects
				(font
					(size 1.016 1.016)
					(thickness 0.1524)
				)
			)
		)
		(duplicate_pad_numbers_are_jumpers no)
		(fp_rect
			(start -0.381 0.8382)
			(end 0.381 -0.8382)
			(stroke
				(width 0)
				(type default)
			)
			(fill no)
			(layer "F.CrtYd")
		)
		(fp_rect
			(start -0.381 0.8382)
			(end 0.381 -0.8382)
			(stroke
				(width 0)
				(type default)
			)
			(fill no)
			(layer "F.Fab")
		)
		(pad "1" smd custom
			(at 0 -0.4318 270)
			(size 0.127 0.127)
			(layers "F.Cu" "F.Mask" "F.Paste")
			(net "PVCC_PVNN_EN_R")
			(options
				(clearance outline)
				(anchor circle)
			)
			(primitives
				(gr_poly
					(pts
						(arc
							(start -0.2032 -0.2794)
							(mid -0.239121 -0.264521)
							(end -0.254 -0.2286)
						)
						(arc
							(start -0.254 0.2286)
							(mid -0.239121 0.264521)
							(end -0.2032 0.2794)
						)
						(arc
							(start 0.2032 0.2794)
							(mid 0.239121 0.264521)
							(end 0.254 0.2286)
						)
						(arc
							(start 0.254 -0.2286)
							(mid 0.239121 -0.264521)
							(end 0.2032 -0.2794)
						)
					)
					(width 0)
					(fill yes)
				)
			)
		)
		(pad "2" smd custom
			(at 0 0.4318 270)
			(size 0.127 0.127)
			(layers "F.Cu" "F.Mask" "F.Paste")
			(net "P3V3_STBY")
			(options
				(clearance outline)
				(anchor circle)
			)
			(primitives
				(gr_poly
					(pts
						(arc
							(start -0.2032 -0.2794)
							(mid -0.239121 -0.264521)
							(end -0.254 -0.2286)
						)
						(arc
							(start -0.254 0.2286)
							(mid -0.239121 0.264521)
							(end -0.2032 0.2794)
						)
						(arc
							(start 0.2032 0.2794)
							(mid 0.239121 0.264521)
							(end 0.254 0.2286)
						)
						(arc
							(start 0.254 -0.2286)
							(mid 0.239121 -0.264521)
							(end 0.2032 -0.2794)
						)
					)
					(width 0)
					(fill yes)
				)
			)
		)
	)
	(footprint ""
		(layer "F.Cu")
		(at 68.3768 -58.9534 90)
		(property "Reference" "R146"
			(at 0 0 90)
			(layer "F.SilkS")
			(hide yes)
			(effects
				(font
					(size 1.27 1.27)
				)
			)
		)
		(property "Value" "10KR2F-2-GP"
			(at 1.7907 -1.1176 90)
			(unlocked yes)
			(layer "F.Fab")
			(hide yes)
			(effects
				(font
					(size 1.016 1.016)
					(thickness 0.1524)
				)
			)
		)
		(property "Device Type" "R402H16"
			(at 1.7907 -2.6416 90)
			(unlocked yes)
			(layer "F.Fab")
			(hide yes)
			(effects
				(font
					(size 1.016 1.016)
					(thickness 0.1524)
				)
			)
		)
		(duplicate_pad_numbers_are_jumpers no)
		(fp_rect
			(start -0.381 0.8382)
			(end 0.381 -0.8382)
			(stroke
				(width 0)
				(type default)
			)
			(fill no)
			(layer "F.CrtYd")
		)
		(fp_rect
			(start -0.381 0.8382)
			(end 0.381 -0.8382)
			(stroke
				(width 0)
				(type default)
			)
			(fill no)
			(layer "F.Fab")
		)
		(pad "1" smd custom
			(at 0 -0.4318 90)
			(size 0.127 0.127)
			(layers "F.Cu" "F.Mask" "F.Paste")
			(net "P3V3")
			(options
				(clearance outline)
				(anchor circle)
			)
			(primitives
				(gr_poly
					(pts
						(arc
							(start -0.2032 -0.2794)
							(mid -0.239121 -0.264521)
							(end -0.254 -0.2286)
						)
						(arc
							(start -0.254 0.2286)
							(mid -0.239121 0.264521)
							(end -0.2032 0.2794)
						)
						(arc
							(start 0.2032 0.2794)
							(mid 0.239121 0.264521)
							(end 0.254 0.2286)
						)
						(arc
							(start 0.254 -0.2286)
							(mid 0.239121 -0.264521)
							(end 0.2032 -0.2794)
						)
					)
					(width 0)
					(fill yes)
				)
			)
		)
		(pad "2" smd custom
			(at 0 0.4318 90)
			(size 0.127 0.127)
			(layers "F.Cu" "F.Mask" "F.Paste")
			(net "P3V3_SENSE")
			(options
				(clearance outline)
				(anchor circle)
			)
			(primitives
				(gr_poly
					(pts
						(arc
							(start -0.2032 -0.2794)
							(mid -0.239121 -0.264521)
							(end -0.254 -0.2286)
						)
						(arc
							(start -0.254 0.2286)
							(mid -0.239121 0.264521)
							(end -0.2032 0.2794)
						)
						(arc
							(start 0.2032 0.2794)
							(mid 0.239121 0.264521)
							(end 0.254 0.2286)
						)
						(arc
							(start 0.254 -0.2286)
							(mid 0.239121 -0.264521)
							(end 0.2032 -0.2794)
						)
					)
					(width 0)
					(fill yes)
				)
			)
		)
	)
	(footprint ""
		(layer "F.Cu")
		(at 204.597 -35.56 180)
		(property "Reference" "PC82"
			(at 0 0 180)
			(layer "F.SilkS")
			(hide yes)
			(effects
				(font
					(size 1.27 1.27)
				)
			)
		)
		(property "Value" "SCD1U25V2KX-2-GP"
			(at 1.8923 -1.2065 180)
			(unlocked yes)
			(layer "F.Fab")
			(hide yes)
			(effects
				(font
					(size 1.016 1.016)
					(thickness 0.1524)
				)
			)
		)
		(property "Device Type" "C402H22"
			(at 1.8923 -2.7305 180)
			(unlocked yes)
			(layer "F.Fab")
			(hide yes)
			(effects
				(font
					(size 1.016 1.016)
					(thickness 0.1524)
				)
			)
		)
		(duplicate_pad_numbers_are_jumpers no)
		(fp_rect
			(start -0.381 0.7366)
			(end 0.381 -0.7366)
			(stroke
				(width 0)
				(type default)
			)
			(fill no)
			(layer "F.CrtYd")
		)
		(fp_rect
			(start -0.381 0.7366)
			(end 0.381 -0.7366)
			(stroke
				(width 0)
				(type default)
			)
			(fill no)
			(layer "F.Fab")
		)
		(pad "1" smd custom
			(at 0 -0.4572 180)
			(size 0.1143 0.1143)
			(layers "F.Cu" "F.Mask" "F.Paste")
			(net "PVDDR_VIN")
			(options
				(clearance outline)
				(anchor circle)
			)
			(primitives
				(gr_poly
					(pts
						(arc
							(start -0.254 -0.1778)
							(mid -0.239121 -0.213721)
							(end -0.2032 -0.2286)
						)
						(arc
							(start 0.2032 -0.2286)
							(mid 0.239121 -0.213721)
							(end 0.254 -0.1778)
						)
						(arc
							(start 0.254 0.1778)
							(mid 0.239121 0.213721)
							(end 0.2032 0.2286)
						)
						(arc
							(start -0.2032 0.2286)
							(mid -0.239121 0.213721)
							(end -0.254 0.1778)
						)
					)
					(width 0)
					(fill yes)
				)
			)
		)
		(pad "2" smd custom
			(at 0 0.4572 180)
			(size 0.1143 0.1143)
			(layers "F.Cu" "F.Mask" "F.Paste")
			(net "GND")
			(options
				(clearance outline)
				(anchor circle)
			)
			(primitives
				(gr_poly
					(pts
						(arc
							(start -0.254 -0.1778)
							(mid -0.239121 -0.213721)
							(end -0.2032 -0.2286)
						)
						(arc
							(start 0.2032 -0.2286)
							(mid 0.239121 -0.213721)
							(end 0.254 -0.1778)
						)
						(arc
							(start 0.254 0.1778)
							(mid 0.239121 0.213721)
							(end 0.2032 0.2286)
						)
						(arc
							(start -0.2032 0.2286)
							(mid -0.239121 0.213721)
							(end -0.254 0.1778)
						)
					)
					(width 0)
					(fill yes)
				)
			)
		)
	)
	(footprint ""
		(layer "F.Cu")
		(at 74.168 -43.307 90)
		(property "Reference" "R73"
			(at 0 0 90)
			(layer "F.SilkS")
			(hide yes)
			(effects
				(font
					(size 1.27 1.27)
				)
			)
		)
		(property "Value" "4K7R2F-GP"
			(at 0.064008 -3.993896 90)
			(unlocked yes)
			(layer "F.Fab")
			(hide yes)
			(effects
				(font
					(size 1.016 1.016)
					(thickness 0.1524)
				)
			)
		)
		(property "Device Type" "R402H16"
			(at 0.064008 -5.517896 90)
			(unlocked yes)
			(layer "F.Fab")
			(hide yes)
			(effects
				(font
					(size 1.016 1.016)
					(thickness 0.1524)
				)
			)
		)
		(duplicate_pad_numbers_are_jumpers no)
		(fp_rect
			(start -0.381 0.8382)
			(end 0.381 -0.8382)
			(stroke
				(width 0)
				(type default)
			)
			(fill no)
			(layer "F.CrtYd")
		)
		(fp_rect
			(start -0.381 0.8382)
			(end 0.381 -0.8382)
			(stroke
				(width 0)
				(type default)
			)
			(fill no)
			(layer "F.Fab")
		)
		(pad "1" smd custom
			(at 0 -0.4318 90)
			(size 0.127 0.127)
			(layers "F.Cu" "F.Mask" "F.Paste")
			(net "P3V3")
			(options
				(clearance outline)
				(anchor circle)
			)
			(primitives
				(gr_poly
					(pts
						(arc
							(start -0.2032 -0.2794)
							(mid -0.239121 -0.264521)
							(end -0.254 -0.2286)
						)
						(arc
							(start -0.254 0.2286)
							(mid -0.239121 0.264521)
							(end -0.2032 0.2794)
						)
						(arc
							(start 0.2032 0.2794)
							(mid 0.239121 0.264521)
							(end 0.254 0.2286)
						)
						(arc
							(start 0.254 -0.2286)
							(mid 0.239121 -0.264521)
							(end 0.2032 -0.2794)
						)
					)
					(width 0)
					(fill yes)
				)
			)
		)
		(pad "2" smd custom
			(at 0 0.4318 90)
			(size 0.127 0.127)
			(layers "F.Cu" "F.Mask" "F.Paste")
			(net "CPU_ERR_N0")
			(options
				(clearance outline)
				(anchor circle)
			)
			(primitives
				(gr_poly
					(pts
						(arc
							(start -0.2032 -0.2794)
							(mid -0.239121 -0.264521)
							(end -0.254 -0.2286)
						)
						(arc
							(start -0.254 0.2286)
							(mid -0.239121 0.264521)
							(end -0.2032 0.2794)
						)
						(arc
							(start 0.2032 0.2794)
							(mid 0.239121 0.264521)
							(end 0.254 0.2286)
						)
						(arc
							(start 0.254 -0.2286)
							(mid 0.239121 -0.264521)
							(end 0.2032 -0.2794)
						)
					)
					(width 0)
					(fill yes)
				)
			)
		)
	)
	(footprint ""
		(layer "F.Cu")
		(at 189.611 -40.259 90)
		(property "Reference" "PR119"
			(at 0 0 90)
			(layer "F.SilkS")
			(hide yes)
			(effects
				(font
					(size 1.27 1.27)
				)
			)
		)
		(property "Value" "0R2J-2-GP"
			(at 1.7907 -1.1176 90)
			(unlocked yes)
			(layer "F.Fab")
			(hide yes)
			(effects
				(font
					(size 1.016 1.016)
					(thickness 0.1524)
				)
			)
		)
		(property "Device Type" "R402H16"
			(at 1.7907 -2.6416 90)
			(unlocked yes)
			(layer "F.Fab")
			(hide yes)
			(effects
				(font
					(size 1.016 1.016)
					(thickness 0.1524)
				)
			)
		)
		(duplicate_pad_numbers_are_jumpers no)
		(fp_rect
			(start -0.381 0.8382)
			(end 0.381 -0.8382)
			(stroke
				(width 0)
				(type default)
			)
			(fill no)
			(layer "F.CrtYd")
		)
		(fp_rect
			(start -0.381 0.8382)
			(end 0.381 -0.8382)
			(stroke
				(width 0)
				(type default)
			)
			(fill no)
			(layer "F.Fab")
		)
		(pad "1" smd custom
			(at 0 -0.4318 90)
			(size 0.127 0.127)
			(layers "F.Cu" "F.Mask" "F.Paste")
			(net "VR_PVDDR_A_VAUTO")
			(options
				(clearance outline)
				(anchor circle)
			)
			(primitives
				(gr_poly
					(pts
						(arc
							(start -0.2032 -0.2794)
							(mid -0.239121 -0.264521)
							(end -0.254 -0.2286)
						)
						(arc
							(start -0.254 0.2286)
							(mid -0.239121 0.264521)
							(end -0.2032 0.2794)
						)
						(arc
							(start 0.2032 0.2794)
							(mid 0.239121 0.264521)
							(end 0.254 0.2286)
						)
						(arc
							(start 0.254 -0.2286)
							(mid 0.239121 -0.264521)
							(end 0.2032 -0.2794)
						)
					)
					(width 0)
					(fill yes)
				)
			)
		)
		(pad "2" smd custom
			(at 0 0.4318 90)
			(size 0.127 0.127)
			(layers "F.Cu" "F.Mask" "F.Paste")
			(net "GND")
			(options
				(clearance outline)
				(anchor circle)
			)
			(primitives
				(gr_poly
					(pts
						(arc
							(start -0.2032 -0.2794)
							(mid -0.239121 -0.264521)
							(end -0.254 -0.2286)
						)
						(arc
							(start -0.254 0.2286)
							(mid -0.239121 0.264521)
							(end -0.2032 0.2794)
						)
						(arc
							(start 0.2032 0.2794)
							(mid 0.239121 0.264521)
							(end 0.254 0.2286)
						)
						(arc
							(start 0.254 -0.2286)
							(mid 0.239121 -0.264521)
							(end 0.2032 -0.2794)
						)
					)
					(width 0)
					(fill yes)
				)
			)
		)
	)
	(footprint ""
		(layer "F.Cu")
		(at 31.369 -30.734 -90)
		(property "Reference" "R272"
			(at 0 0 270)
			(layer "F.SilkS")
			(hide yes)
			(effects
				(font
					(size 1.27 1.27)
				)
			)
		)
		(property "Value" "1KR3J-L1-GP"
			(at -0.0254 -2.5146 270)
			(unlocked yes)
			(layer "F.Fab")
			(hide yes)
			(effects
				(font
					(size 1.016 1.016)
					(thickness 0.1524)
				)
			)
		)
		(property "Device Type" "R603H22"
			(at -0.0254 -4.0386 270)
			(unlocked yes)
			(layer "F.Fab")
			(hide yes)
			(effects
				(font
					(size 1.016 1.016)
					(thickness 0.1524)
				)
			)
		)
		(duplicate_pad_numbers_are_jumpers no)
		(fp_line
			(start -0.2032 0)
			(end -0.4191 0)
			(stroke
				(width 0.2032)
				(type default)
			)
			(layer "F.SilkS")
		)
		(fp_line
			(start 0.4318 0)
			(end 0.2032 0)
			(stroke
				(width 0.2032)
				(type default)
			)
			(layer "F.SilkS")
		)
		(fp_rect
			(start -0.635 1.1811)
			(end 0.635 -1.1811)
			(stroke
				(width 0)
				(type default)
			)
			(fill no)
			(layer "F.CrtYd")
		)
		(fp_rect
			(start -0.635 1.1811)
			(end 0.635 -1.1811)
			(stroke
				(width 0)
				(type default)
			)
			(fill no)
			(layer "F.Fab")
		)
		(pad "1" smd custom
			(at 0 -0.6604 270)
			(size 0.19685 0.19685)
			(layers "F.Cu" "F.Mask" "F.Paste")
			(net "XDP_CPU_R_RESET#")
			(options
				(clearance outline)
				(anchor circle)
			)
			(primitives
				(gr_poly
					(pts
						(arc
							(start 0.508 -0.2921)
							(mid 0.478242 -0.363942)
							(end 0.4064 -0.3937)
						)
						(arc
							(start -0.4064 -0.3937)
							(mid -0.478242 -0.363942)
							(end -0.508 -0.2921)
						)
						(arc
							(start -0.508 0.2921)
							(mid -0.478242 0.363942)
							(end -0.4064 0.3937)
						)
						(arc
							(start 0.4064 0.3937)
							(mid 0.478242 0.363942)
							(end 0.508 0.2921)
						)
					)
					(width 0)
					(fill yes)
				)
			)
		)
		(pad "2" smd custom
			(at 0 0.6604 270)
			(size 0.19685 0.19685)
			(layers "F.Cu" "F.Mask" "F.Paste")
			(net "XDP_CPU_RESET#")
			(options
				(clearance outline)
				(anchor circle)
			)
			(primitives
				(gr_poly
					(pts
						(arc
							(start 0.508 -0.2921)
							(mid 0.478242 -0.363942)
							(end 0.4064 -0.3937)
						)
						(arc
							(start -0.4064 -0.3937)
							(mid -0.478242 -0.363942)
							(end -0.508 -0.2921)
						)
						(arc
							(start -0.508 0.2921)
							(mid -0.478242 0.363942)
							(end -0.4064 0.3937)
						)
						(arc
							(start 0.4064 0.3937)
							(mid 0.478242 0.363942)
							(end 0.508 0.2921)
						)
					)
					(width 0)
					(fill yes)
				)
			)
		)
	)
	(footprint ""
		(layer "F.Cu")
		(at 46.863 -16.0782 180)
		(property "Reference" "R359"
			(at 0 0 180)
			(layer "F.SilkS")
			(hide yes)
			(effects
				(font
					(size 1.27 1.27)
				)
			)
		)
		(property "Value" "4K7R2F-GP"
			(at 0.064008 -3.993896 180)
			(unlocked yes)
			(layer "F.Fab")
			(hide yes)
			(effects
				(font
					(size 1.016 1.016)
					(thickness 0.1524)
				)
			)
		)
		(property "Device Type" "R402H16"
			(at 0.064008 -5.517896 180)
			(unlocked yes)
			(layer "F.Fab")
			(hide yes)
			(effects
				(font
					(size 1.016 1.016)
					(thickness 0.1524)
				)
			)
		)
		(duplicate_pad_numbers_are_jumpers no)
		(fp_rect
			(start -0.381 0.8382)
			(end 0.381 -0.8382)
			(stroke
				(width 0)
				(type default)
			)
			(fill no)
			(layer "F.CrtYd")
		)
		(fp_rect
			(start -0.381 0.8382)
			(end 0.381 -0.8382)
			(stroke
				(width 0)
				(type default)
			)
			(fill no)
			(layer "F.Fab")
		)
		(pad "1" smd custom
			(at 0 -0.4318 180)
			(size 0.127 0.127)
			(layers "F.Cu" "F.Mask" "F.Paste")
			(net "P3V3")
			(options
				(clearance outline)
				(anchor circle)
			)
			(primitives
				(gr_poly
					(pts
						(arc
							(start -0.2032 -0.2794)
							(mid -0.239121 -0.264521)
							(end -0.254 -0.2286)
						)
						(arc
							(start -0.254 0.2286)
							(mid -0.239121 0.264521)
							(end -0.2032 0.2794)
						)
						(arc
							(start 0.2032 0.2794)
							(mid 0.239121 0.264521)
							(end 0.254 0.2286)
						)
						(arc
							(start 0.254 -0.2286)
							(mid 0.239121 -0.264521)
							(end 0.2032 -0.2794)
						)
					)
					(width 0)
					(fill yes)
				)
			)
		)
		(pad "2" smd custom
			(at 0 0.4318 180)
			(size 0.127 0.127)
			(layers "F.Cu" "F.Mask" "F.Paste")
			(net "CLKBUFF_OE2#")
			(options
				(clearance outline)
				(anchor circle)
			)
			(primitives
				(gr_poly
					(pts
						(arc
							(start -0.2032 -0.2794)
							(mid -0.239121 -0.264521)
							(end -0.254 -0.2286)
						)
						(arc
							(start -0.254 0.2286)
							(mid -0.239121 0.264521)
							(end -0.2032 0.2794)
						)
						(arc
							(start 0.2032 0.2794)
							(mid 0.239121 0.264521)
							(end 0.254 0.2286)
						)
						(arc
							(start 0.254 -0.2286)
							(mid 0.239121 -0.264521)
							(end 0.2032 -0.2794)
						)
					)
					(width 0)
					(fill yes)
				)
			)
		)
	)
	(footprint ""
		(layer "F.Cu")
		(at 51.816 -50.8)
		(property "Reference" "PR153"
			(at 0 0 0)
			(layer "F.SilkS")
			(hide yes)
			(effects
				(font
					(size 1.27 1.27)
				)
			)
		)
		(property "Value" "0R3J-6-GP"
			(at -0.0254 -2.0193 0)
			(unlocked yes)
			(layer "F.Fab")
			(hide yes)
			(effects
				(font
					(size 1.016 1.016)
					(thickness 0.1524)
				)
			)
		)
		(property "Device Type" "R603H22"
			(at -0.0254 -3.5433 0)
			(unlocked yes)
			(layer "F.Fab")
			(hide yes)
			(effects
				(font
					(size 1.016 1.016)
					(thickness 0.1524)
				)
			)
		)
		(duplicate_pad_numbers_are_jumpers no)
		(fp_line
			(start -0.2032 0)
			(end -0.4191 0)
			(stroke
				(width 0.2032)
				(type default)
			)
			(layer "F.SilkS")
		)
		(fp_line
			(start 0.4318 0)
			(end 0.2032 0)
			(stroke
				(width 0.2032)
				(type default)
			)
			(layer "F.SilkS")
		)
		(fp_rect
			(start -0.635 1.1811)
			(end 0.635 -1.1811)
			(stroke
				(width 0)
				(type default)
			)
			(fill no)
			(layer "F.CrtYd")
		)
		(fp_rect
			(start -0.635 1.1811)
			(end 0.635 -1.1811)
			(stroke
				(width 0)
				(type default)
			)
			(fill no)
			(layer "F.Fab")
		)
		(pad "1" smd custom
			(at 0 -0.6604)
			(size 0.19685 0.19685)
			(layers "F.Cu" "F.Mask" "F.Paste")
			(net "P3V3_STBY")
			(options
				(clearance outline)
				(anchor circle)
			)
			(primitives
				(gr_poly
					(pts
						(arc
							(start 0.508 -0.2921)
							(mid 0.478242 -0.363942)
							(end 0.4064 -0.3937)
						)
						(arc
							(start -0.4064 -0.3937)
							(mid -0.478242 -0.363942)
							(end -0.508 -0.2921)
						)
						(arc
							(start -0.508 0.2921)
							(mid -0.478242 0.363942)
							(end -0.4064 0.3937)
						)
						(arc
							(start 0.4064 0.3937)
							(mid 0.478242 0.363942)
							(end 0.508 0.2921)
						)
					)
					(width 0)
					(fill yes)
				)
			)
		)
		(pad "2" smd custom
			(at 0 0.6604)
			(size 0.19685 0.19685)
			(layers "F.Cu" "F.Mask" "F.Paste")
			(net "VR_PVIN_P1V0_STBY")
			(options
				(clearance outline)
				(anchor circle)
			)
			(primitives
				(gr_poly
					(pts
						(arc
							(start 0.508 -0.2921)
							(mid 0.478242 -0.363942)
							(end 0.4064 -0.3937)
						)
						(arc
							(start -0.4064 -0.3937)
							(mid -0.478242 -0.363942)
							(end -0.508 -0.2921)
						)
						(arc
							(start -0.508 0.2921)
							(mid -0.478242 0.363942)
							(end -0.4064 0.3937)
						)
						(arc
							(start 0.4064 0.3937)
							(mid 0.478242 0.363942)
							(end 0.508 0.2921)
						)
					)
					(width 0)
					(fill yes)
				)
			)
		)
	)
	(footprint ""
		(layer "F.Cu")
		(at 68.834 -57.7088)
		(property "Reference" "R503"
			(at 0 0 0)
			(layer "F.SilkS")
			(hide yes)
			(effects
				(font
					(size 1.27 1.27)
				)
			)
		)
		(property "Value" "10KR2F-2-GP"
			(at 1.7907 -1.1176 0)
			(unlocked yes)
			(layer "F.Fab")
			(hide yes)
			(effects
				(font
					(size 1.016 1.016)
					(thickness 0.1524)
				)
			)
		)
		(property "Device Type" "R402H16"
			(at 1.7907 -2.6416 0)
			(unlocked yes)
			(layer "F.Fab")
			(hide yes)
			(effects
				(font
					(size 1.016 1.016)
					(thickness 0.1524)
				)
			)
		)
		(duplicate_pad_numbers_are_jumpers no)
		(fp_rect
			(start -0.381 0.8382)
			(end 0.381 -0.8382)
			(stroke
				(width 0)
				(type default)
			)
			(fill no)
			(layer "F.CrtYd")
		)
		(fp_rect
			(start -0.381 0.8382)
			(end 0.381 -0.8382)
			(stroke
				(width 0)
				(type default)
			)
			(fill no)
			(layer "F.Fab")
		)
		(pad "1" smd custom
			(at 0 -0.4318)
			(size 0.127 0.127)
			(layers "F.Cu" "F.Mask" "F.Paste")
			(net "P3V3_SENSE")
			(options
				(clearance outline)
				(anchor circle)
			)
			(primitives
				(gr_poly
					(pts
						(arc
							(start -0.2032 -0.2794)
							(mid -0.239121 -0.264521)
							(end -0.254 -0.2286)
						)
						(arc
							(start -0.254 0.2286)
							(mid -0.239121 0.264521)
							(end -0.2032 0.2794)
						)
						(arc
							(start 0.2032 0.2794)
							(mid 0.239121 0.264521)
							(end 0.254 0.2286)
						)
						(arc
							(start 0.254 -0.2286)
							(mid 0.239121 -0.264521)
							(end 0.2032 -0.2794)
						)
					)
					(width 0)
					(fill yes)
				)
			)
		)
		(pad "2" smd custom
			(at 0 0.4318)
			(size 0.127 0.127)
			(layers "F.Cu" "F.Mask" "F.Paste")
			(net "GND")
			(options
				(clearance outline)
				(anchor circle)
			)
			(primitives
				(gr_poly
					(pts
						(arc
							(start -0.2032 -0.2794)
							(mid -0.239121 -0.264521)
							(end -0.254 -0.2286)
						)
						(arc
							(start -0.254 0.2286)
							(mid -0.239121 0.264521)
							(end -0.2032 0.2794)
						)
						(arc
							(start 0.2032 0.2794)
							(mid 0.239121 0.264521)
							(end 0.254 0.2286)
						)
						(arc
							(start 0.254 -0.2286)
							(mid 0.239121 -0.264521)
							(end 0.2032 -0.2794)
						)
					)
					(width 0)
					(fill yes)
				)
			)
		)
	)
	(footprint ""
		(layer "F.Cu")
		(at 19.6596 -50.9524)
		(property "Reference" "PR94"
			(at 0 0 0)
			(layer "F.SilkS")
			(hide yes)
			(effects
				(font
					(size 1.27 1.27)
				)
			)
		)
		(property "Value" "100R3F-1-GP"
			(at -0.0254 -2.0193 0)
			(unlocked yes)
			(layer "F.Fab")
			(hide yes)
			(effects
				(font
					(size 1.016 1.016)
					(thickness 0.1524)
				)
			)
		)
		(property "Device Type" "R603H22"
			(at -0.0254 -3.5433 0)
			(unlocked yes)
			(layer "F.Fab")
			(hide yes)
			(effects
				(font
					(size 1.016 1.016)
					(thickness 0.1524)
				)
			)
		)
		(duplicate_pad_numbers_are_jumpers no)
		(fp_line
			(start -0.2032 0)
			(end -0.4191 0)
			(stroke
				(width 0.2032)
				(type default)
			)
			(layer "F.SilkS")
		)
		(fp_line
			(start 0.4318 0)
			(end 0.2032 0)
			(stroke
				(width 0.2032)
				(type default)
			)
			(layer "F.SilkS")
		)
		(fp_rect
			(start -0.635 1.1811)
			(end 0.635 -1.1811)
			(stroke
				(width 0)
				(type default)
			)
			(fill no)
			(layer "F.CrtYd")
		)
		(fp_rect
			(start -0.635 1.1811)
			(end 0.635 -1.1811)
			(stroke
				(width 0)
				(type default)
			)
			(fill no)
			(layer "F.Fab")
		)
		(pad "1" smd custom
			(at 0 -0.6604)
			(size 0.19685 0.19685)
			(layers "F.Cu" "F.Mask" "F.Paste")
			(net "VR_PVCCP_FB")
			(options
				(clearance outline)
				(anchor circle)
			)
			(primitives
				(gr_poly
					(pts
						(arc
							(start 0.508 -0.2921)
							(mid 0.478242 -0.363942)
							(end 0.4064 -0.3937)
						)
						(arc
							(start -0.4064 -0.3937)
							(mid -0.478242 -0.363942)
							(end -0.508 -0.2921)
						)
						(arc
							(start -0.508 0.2921)
							(mid -0.478242 0.363942)
							(end -0.4064 0.3937)
						)
						(arc
							(start 0.4064 0.3937)
							(mid 0.478242 0.363942)
							(end 0.508 0.2921)
						)
					)
					(width 0)
					(fill yes)
				)
			)
		)
		(pad "2" smd custom
			(at 0 0.6604)
			(size 0.19685 0.19685)
			(layers "F.Cu" "F.Mask" "F.Paste")
			(net "VR_PVCCP_FB_RC1")
			(options
				(clearance outline)
				(anchor circle)
			)
			(primitives
				(gr_poly
					(pts
						(arc
							(start 0.508 -0.2921)
							(mid 0.478242 -0.363942)
							(end 0.4064 -0.3937)
						)
						(arc
							(start -0.4064 -0.3937)
							(mid -0.478242 -0.363942)
							(end -0.508 -0.2921)
						)
						(arc
							(start -0.508 0.2921)
							(mid -0.478242 0.363942)
							(end -0.4064 0.3937)
						)
						(arc
							(start 0.4064 0.3937)
							(mid 0.478242 0.363942)
							(end 0.508 0.2921)
						)
					)
					(width 0)
					(fill yes)
				)
			)
		)
	)
	(footprint ""
		(layer "F.Cu")
		(at 157.353 -59.309)
		(property "Reference" "C327"
			(at 0 0 0)
			(layer "F.SilkS")
			(hide yes)
			(effects
				(font
					(size 1.27 1.27)
				)
			)
		)
		(property "Value" "SCD1U16V2KX-3GP"
			(at 1.8923 -1.2065 0)
			(unlocked yes)
			(layer "F.Fab")
			(hide yes)
			(effects
				(font
					(size 1.016 1.016)
					(thickness 0.1524)
				)
			)
		)
		(property "Device Type" "C402H22"
			(at 1.8923 -2.7305 0)
			(unlocked yes)
			(layer "F.Fab")
			(hide yes)
			(effects
				(font
					(size 1.016 1.016)
					(thickness 0.1524)
				)
			)
		)
		(duplicate_pad_numbers_are_jumpers no)
		(fp_rect
			(start -0.381 0.7366)
			(end 0.381 -0.7366)
			(stroke
				(width 0)
				(type default)
			)
			(fill no)
			(layer "F.CrtYd")
		)
		(fp_rect
			(start -0.381 0.7366)
			(end 0.381 -0.7366)
			(stroke
				(width 0)
				(type default)
			)
			(fill no)
			(layer "F.Fab")
		)
		(pad "1" smd custom
			(at 0 -0.4572)
			(size 0.1143 0.1143)
			(layers "F.Cu" "F.Mask" "F.Paste")
			(net "PV_VDDR")
			(options
				(clearance outline)
				(anchor circle)
			)
			(primitives
				(gr_poly
					(pts
						(arc
							(start -0.254 -0.1778)
							(mid -0.239121 -0.213721)
							(end -0.2032 -0.2286)
						)
						(arc
							(start 0.2032 -0.2286)
							(mid 0.239121 -0.213721)
							(end 0.254 -0.1778)
						)
						(arc
							(start 0.254 0.1778)
							(mid 0.239121 0.213721)
							(end 0.2032 0.2286)
						)
						(arc
							(start -0.2032 0.2286)
							(mid -0.239121 0.213721)
							(end -0.254 0.1778)
						)
					)
					(width 0)
					(fill yes)
				)
			)
		)
		(pad "2" smd custom
			(at 0 0.4572)
			(size 0.1143 0.1143)
			(layers "F.Cu" "F.Mask" "F.Paste")
			(net "GND")
			(options
				(clearance outline)
				(anchor circle)
			)
			(primitives
				(gr_poly
					(pts
						(arc
							(start -0.254 -0.1778)
							(mid -0.239121 -0.213721)
							(end -0.2032 -0.2286)
						)
						(arc
							(start 0.2032 -0.2286)
							(mid 0.239121 -0.213721)
							(end 0.254 -0.1778)
						)
						(arc
							(start 0.254 0.1778)
							(mid 0.239121 0.213721)
							(end 0.2032 0.2286)
						)
						(arc
							(start -0.2032 0.2286)
							(mid -0.239121 0.213721)
							(end -0.254 0.1778)
						)
					)
					(width 0)
					(fill yes)
				)
			)
		)
	)
	(footprint ""
		(layer "F.Cu")
		(at 169.545 -42.291 180)
		(property "Reference" "PR228"
			(at 0 0 180)
			(layer "F.SilkS")
			(hide yes)
			(effects
				(font
					(size 1.27 1.27)
				)
			)
		)
		(property "Value" "30K1R2F-L-GP"
			(at 1.7907 -1.1176 180)
			(unlocked yes)
			(layer "F.Fab")
			(hide yes)
			(effects
				(font
					(size 1.016 1.016)
					(thickness 0.1524)
				)
			)
		)
		(property "Device Type" "R402H16"
			(at 1.7907 -2.6416 180)
			(unlocked yes)
			(layer "F.Fab")
			(hide yes)
			(effects
				(font
					(size 1.016 1.016)
					(thickness 0.1524)
				)
			)
		)
		(duplicate_pad_numbers_are_jumpers no)
		(fp_rect
			(start -0.381 0.8382)
			(end 0.381 -0.8382)
			(stroke
				(width 0)
				(type default)
			)
			(fill no)
			(layer "F.CrtYd")
		)
		(fp_rect
			(start -0.381 0.8382)
			(end 0.381 -0.8382)
			(stroke
				(width 0)
				(type default)
			)
			(fill no)
			(layer "F.Fab")
		)
		(pad "1" smd custom
			(at 0 -0.4318 180)
			(size 0.127 0.127)
			(layers "F.Cu" "F.Mask" "F.Paste")
			(net "P2V5_STBY_FB")
			(options
				(clearance outline)
				(anchor circle)
			)
			(primitives
				(gr_poly
					(pts
						(arc
							(start -0.2032 -0.2794)
							(mid -0.239121 -0.264521)
							(end -0.254 -0.2286)
						)
						(arc
							(start -0.254 0.2286)
							(mid -0.239121 0.264521)
							(end -0.2032 0.2794)
						)
						(arc
							(start 0.2032 0.2794)
							(mid 0.239121 0.264521)
							(end 0.254 0.2286)
						)
						(arc
							(start 0.254 -0.2286)
							(mid 0.239121 -0.264521)
							(end 0.2032 -0.2794)
						)
					)
					(width 0)
					(fill yes)
				)
			)
		)
		(pad "2" smd custom
			(at 0 0.4318 180)
			(size 0.127 0.127)
			(layers "F.Cu" "F.Mask" "F.Paste")
			(net "GND")
			(options
				(clearance outline)
				(anchor circle)
			)
			(primitives
				(gr_poly
					(pts
						(arc
							(start -0.2032 -0.2794)
							(mid -0.239121 -0.264521)
							(end -0.254 -0.2286)
						)
						(arc
							(start -0.254 0.2286)
							(mid -0.239121 0.264521)
							(end -0.2032 0.2794)
						)
						(arc
							(start 0.2032 0.2794)
							(mid 0.239121 0.264521)
							(end 0.254 0.2286)
						)
						(arc
							(start 0.254 -0.2286)
							(mid 0.239121 -0.264521)
							(end 0.2032 -0.2794)
						)
					)
					(width 0)
					(fill yes)
				)
			)
		)
	)
	(footprint ""
		(layer "F.Cu")
		(at 44.704 -20.701 -90)
		(property "Reference" "R247"
			(at 0 0 270)
			(layer "F.SilkS")
			(hide yes)
			(effects
				(font
					(size 1.27 1.27)
				)
			)
		)
		(property "Value" "51R2F-2-GP"
			(at 0.064008 -3.993896 270)
			(unlocked yes)
			(layer "F.Fab")
			(hide yes)
			(effects
				(font
					(size 1.016 1.016)
					(thickness 0.1524)
				)
			)
		)
		(property "Device Type" "R402H16"
			(at 0.064008 -5.517896 270)
			(unlocked yes)
			(layer "F.Fab")
			(hide yes)
			(effects
				(font
					(size 1.016 1.016)
					(thickness 0.1524)
				)
			)
		)
		(duplicate_pad_numbers_are_jumpers no)
		(fp_rect
			(start -0.381 0.8382)
			(end 0.381 -0.8382)
			(stroke
				(width 0)
				(type default)
			)
			(fill no)
			(layer "F.CrtYd")
		)
		(fp_rect
			(start -0.381 0.8382)
			(end 0.381 -0.8382)
			(stroke
				(width 0)
				(type default)
			)
			(fill no)
			(layer "F.Fab")
		)
		(pad "1" smd custom
			(at 0 -0.4318 270)
			(size 0.127 0.127)
			(layers "F.Cu" "F.Mask" "F.Paste")
			(net "P1V0")
			(options
				(clearance outline)
				(anchor circle)
			)
			(primitives
				(gr_poly
					(pts
						(arc
							(start -0.2032 -0.2794)
							(mid -0.239121 -0.264521)
							(end -0.254 -0.2286)
						)
						(arc
							(start -0.254 0.2286)
							(mid -0.239121 0.264521)
							(end -0.2032 0.2794)
						)
						(arc
							(start 0.2032 0.2794)
							(mid 0.239121 0.264521)
							(end 0.254 0.2286)
						)
						(arc
							(start 0.254 -0.2286)
							(mid 0.239121 -0.264521)
							(end 0.2032 -0.2794)
						)
					)
					(width 0)
					(fill yes)
				)
			)
		)
		(pad "2" smd custom
			(at 0 0.4318 270)
			(size 0.127 0.127)
			(layers "F.Cu" "F.Mask" "F.Paste")
			(net "XDP_CPU_PREQ#")
			(options
				(clearance outline)
				(anchor circle)
			)
			(primitives
				(gr_poly
					(pts
						(arc
							(start -0.2032 -0.2794)
							(mid -0.239121 -0.264521)
							(end -0.254 -0.2286)
						)
						(arc
							(start -0.254 0.2286)
							(mid -0.239121 0.264521)
							(end -0.2032 0.2794)
						)
						(arc
							(start 0.2032 0.2794)
							(mid 0.239121 0.264521)
							(end 0.254 0.2286)
						)
						(arc
							(start 0.254 -0.2286)
							(mid 0.239121 -0.264521)
							(end 0.2032 -0.2794)
						)
					)
					(width 0)
					(fill yes)
				)
			)
		)
	)
	(footprint ""
		(layer "F.Cu")
		(at 197.739 -3.048 90)
		(property "Reference" "C90"
			(at 0 0 90)
			(layer "F.SilkS")
			(hide yes)
			(effects
				(font
					(size 1.27 1.27)
				)
			)
		)
		(property "Value" "SC10U6D3V3MX-GP"
			(at 0 -2.8194 90)
			(unlocked yes)
			(layer "F.Fab")
			(hide yes)
			(effects
				(font
					(size 1.016 1.016)
					(thickness 0.1524)
				)
			)
		)
		(property "Device Type" "C603H38"
			(at 0 -4.3434 90)
			(unlocked yes)
			(layer "F.Fab")
			(hide yes)
			(effects
				(font
					(size 1.016 1.016)
					(thickness 0.1524)
				)
			)
		)
		(duplicate_pad_numbers_are_jumpers no)
		(fp_line
			(start -0.4064 0)
			(end 0.4064 0)
			(stroke
				(width 0.2286)
				(type default)
			)
			(layer "F.SilkS")
		)
		(fp_rect
			(start -0.635 1.1811)
			(end 0.635 -1.1811)
			(stroke
				(width 0)
				(type default)
			)
			(fill no)
			(layer "F.CrtYd")
		)
		(fp_rect
			(start -0.635 1.1811)
			(end 0.635 -1.1811)
			(stroke
				(width 0)
				(type default)
			)
			(fill no)
			(layer "F.Fab")
		)
		(pad "1" smd custom
			(at 0 -0.6604 90)
			(size 0.19685 0.19685)
			(layers "F.Cu" "F.Mask" "F.Paste")
			(net "PV_VTT_DDR_B")
			(options
				(clearance outline)
				(anchor circle)
			)
			(primitives
				(gr_poly
					(pts
						(arc
							(start 0.508 -0.2921)
							(mid 0.478242 -0.363942)
							(end 0.4064 -0.3937)
						)
						(arc
							(start -0.4064 -0.3937)
							(mid -0.478242 -0.363942)
							(end -0.508 -0.2921)
						)
						(arc
							(start -0.508 0.2921)
							(mid -0.478242 0.363942)
							(end -0.4064 0.3937)
						)
						(arc
							(start 0.4064 0.3937)
							(mid 0.478242 0.363942)
							(end 0.508 0.2921)
						)
					)
					(width 0)
					(fill yes)
				)
			)
		)
		(pad "2" smd custom
			(at 0 0.6604 90)
			(size 0.19685 0.19685)
			(layers "F.Cu" "F.Mask" "F.Paste")
			(net "GND")
			(options
				(clearance outline)
				(anchor circle)
			)
			(primitives
				(gr_poly
					(pts
						(arc
							(start 0.508 -0.2921)
							(mid 0.478242 -0.363942)
							(end 0.4064 -0.3937)
						)
						(arc
							(start -0.4064 -0.3937)
							(mid -0.478242 -0.363942)
							(end -0.508 -0.2921)
						)
						(arc
							(start -0.508 0.2921)
							(mid -0.478242 0.363942)
							(end -0.4064 0.3937)
						)
						(arc
							(start 0.4064 0.3937)
							(mid 0.478242 0.363942)
							(end 0.508 0.2921)
						)
					)
					(width 0)
					(fill yes)
				)
			)
		)
	)
	(footprint ""
		(layer "F.Cu")
		(at 132.842 -19.431 180)
		(property "Reference" "R506"
			(at 0 0 180)
			(layer "F.SilkS")
			(hide yes)
			(effects
				(font
					(size 1.27 1.27)
				)
			)
		)
		(property "Value" "1KR2F-3-GP"
			(at 1.7907 -1.1176 180)
			(unlocked yes)
			(layer "F.Fab")
			(hide yes)
			(effects
				(font
					(size 1.016 1.016)
					(thickness 0.1524)
				)
			)
		)
		(property "Device Type" "R402H16"
			(at 1.7907 -2.6416 180)
			(unlocked yes)
			(layer "F.Fab")
			(hide yes)
			(effects
				(font
					(size 1.016 1.016)
					(thickness 0.1524)
				)
			)
		)
		(duplicate_pad_numbers_are_jumpers no)
		(fp_rect
			(start -0.381 0.8382)
			(end 0.381 -0.8382)
			(stroke
				(width 0)
				(type default)
			)
			(fill no)
			(layer "F.CrtYd")
		)
		(fp_rect
			(start -0.381 0.8382)
			(end 0.381 -0.8382)
			(stroke
				(width 0)
				(type default)
			)
			(fill no)
			(layer "F.Fab")
		)
		(pad "1" smd custom
			(at 0 -0.4318 180)
			(size 0.127 0.127)
			(layers "F.Cu" "F.Mask" "F.Paste")
			(net "POWER_GOOD_R")
			(options
				(clearance outline)
				(anchor circle)
			)
			(primitives
				(gr_poly
					(pts
						(arc
							(start -0.2032 -0.2794)
							(mid -0.239121 -0.264521)
							(end -0.254 -0.2286)
						)
						(arc
							(start -0.254 0.2286)
							(mid -0.239121 0.264521)
							(end -0.2032 0.2794)
						)
						(arc
							(start 0.2032 0.2794)
							(mid 0.239121 0.264521)
							(end 0.254 0.2286)
						)
						(arc
							(start 0.254 -0.2286)
							(mid 0.239121 -0.264521)
							(end 0.2032 -0.2794)
						)
					)
					(width 0)
					(fill yes)
				)
			)
		)
		(pad "2" smd custom
			(at 0 0.4318 180)
			(size 0.127 0.127)
			(layers "F.Cu" "F.Mask" "F.Paste")
			(net "GND")
			(options
				(clearance outline)
				(anchor circle)
			)
			(primitives
				(gr_poly
					(pts
						(arc
							(start -0.2032 -0.2794)
							(mid -0.239121 -0.264521)
							(end -0.254 -0.2286)
						)
						(arc
							(start -0.254 0.2286)
							(mid -0.239121 0.264521)
							(end -0.2032 0.2794)
						)
						(arc
							(start 0.2032 0.2794)
							(mid 0.239121 0.264521)
							(end 0.254 0.2286)
						)
						(arc
							(start 0.254 -0.2286)
							(mid 0.239121 -0.264521)
							(end 0.2032 -0.2794)
						)
					)
					(width 0)
					(fill yes)
				)
			)
		)
	)
	(footprint ""
		(layer "F.Cu")
		(at 38.862 -42.037)
		(property "Reference" "R59"
			(at 0 0 0)
			(layer "F.SilkS")
			(hide yes)
			(effects
				(font
					(size 1.27 1.27)
				)
			)
		)
		(property "Value" "33R2F-3-GP"
			(at 1.7907 -1.1176 0)
			(unlocked yes)
			(layer "F.Fab")
			(hide yes)
			(effects
				(font
					(size 1.016 1.016)
					(thickness 0.1524)
				)
			)
		)
		(property "Device Type" "R402H16"
			(at 1.7907 -2.6416 0)
			(unlocked yes)
			(layer "F.Fab")
			(hide yes)
			(effects
				(font
					(size 1.016 1.016)
					(thickness 0.1524)
				)
			)
		)
		(duplicate_pad_numbers_are_jumpers no)
		(fp_rect
			(start -0.381 0.8382)
			(end 0.381 -0.8382)
			(stroke
				(width 0)
				(type default)
			)
			(fill no)
			(layer "F.CrtYd")
		)
		(fp_rect
			(start -0.381 0.8382)
			(end 0.381 -0.8382)
			(stroke
				(width 0)
				(type default)
			)
			(fill no)
			(layer "F.Fab")
		)
		(pad "1" smd custom
			(at 0 -0.4318)
			(size 0.127 0.127)
			(layers "F.Cu" "F.Mask" "F.Paste")
			(net "P3V3_CPU_PG_S2")
			(options
				(clearance outline)
				(anchor circle)
			)
			(primitives
				(gr_poly
					(pts
						(arc
							(start -0.2032 -0.2794)
							(mid -0.239121 -0.264521)
							(end -0.254 -0.2286)
						)
						(arc
							(start -0.254 0.2286)
							(mid -0.239121 0.264521)
							(end -0.2032 0.2794)
						)
						(arc
							(start 0.2032 0.2794)
							(mid 0.239121 0.264521)
							(end 0.254 0.2286)
						)
						(arc
							(start 0.254 -0.2286)
							(mid 0.239121 -0.264521)
							(end 0.2032 -0.2794)
						)
					)
					(width 0)
					(fill yes)
				)
			)
		)
		(pad "2" smd custom
			(at 0 0.4318)
			(size 0.127 0.127)
			(layers "F.Cu" "F.Mask" "F.Paste")
			(net "CPU_RSMRST#")
			(options
				(clearance outline)
				(anchor circle)
			)
			(primitives
				(gr_poly
					(pts
						(arc
							(start -0.2032 -0.2794)
							(mid -0.239121 -0.264521)
							(end -0.254 -0.2286)
						)
						(arc
							(start -0.254 0.2286)
							(mid -0.239121 0.264521)
							(end -0.2032 0.2794)
						)
						(arc
							(start 0.2032 0.2794)
							(mid 0.239121 0.264521)
							(end 0.254 0.2286)
						)
						(arc
							(start 0.254 -0.2286)
							(mid 0.239121 -0.264521)
							(end 0.2032 -0.2794)
						)
					)
					(width 0)
					(fill yes)
				)
			)
		)
	)
	(footprint ""
		(layer "F.Cu")
		(at 129.3368 -25.781 180)
		(property "Reference" "R483"
			(at 0 0 180)
			(layer "F.SilkS")
			(hide yes)
			(effects
				(font
					(size 1.27 1.27)
				)
			)
		)
		(property "Value" "0R2J-2-GP"
			(at 1.7907 -1.1176 180)
			(unlocked yes)
			(layer "F.Fab")
			(hide yes)
			(effects
				(font
					(size 1.016 1.016)
					(thickness 0.1524)
				)
			)
		)
		(property "Device Type" "R402H16"
			(at 1.7907 -2.6416 180)
			(unlocked yes)
			(layer "F.Fab")
			(hide yes)
			(effects
				(font
					(size 1.016 1.016)
					(thickness 0.1524)
				)
			)
		)
		(duplicate_pad_numbers_are_jumpers no)
		(fp_rect
			(start -0.381 0.8382)
			(end 0.381 -0.8382)
			(stroke
				(width 0)
				(type default)
			)
			(fill no)
			(layer "F.CrtYd")
		)
		(fp_rect
			(start -0.381 0.8382)
			(end 0.381 -0.8382)
			(stroke
				(width 0)
				(type default)
			)
			(fill no)
			(layer "F.Fab")
		)
		(pad "1" smd custom
			(at 0 -0.4318 180)
			(size 0.127 0.127)
			(layers "F.Cu" "F.Mask" "F.Paste")
			(net "PMU_PLTRST#")
			(options
				(clearance outline)
				(anchor circle)
			)
			(primitives
				(gr_poly
					(pts
						(arc
							(start -0.2032 -0.2794)
							(mid -0.239121 -0.264521)
							(end -0.254 -0.2286)
						)
						(arc
							(start -0.254 0.2286)
							(mid -0.239121 0.264521)
							(end -0.2032 0.2794)
						)
						(arc
							(start 0.2032 0.2794)
							(mid 0.239121 0.264521)
							(end 0.254 0.2286)
						)
						(arc
							(start 0.254 -0.2286)
							(mid 0.239121 -0.264521)
							(end 0.2032 -0.2794)
						)
					)
					(width 0)
					(fill yes)
				)
			)
		)
		(pad "2" smd custom
			(at 0 0.4318 180)
			(size 0.127 0.127)
			(layers "F.Cu" "F.Mask" "F.Paste")
			(net "PMU_PLD_R_PLTRST#")
			(options
				(clearance outline)
				(anchor circle)
			)
			(primitives
				(gr_poly
					(pts
						(arc
							(start -0.2032 -0.2794)
							(mid -0.239121 -0.264521)
							(end -0.254 -0.2286)
						)
						(arc
							(start -0.254 0.2286)
							(mid -0.239121 0.264521)
							(end -0.2032 0.2794)
						)
						(arc
							(start 0.2032 0.2794)
							(mid 0.239121 0.264521)
							(end 0.254 0.2286)
						)
						(arc
							(start 0.254 -0.2286)
							(mid 0.239121 -0.264521)
							(end 0.2032 -0.2794)
						)
					)
					(width 0)
					(fill yes)
				)
			)
		)
	)
	(footprint ""
		(layer "F.Cu")
		(at 27.0764 -56.9468 90)
		(property "Reference" "PR54"
			(at 0 0 90)
			(layer "F.SilkS")
			(hide yes)
			(effects
				(font
					(size 1.27 1.27)
				)
			)
		)
		(property "Value" "0R3J-0-U-GP"
			(at -0.0254 -2.0193 90)
			(unlocked yes)
			(layer "F.Fab")
			(hide yes)
			(effects
				(font
					(size 1.016 1.016)
					(thickness 0.1524)
				)
			)
		)
		(property "Device Type" "R603H22"
			(at -0.0254 -3.5433 90)
			(unlocked yes)
			(layer "F.Fab")
			(hide yes)
			(effects
				(font
					(size 1.016 1.016)
					(thickness 0.1524)
				)
			)
		)
		(duplicate_pad_numbers_are_jumpers no)
		(fp_line
			(start 0.4318 0)
			(end 0.2032 0)
			(stroke
				(width 0.2032)
				(type default)
			)
			(layer "F.SilkS")
		)
		(fp_line
			(start -0.2032 0)
			(end -0.4191 0)
			(stroke
				(width 0.2032)
				(type default)
			)
			(layer "F.SilkS")
		)
		(fp_rect
			(start -0.635 1.1811)
			(end 0.635 -1.1811)
			(stroke
				(width 0)
				(type default)
			)
			(fill no)
			(layer "F.CrtYd")
		)
		(fp_rect
			(start -0.635 1.1811)
			(end 0.635 -1.1811)
			(stroke
				(width 0)
				(type default)
			)
			(fill no)
			(layer "F.Fab")
		)
		(pad "1" smd custom
			(at 0 -0.6604 90)
			(size 0.19685 0.19685)
			(layers "F.Cu" "F.Mask" "F.Paste")
			(net "VR_PVCCP_GL")
			(options
				(clearance outline)
				(anchor circle)
			)
			(primitives
				(gr_poly
					(pts
						(arc
							(start 0.508 -0.2921)
							(mid 0.478242 -0.363942)
							(end 0.4064 -0.3937)
						)
						(arc
							(start -0.4064 -0.3937)
							(mid -0.478242 -0.363942)
							(end -0.508 -0.2921)
						)
						(arc
							(start -0.508 0.2921)
							(mid -0.478242 0.363942)
							(end -0.4064 0.3937)
						)
						(arc
							(start 0.4064 0.3937)
							(mid 0.478242 0.363942)
							(end 0.508 0.2921)
						)
					)
					(width 0)
					(fill yes)
				)
			)
		)
		(pad "2" smd custom
			(at 0 0.6604 90)
			(size 0.19685 0.19685)
			(layers "F.Cu" "F.Mask" "F.Paste")
			(net "VR_PVCCP_LH_R")
			(options
				(clearance outline)
				(anchor circle)
			)
			(primitives
				(gr_poly
					(pts
						(arc
							(start 0.508 -0.2921)
							(mid 0.478242 -0.363942)
							(end 0.4064 -0.3937)
						)
						(arc
							(start -0.4064 -0.3937)
							(mid -0.478242 -0.363942)
							(end -0.508 -0.2921)
						)
						(arc
							(start -0.508 0.2921)
							(mid -0.478242 0.363942)
							(end -0.4064 0.3937)
						)
						(arc
							(start 0.4064 0.3937)
							(mid 0.478242 0.363942)
							(end 0.508 0.2921)
						)
					)
					(width 0)
					(fill yes)
				)
			)
		)
	)
	(footprint ""
		(layer "F.Cu")
		(at 168.4528 -52.07 -90)
		(property "Reference" "R182"
			(at 0 0 270)
			(layer "F.SilkS")
			(hide yes)
			(effects
				(font
					(size 1.27 1.27)
				)
			)
		)
		(property "Value" "33R2F-3-GP"
			(at 1.7907 -1.1176 270)
			(unlocked yes)
			(layer "F.Fab")
			(hide yes)
			(effects
				(font
					(size 1.016 1.016)
					(thickness 0.1524)
				)
			)
		)
		(property "Device Type" "R402H16"
			(at 1.7907 -2.6416 270)
			(unlocked yes)
			(layer "F.Fab")
			(hide yes)
			(effects
				(font
					(size 1.016 1.016)
					(thickness 0.1524)
				)
			)
		)
		(duplicate_pad_numbers_are_jumpers no)
		(fp_rect
			(start -0.381 0.8382)
			(end 0.381 -0.8382)
			(stroke
				(width 0)
				(type default)
			)
			(fill no)
			(layer "F.CrtYd")
		)
		(fp_rect
			(start -0.381 0.8382)
			(end 0.381 -0.8382)
			(stroke
				(width 0)
				(type default)
			)
			(fill no)
			(layer "F.Fab")
		)
		(pad "1" smd custom
			(at 0 -0.4318 270)
			(size 0.127 0.127)
			(layers "F.Cu" "F.Mask" "F.Paste")
			(net "C_CSO#")
			(options
				(clearance outline)
				(anchor circle)
			)
			(primitives
				(gr_poly
					(pts
						(arc
							(start -0.2032 -0.2794)
							(mid -0.239121 -0.264521)
							(end -0.254 -0.2286)
						)
						(arc
							(start -0.254 0.2286)
							(mid -0.239121 0.264521)
							(end -0.2032 0.2794)
						)
						(arc
							(start 0.2032 0.2794)
							(mid 0.239121 0.264521)
							(end 0.254 0.2286)
						)
						(arc
							(start 0.254 -0.2286)
							(mid 0.239121 -0.264521)
							(end 0.2032 -0.2794)
						)
					)
					(width 0)
					(fill yes)
				)
			)
		)
		(pad "2" smd custom
			(at 0 0.4318 270)
			(size 0.127 0.127)
			(layers "F.Cu" "F.Mask" "F.Paste")
			(net "C_R_CSO#")
			(options
				(clearance outline)
				(anchor circle)
			)
			(primitives
				(gr_poly
					(pts
						(arc
							(start -0.2032 -0.2794)
							(mid -0.239121 -0.264521)
							(end -0.254 -0.2286)
						)
						(arc
							(start -0.254 0.2286)
							(mid -0.239121 0.264521)
							(end -0.2032 0.2794)
						)
						(arc
							(start 0.2032 0.2794)
							(mid 0.239121 0.264521)
							(end 0.254 0.2286)
						)
						(arc
							(start 0.254 -0.2286)
							(mid 0.239121 -0.264521)
							(end 0.2032 -0.2794)
						)
					)
					(width 0)
					(fill yes)
				)
			)
		)
	)
	(footprint ""
		(layer "F.Cu")
		(at 169.926 -40.132 -90)
		(property "Reference" "PR227"
			(at 0 0 270)
			(layer "F.SilkS")
			(hide yes)
			(effects
				(font
					(size 1.27 1.27)
				)
			)
		)
		(property "Value" "31K6R2F-GP"
			(at 1.7907 -1.1176 270)
			(unlocked yes)
			(layer "F.Fab")
			(hide yes)
			(effects
				(font
					(size 1.016 1.016)
					(thickness 0.1524)
				)
			)
		)
		(property "Device Type" "R402H16"
			(at 1.7907 -2.6416 270)
			(unlocked yes)
			(layer "F.Fab")
			(hide yes)
			(effects
				(font
					(size 1.016 1.016)
					(thickness 0.1524)
				)
			)
		)
		(duplicate_pad_numbers_are_jumpers no)
		(fp_rect
			(start -0.381 0.8382)
			(end 0.381 -0.8382)
			(stroke
				(width 0)
				(type default)
			)
			(fill no)
			(layer "F.CrtYd")
		)
		(fp_rect
			(start -0.381 0.8382)
			(end 0.381 -0.8382)
			(stroke
				(width 0)
				(type default)
			)
			(fill no)
			(layer "F.Fab")
		)
		(pad "1" smd custom
			(at 0 -0.4318 270)
			(size 0.127 0.127)
			(layers "F.Cu" "F.Mask" "F.Paste")
			(net "P2V5_STBY_OUT")
			(options
				(clearance outline)
				(anchor circle)
			)
			(primitives
				(gr_poly
					(pts
						(arc
							(start -0.2032 -0.2794)
							(mid -0.239121 -0.264521)
							(end -0.254 -0.2286)
						)
						(arc
							(start -0.254 0.2286)
							(mid -0.239121 0.264521)
							(end -0.2032 0.2794)
						)
						(arc
							(start 0.2032 0.2794)
							(mid 0.239121 0.264521)
							(end 0.254 0.2286)
						)
						(arc
							(start 0.254 -0.2286)
							(mid 0.239121 -0.264521)
							(end 0.2032 -0.2794)
						)
					)
					(width 0)
					(fill yes)
				)
			)
		)
		(pad "2" smd custom
			(at 0 0.4318 270)
			(size 0.127 0.127)
			(layers "F.Cu" "F.Mask" "F.Paste")
			(net "P2V5_STBY_FB")
			(options
				(clearance outline)
				(anchor circle)
			)
			(primitives
				(gr_poly
					(pts
						(arc
							(start -0.2032 -0.2794)
							(mid -0.239121 -0.264521)
							(end -0.254 -0.2286)
						)
						(arc
							(start -0.254 0.2286)
							(mid -0.239121 0.264521)
							(end -0.2032 0.2794)
						)
						(arc
							(start 0.2032 0.2794)
							(mid 0.239121 0.264521)
							(end 0.254 0.2286)
						)
						(arc
							(start 0.254 -0.2286)
							(mid 0.239121 -0.264521)
							(end 0.2032 -0.2794)
						)
					)
					(width 0)
					(fill yes)
				)
			)
		)
	)
	(footprint ""
		(layer "F.Cu")
		(at 17.8308 -67.1322)
		(property "Reference" "PC9"
			(at 0 0 0)
			(layer "F.SilkS")
			(hide yes)
			(effects
				(font
					(size 1.27 1.27)
				)
			)
		)
		(property "Value" "SCD1U16V2KX-3GP"
			(at 1.8923 -1.2065 0)
			(unlocked yes)
			(layer "F.Fab")
			(hide yes)
			(effects
				(font
					(size 1.016 1.016)
					(thickness 0.1524)
				)
			)
		)
		(property "Device Type" "C402H22"
			(at 1.8923 -2.7305 0)
			(unlocked yes)
			(layer "F.Fab")
			(hide yes)
			(effects
				(font
					(size 1.016 1.016)
					(thickness 0.1524)
				)
			)
		)
		(duplicate_pad_numbers_are_jumpers no)
		(fp_rect
			(start -0.381 0.7366)
			(end 0.381 -0.7366)
			(stroke
				(width 0)
				(type default)
			)
			(fill no)
			(layer "F.CrtYd")
		)
		(fp_rect
			(start -0.381 0.7366)
			(end 0.381 -0.7366)
			(stroke
				(width 0)
				(type default)
			)
			(fill no)
			(layer "F.Fab")
		)
		(pad "1" smd custom
			(at 0 -0.4572)
			(size 0.1143 0.1143)
			(layers "F.Cu" "F.Mask" "F.Paste")
			(net "GND")
			(options
				(clearance outline)
				(anchor circle)
			)
			(primitives
				(gr_poly
					(pts
						(arc
							(start -0.254 -0.1778)
							(mid -0.239121 -0.213721)
							(end -0.2032 -0.2286)
						)
						(arc
							(start 0.2032 -0.2286)
							(mid 0.239121 -0.213721)
							(end 0.254 -0.1778)
						)
						(arc
							(start 0.254 0.1778)
							(mid 0.239121 0.213721)
							(end 0.2032 0.2286)
						)
						(arc
							(start -0.2032 0.2286)
							(mid -0.239121 0.213721)
							(end -0.254 0.1778)
						)
					)
					(width 0)
					(fill yes)
				)
			)
		)
		(pad "2" smd custom
			(at 0 0.4572)
			(size 0.1143 0.1143)
			(layers "F.Cu" "F.Mask" "F.Paste")
			(net "VR_PVNN_ISUMN")
			(options
				(clearance outline)
				(anchor circle)
			)
			(primitives
				(gr_poly
					(pts
						(arc
							(start -0.254 -0.1778)
							(mid -0.239121 -0.213721)
							(end -0.2032 -0.2286)
						)
						(arc
							(start 0.2032 -0.2286)
							(mid 0.239121 -0.213721)
							(end 0.254 -0.1778)
						)
						(arc
							(start 0.254 0.1778)
							(mid 0.239121 0.213721)
							(end 0.2032 0.2286)
						)
						(arc
							(start -0.2032 0.2286)
							(mid -0.239121 0.213721)
							(end -0.254 0.1778)
						)
					)
					(width 0)
					(fill yes)
				)
			)
		)
	)
	(footprint ""
		(layer "F.Cu")
		(at 8.509 -58.293 90)
		(property "Reference" "C42"
			(at 0 0 90)
			(layer "F.SilkS")
			(hide yes)
			(effects
				(font
					(size 1.27 1.27)
				)
			)
		)
		(property "Value" "SCD1U16V2KX-3GP"
			(at 1.1811 -2.7051 90)
			(unlocked yes)
			(layer "F.Fab")
			(hide yes)
			(effects
				(font
					(size 1.016 1.016)
					(thickness 0.1524)
				)
			)
		)
		(property "Device Type" "C402H22"
			(at 1.1811 -4.2291 90)
			(unlocked yes)
			(layer "F.Fab")
			(hide yes)
			(effects
				(font
					(size 1.016 1.016)
					(thickness 0.1524)
				)
			)
		)
		(duplicate_pad_numbers_are_jumpers no)
		(fp_rect
			(start -0.381 0.7366)
			(end 0.381 -0.7366)
			(stroke
				(width 0)
				(type default)
			)
			(fill no)
			(layer "F.CrtYd")
		)
		(fp_rect
			(start -0.381 0.7366)
			(end 0.381 -0.7366)
			(stroke
				(width 0)
				(type default)
			)
			(fill no)
			(layer "F.Fab")
		)
		(pad "1" smd custom
			(at 0 -0.4572 90)
			(size 0.1143 0.1143)
			(layers "F.Cu" "F.Mask" "F.Paste")
			(net "P2E_CPU_NGFF_C_RX_DN13")
			(options
				(clearance outline)
				(anchor circle)
			)
			(primitives
				(gr_poly
					(pts
						(arc
							(start -0.254 -0.1778)
							(mid -0.239121 -0.213721)
							(end -0.2032 -0.2286)
						)
						(arc
							(start 0.2032 -0.2286)
							(mid 0.239121 -0.213721)
							(end 0.254 -0.1778)
						)
						(arc
							(start 0.254 0.1778)
							(mid 0.239121 0.213721)
							(end 0.2032 0.2286)
						)
						(arc
							(start -0.2032 0.2286)
							(mid -0.239121 0.213721)
							(end -0.254 0.1778)
						)
					)
					(width 0)
					(fill yes)
				)
			)
		)
		(pad "2" smd custom
			(at 0 0.4572 90)
			(size 0.1143 0.1143)
			(layers "F.Cu" "F.Mask" "F.Paste")
			(net "P2E_CPU_NGFF_RX_DN13")
			(options
				(clearance outline)
				(anchor circle)
			)
			(primitives
				(gr_poly
					(pts
						(arc
							(start -0.254 -0.1778)
							(mid -0.239121 -0.213721)
							(end -0.2032 -0.2286)
						)
						(arc
							(start 0.2032 -0.2286)
							(mid 0.239121 -0.213721)
							(end 0.254 -0.1778)
						)
						(arc
							(start 0.254 0.1778)
							(mid 0.239121 0.213721)
							(end 0.2032 0.2286)
						)
						(arc
							(start -0.2032 0.2286)
							(mid -0.239121 0.213721)
							(end -0.254 0.1778)
						)
					)
					(width 0)
					(fill yes)
				)
			)
		)
	)
	(footprint ""
		(layer "F.Cu")
		(at 5.08 -32.258)
		(property "Reference" "PR209"
			(at 0 0 0)
			(layer "F.SilkS")
			(hide yes)
			(effects
				(font
					(size 1.27 1.27)
				)
			)
		)
		(property "Value" "2D2R3J-2-GP"
			(at -0.0254 -2.0193 0)
			(unlocked yes)
			(layer "F.Fab")
			(hide yes)
			(effects
				(font
					(size 1.016 1.016)
					(thickness 0.1524)
				)
			)
		)
		(property "Device Type" "R603H22"
			(at -0.0254 -3.5433 0)
			(unlocked yes)
			(layer "F.Fab")
			(hide yes)
			(effects
				(font
					(size 1.016 1.016)
					(thickness 0.1524)
				)
			)
		)
		(duplicate_pad_numbers_are_jumpers no)
		(fp_line
			(start -0.2032 0)
			(end -0.4191 0)
			(stroke
				(width 0.2032)
				(type default)
			)
			(layer "F.SilkS")
		)
		(fp_line
			(start 0.4318 0)
			(end 0.2032 0)
			(stroke
				(width 0.2032)
				(type default)
			)
			(layer "F.SilkS")
		)
		(fp_rect
			(start -0.635 1.1811)
			(end 0.635 -1.1811)
			(stroke
				(width 0)
				(type default)
			)
			(fill no)
			(layer "F.CrtYd")
		)
		(fp_rect
			(start -0.635 1.1811)
			(end 0.635 -1.1811)
			(stroke
				(width 0)
				(type default)
			)
			(fill no)
			(layer "F.Fab")
		)
		(pad "1" smd custom
			(at 0 -0.6604)
			(size 0.19685 0.19685)
			(layers "F.Cu" "F.Mask" "F.Paste")
			(net "P3V3_STBY_VDD")
			(options
				(clearance outline)
				(anchor circle)
			)
			(primitives
				(gr_poly
					(pts
						(arc
							(start 0.508 -0.2921)
							(mid 0.478242 -0.363942)
							(end 0.4064 -0.3937)
						)
						(arc
							(start -0.4064 -0.3937)
							(mid -0.478242 -0.363942)
							(end -0.508 -0.2921)
						)
						(arc
							(start -0.508 0.2921)
							(mid -0.478242 0.363942)
							(end -0.4064 0.3937)
						)
						(arc
							(start 0.4064 0.3937)
							(mid 0.478242 0.363942)
							(end 0.508 0.2921)
						)
					)
					(width 0)
					(fill yes)
				)
			)
		)
		(pad "2" smd custom
			(at 0 0.6604)
			(size 0.19685 0.19685)
			(layers "F.Cu" "F.Mask" "F.Paste")
			(net "P12V")
			(options
				(clearance outline)
				(anchor circle)
			)
			(primitives
				(gr_poly
					(pts
						(arc
							(start 0.508 -0.2921)
							(mid 0.478242 -0.363942)
							(end 0.4064 -0.3937)
						)
						(arc
							(start -0.4064 -0.3937)
							(mid -0.478242 -0.363942)
							(end -0.508 -0.2921)
						)
						(arc
							(start -0.508 0.2921)
							(mid -0.478242 0.363942)
							(end -0.4064 0.3937)
						)
						(arc
							(start 0.4064 0.3937)
							(mid 0.478242 0.363942)
							(end 0.508 0.2921)
						)
					)
					(width 0)
					(fill yes)
				)
			)
		)
	)
	(footprint ""
		(layer "F.Cu")
		(at 111.633 -57.912 90)
		(property "Reference" "R24"
			(at 0 0 90)
			(layer "F.SilkS")
			(hide yes)
			(effects
				(font
					(size 1.27 1.27)
				)
			)
		)
		(property "Value" "100R2F-L1-GP-U"
			(at 0.064008 -3.993896 90)
			(unlocked yes)
			(layer "F.Fab")
			(hide yes)
			(effects
				(font
					(size 1.016 1.016)
					(thickness 0.1524)
				)
			)
		)
		(property "Device Type" "R402H14"
			(at 0.064008 -5.517896 90)
			(unlocked yes)
			(layer "F.Fab")
			(hide yes)
			(effects
				(font
					(size 1.016 1.016)
					(thickness 0.1524)
				)
			)
		)
		(duplicate_pad_numbers_are_jumpers no)
		(fp_rect
			(start -0.381 0.8382)
			(end 0.381 -0.8382)
			(stroke
				(width 0)
				(type default)
			)
			(fill no)
			(layer "F.CrtYd")
		)
		(fp_rect
			(start -0.381 0.8382)
			(end 0.381 -0.8382)
			(stroke
				(width 0)
				(type default)
			)
			(fill no)
			(layer "F.Fab")
		)
		(pad "1" smd custom
			(at 0 -0.4318 90)
			(size 0.127 0.127)
			(layers "F.Cu" "F.Mask" "F.Paste")
			(net "M_A_MON2_P")
			(options
				(clearance outline)
				(anchor circle)
			)
			(primitives
				(gr_poly
					(pts
						(arc
							(start -0.2032 -0.2794)
							(mid -0.239121 -0.264521)
							(end -0.254 -0.2286)
						)
						(arc
							(start -0.254 0.2286)
							(mid -0.239121 0.264521)
							(end -0.2032 0.2794)
						)
						(arc
							(start 0.2032 0.2794)
							(mid 0.239121 0.264521)
							(end 0.254 0.2286)
						)
						(arc
							(start 0.254 -0.2286)
							(mid 0.239121 -0.264521)
							(end 0.2032 -0.2794)
						)
					)
					(width 0)
					(fill yes)
				)
			)
		)
		(pad "2" smd custom
			(at 0 0.4318 90)
			(size 0.127 0.127)
			(layers "F.Cu" "F.Mask" "F.Paste")
			(net "M_A_MON2_N")
			(options
				(clearance outline)
				(anchor circle)
			)
			(primitives
				(gr_poly
					(pts
						(arc
							(start -0.2032 -0.2794)
							(mid -0.239121 -0.264521)
							(end -0.254 -0.2286)
						)
						(arc
							(start -0.254 0.2286)
							(mid -0.239121 0.264521)
							(end -0.2032 0.2794)
						)
						(arc
							(start 0.2032 0.2794)
							(mid 0.239121 0.264521)
							(end 0.254 0.2286)
						)
						(arc
							(start 0.254 -0.2286)
							(mid 0.239121 -0.264521)
							(end 0.2032 -0.2794)
						)
					)
					(width 0)
					(fill yes)
				)
			)
		)
	)
	(footprint ""
		(layer "F.Cu")
		(at 163.83 -42.418)
		(property "Reference" "R75"
			(at 0 0 0)
			(layer "F.SilkS")
			(hide yes)
			(effects
				(font
					(size 1.27 1.27)
				)
			)
		)
		(property "Value" "10KR2F-2-GP"
			(at 0.064008 -3.993896 0)
			(unlocked yes)
			(layer "F.Fab")
			(hide yes)
			(effects
				(font
					(size 1.016 1.016)
					(thickness 0.1524)
				)
			)
		)
		(property "Device Type" "R402H16"
			(at 0.064008 -5.517896 0)
			(unlocked yes)
			(layer "F.Fab")
			(hide yes)
			(effects
				(font
					(size 1.016 1.016)
					(thickness 0.1524)
				)
			)
		)
		(duplicate_pad_numbers_are_jumpers no)
		(fp_rect
			(start -0.381 0.8382)
			(end 0.381 -0.8382)
			(stroke
				(width 0)
				(type default)
			)
			(fill no)
			(layer "F.CrtYd")
		)
		(fp_rect
			(start -0.381 0.8382)
			(end 0.381 -0.8382)
			(stroke
				(width 0)
				(type default)
			)
			(fill no)
			(layer "F.Fab")
		)
		(pad "1" smd custom
			(at 0 -0.4318)
			(size 0.127 0.127)
			(layers "F.Cu" "F.Mask" "F.Paste")
			(net "P3V3_STBY")
			(options
				(clearance outline)
				(anchor circle)
			)
			(primitives
				(gr_poly
					(pts
						(arc
							(start -0.2032 -0.2794)
							(mid -0.239121 -0.264521)
							(end -0.254 -0.2286)
						)
						(arc
							(start -0.254 0.2286)
							(mid -0.239121 0.264521)
							(end -0.2032 0.2794)
						)
						(arc
							(start 0.2032 0.2794)
							(mid 0.239121 0.264521)
							(end 0.254 0.2286)
						)
						(arc
							(start 0.254 -0.2286)
							(mid 0.239121 -0.264521)
							(end 0.2032 -0.2794)
						)
					)
					(width 0)
					(fill yes)
				)
			)
		)
		(pad "2" smd custom
			(at 0 0.4318)
			(size 0.127 0.127)
			(layers "F.Cu" "F.Mask" "F.Paste")
			(net "OSC_5M_EN")
			(options
				(clearance outline)
				(anchor circle)
			)
			(primitives
				(gr_poly
					(pts
						(arc
							(start -0.2032 -0.2794)
							(mid -0.239121 -0.264521)
							(end -0.254 -0.2286)
						)
						(arc
							(start -0.254 0.2286)
							(mid -0.239121 0.264521)
							(end -0.2032 0.2794)
						)
						(arc
							(start 0.2032 0.2794)
							(mid 0.239121 0.264521)
							(end 0.254 0.2286)
						)
						(arc
							(start 0.254 -0.2286)
							(mid 0.239121 -0.264521)
							(end 0.2032 -0.2794)
						)
					)
					(width 0)
					(fill yes)
				)
			)
		)
	)
	(footprint ""
		(layer "F.Cu")
		(at 67.818 -21.082 180)
		(property "Reference" "R157"
			(at 0 0 180)
			(layer "F.SilkS")
			(hide yes)
			(effects
				(font
					(size 1.27 1.27)
				)
			)
		)
		(property "Value" "4K7R2F-GP"
			(at 1.7907 -1.1176 180)
			(unlocked yes)
			(layer "F.Fab")
			(hide yes)
			(effects
				(font
					(size 1.016 1.016)
					(thickness 0.1524)
				)
			)
		)
		(property "Device Type" "R402H16"
			(at 1.7907 -2.6416 180)
			(unlocked yes)
			(layer "F.Fab")
			(hide yes)
			(effects
				(font
					(size 1.016 1.016)
					(thickness 0.1524)
				)
			)
		)
		(duplicate_pad_numbers_are_jumpers no)
		(fp_rect
			(start -0.381 0.8382)
			(end 0.381 -0.8382)
			(stroke
				(width 0)
				(type default)
			)
			(fill no)
			(layer "F.CrtYd")
		)
		(fp_rect
			(start -0.381 0.8382)
			(end 0.381 -0.8382)
			(stroke
				(width 0)
				(type default)
			)
			(fill no)
			(layer "F.Fab")
		)
		(pad "1" smd custom
			(at 0 -0.4318 180)
			(size 0.127 0.127)
			(layers "F.Cu" "F.Mask" "F.Paste")
			(net "P3V3_CPU")
			(options
				(clearance outline)
				(anchor circle)
			)
			(primitives
				(gr_poly
					(pts
						(arc
							(start -0.2032 -0.2794)
							(mid -0.239121 -0.264521)
							(end -0.254 -0.2286)
						)
						(arc
							(start -0.254 0.2286)
							(mid -0.239121 0.264521)
							(end -0.2032 0.2794)
						)
						(arc
							(start 0.2032 0.2794)
							(mid 0.239121 0.264521)
							(end 0.254 0.2286)
						)
						(arc
							(start 0.254 -0.2286)
							(mid 0.239121 -0.264521)
							(end 0.2032 -0.2794)
						)
					)
					(width 0)
					(fill yes)
				)
			)
		)
		(pad "2" smd custom
			(at 0 0.4318 180)
			(size 0.127 0.127)
			(layers "F.Cu" "F.Mask" "F.Paste")
			(net "MSATA_PRESENT_R#")
			(options
				(clearance outline)
				(anchor circle)
			)
			(primitives
				(gr_poly
					(pts
						(arc
							(start -0.2032 -0.2794)
							(mid -0.239121 -0.264521)
							(end -0.254 -0.2286)
						)
						(arc
							(start -0.254 0.2286)
							(mid -0.239121 0.264521)
							(end -0.2032 0.2794)
						)
						(arc
							(start 0.2032 0.2794)
							(mid 0.239121 0.264521)
							(end 0.254 0.2286)
						)
						(arc
							(start 0.254 -0.2286)
							(mid 0.239121 -0.264521)
							(end 0.2032 -0.2794)
						)
					)
					(width 0)
					(fill yes)
				)
			)
		)
	)
	(footprint ""
		(layer "F.Cu")
		(at 8.509 -55.626 90)
		(property "Reference" "C50"
			(at 0 0 90)
			(layer "F.SilkS")
			(hide yes)
			(effects
				(font
					(size 1.27 1.27)
				)
			)
		)
		(property "Value" "SCD1U16V2KX-3GP"
			(at 1.1811 -2.7051 90)
			(unlocked yes)
			(layer "F.Fab")
			(hide yes)
			(effects
				(font
					(size 1.016 1.016)
					(thickness 0.1524)
				)
			)
		)
		(property "Device Type" "C402H22"
			(at 1.1811 -4.2291 90)
			(unlocked yes)
			(layer "F.Fab")
			(hide yes)
			(effects
				(font
					(size 1.016 1.016)
					(thickness 0.1524)
				)
			)
		)
		(duplicate_pad_numbers_are_jumpers no)
		(fp_rect
			(start -0.381 0.7366)
			(end 0.381 -0.7366)
			(stroke
				(width 0)
				(type default)
			)
			(fill no)
			(layer "F.CrtYd")
		)
		(fp_rect
			(start -0.381 0.7366)
			(end 0.381 -0.7366)
			(stroke
				(width 0)
				(type default)
			)
			(fill no)
			(layer "F.Fab")
		)
		(pad "1" smd custom
			(at 0 -0.4572 90)
			(size 0.1143 0.1143)
			(layers "F.Cu" "F.Mask" "F.Paste")
			(net "P2E_CPU_NGFF_TX_DP13")
			(options
				(clearance outline)
				(anchor circle)
			)
			(primitives
				(gr_poly
					(pts
						(arc
							(start -0.254 -0.1778)
							(mid -0.239121 -0.213721)
							(end -0.2032 -0.2286)
						)
						(arc
							(start 0.2032 -0.2286)
							(mid 0.239121 -0.213721)
							(end 0.254 -0.1778)
						)
						(arc
							(start 0.254 0.1778)
							(mid 0.239121 0.213721)
							(end 0.2032 0.2286)
						)
						(arc
							(start -0.2032 0.2286)
							(mid -0.239121 0.213721)
							(end -0.254 0.1778)
						)
					)
					(width 0)
					(fill yes)
				)
			)
		)
		(pad "2" smd custom
			(at 0 0.4572 90)
			(size 0.1143 0.1143)
			(layers "F.Cu" "F.Mask" "F.Paste")
			(net "P2E_CPU_NGFF_C_TX_DP13")
			(options
				(clearance outline)
				(anchor circle)
			)
			(primitives
				(gr_poly
					(pts
						(arc
							(start -0.254 -0.1778)
							(mid -0.239121 -0.213721)
							(end -0.2032 -0.2286)
						)
						(arc
							(start 0.2032 -0.2286)
							(mid 0.239121 -0.213721)
							(end 0.254 -0.1778)
						)
						(arc
							(start 0.254 0.1778)
							(mid 0.239121 0.213721)
							(end 0.2032 0.2286)
						)
						(arc
							(start -0.2032 0.2286)
							(mid -0.239121 0.213721)
							(end -0.254 0.1778)
						)
					)
					(width 0)
					(fill yes)
				)
			)
		)
	)
	(footprint ""
		(layer "F.Cu")
		(at 27.4066 -63.246)
		(property "Reference" "PC62"
			(at 0 0 0)
			(layer "F.SilkS")
			(hide yes)
			(effects
				(font
					(size 1.27 1.27)
				)
			)
		)
		(property "Value" "SC10U16V6KX-2GP"
			(at 0.0127 -3.4671 0)
			(unlocked yes)
			(layer "F.Fab")
			(hide yes)
			(effects
				(font
					(size 1.016 1.016)
					(thickness 0.1524)
				)
			)
		)
		(property "Device Type" "C1206H71"
			(at 0.0127 -4.9911 0)
			(unlocked yes)
			(layer "F.Fab")
			(hide yes)
			(effects
				(font
					(size 1.016 1.016)
					(thickness 0.1524)
				)
			)
		)
		(duplicate_pad_numbers_are_jumpers no)
		(fp_rect
			(start -1.0541 1.9812)
			(end 1.0541 -1.9812)
			(stroke
				(width 0)
				(type default)
			)
			(fill no)
			(layer "F.CrtYd")
		)
		(fp_rect
			(start -1.0541 1.9812)
			(end 1.0541 -1.9812)
			(stroke
				(width 0)
				(type default)
			)
			(fill no)
			(layer "F.Fab")
		)
		(pad "1" smd rect
			(at 0 -1.3462)
			(size 1.8542 1.016)
			(layers "F.Cu" "F.Mask" "F.Paste")
			(net "VCCP_5VBIAS")
		)
		(pad "2" smd rect
			(at 0 1.3462)
			(size 1.8542 1.016)
			(layers "F.Cu" "F.Mask" "F.Paste")
			(net "GND")
		)
	)
	(footprint ""
		(layer "F.Cu")
		(at 8.509 -60.96 90)
		(property "Reference" "C34"
			(at 0 0 90)
			(layer "F.SilkS")
			(hide yes)
			(effects
				(font
					(size 1.27 1.27)
				)
			)
		)
		(property "Value" "SCD1U16V2KX-3GP"
			(at 1.1811 -2.7051 90)
			(unlocked yes)
			(layer "F.Fab")
			(hide yes)
			(effects
				(font
					(size 1.016 1.016)
					(thickness 0.1524)
				)
			)
		)
		(property "Device Type" "C402H22"
			(at 1.1811 -4.2291 90)
			(unlocked yes)
			(layer "F.Fab")
			(hide yes)
			(effects
				(font
					(size 1.016 1.016)
					(thickness 0.1524)
				)
			)
		)
		(duplicate_pad_numbers_are_jumpers no)
		(fp_rect
			(start -0.381 0.7366)
			(end 0.381 -0.7366)
			(stroke
				(width 0)
				(type default)
			)
			(fill no)
			(layer "F.CrtYd")
		)
		(fp_rect
			(start -0.381 0.7366)
			(end 0.381 -0.7366)
			(stroke
				(width 0)
				(type default)
			)
			(fill no)
			(layer "F.Fab")
		)
		(pad "1" smd custom
			(at 0 -0.4572 90)
			(size 0.1143 0.1143)
			(layers "F.Cu" "F.Mask" "F.Paste")
			(net "P2E_CPU_NGFF_C_RX_DP14")
			(options
				(clearance outline)
				(anchor circle)
			)
			(primitives
				(gr_poly
					(pts
						(arc
							(start -0.254 -0.1778)
							(mid -0.239121 -0.213721)
							(end -0.2032 -0.2286)
						)
						(arc
							(start 0.2032 -0.2286)
							(mid 0.239121 -0.213721)
							(end 0.254 -0.1778)
						)
						(arc
							(start 0.254 0.1778)
							(mid 0.239121 0.213721)
							(end 0.2032 0.2286)
						)
						(arc
							(start -0.2032 0.2286)
							(mid -0.239121 0.213721)
							(end -0.254 0.1778)
						)
					)
					(width 0)
					(fill yes)
				)
			)
		)
		(pad "2" smd custom
			(at 0 0.4572 90)
			(size 0.1143 0.1143)
			(layers "F.Cu" "F.Mask" "F.Paste")
			(net "P2E_CPU_NGFF_RX_DP14")
			(options
				(clearance outline)
				(anchor circle)
			)
			(primitives
				(gr_poly
					(pts
						(arc
							(start -0.254 -0.1778)
							(mid -0.239121 -0.213721)
							(end -0.2032 -0.2286)
						)
						(arc
							(start 0.2032 -0.2286)
							(mid 0.239121 -0.213721)
							(end 0.254 -0.1778)
						)
						(arc
							(start 0.254 0.1778)
							(mid 0.239121 0.213721)
							(end 0.2032 0.2286)
						)
						(arc
							(start -0.2032 0.2286)
							(mid -0.239121 0.213721)
							(end -0.254 0.1778)
						)
					)
					(width 0)
					(fill yes)
				)
			)
		)
	)
	(footprint ""
		(layer "F.Cu")
		(at 25.8318 -37.465)
		(property "Reference" "PC77"
			(at 0 0 0)
			(layer "F.SilkS")
			(hide yes)
			(effects
				(font
					(size 1.27 1.27)
				)
			)
		)
		(property "Value" "SC100U6D3V6MX-GP"
			(at 0.0127 -3.4671 0)
			(unlocked yes)
			(layer "F.Fab")
			(hide yes)
			(effects
				(font
					(size 1.016 1.016)
					(thickness 0.1524)
				)
			)
		)
		(property "Device Type" "C1206H71"
			(at 0.0127 -4.9911 0)
			(unlocked yes)
			(layer "F.Fab")
			(hide yes)
			(effects
				(font
					(size 1.016 1.016)
					(thickness 0.1524)
				)
			)
		)
		(duplicate_pad_numbers_are_jumpers no)
		(fp_rect
			(start -1.0541 1.9812)
			(end 1.0541 -1.9812)
			(stroke
				(width 0)
				(type default)
			)
			(fill no)
			(layer "F.CrtYd")
		)
		(fp_rect
			(start -1.0541 1.9812)
			(end 1.0541 -1.9812)
			(stroke
				(width 0)
				(type default)
			)
			(fill no)
			(layer "F.Fab")
		)
		(pad "1" smd rect
			(at 0 -1.3462)
			(size 1.8542 1.016)
			(layers "F.Cu" "F.Mask" "F.Paste")
			(net "P3V3_STBY_OUT")
		)
		(pad "2" smd rect
			(at 0 1.3462)
			(size 1.8542 1.016)
			(layers "F.Cu" "F.Mask" "F.Paste")
			(net "GND")
		)
	)
	(footprint ""
		(layer "F.Cu")
		(at 182.499 -55.626 180)
		(property "Reference" "R201"
			(at 0 0 180)
			(layer "F.SilkS")
			(hide yes)
			(effects
				(font
					(size 1.27 1.27)
				)
			)
		)
		(property "Value" "0R2J-2-GP"
			(at 0.064008 -3.993896 180)
			(unlocked yes)
			(layer "F.Fab")
			(hide yes)
			(effects
				(font
					(size 1.016 1.016)
					(thickness 0.1524)
				)
			)
		)
		(property "Device Type" "R402H16"
			(at 0.064008 -5.517896 180)
			(unlocked yes)
			(layer "F.Fab")
			(hide yes)
			(effects
				(font
					(size 1.016 1.016)
					(thickness 0.1524)
				)
			)
		)
		(duplicate_pad_numbers_are_jumpers no)
		(fp_rect
			(start -0.381 0.8382)
			(end 0.381 -0.8382)
			(stroke
				(width 0)
				(type default)
			)
			(fill no)
			(layer "F.CrtYd")
		)
		(fp_rect
			(start -0.381 0.8382)
			(end 0.381 -0.8382)
			(stroke
				(width 0)
				(type default)
			)
			(fill no)
			(layer "F.Fab")
		)
		(pad "1" smd custom
			(at 0 -0.4318 180)
			(size 0.127 0.127)
			(layers "F.Cu" "F.Mask" "F.Paste")
			(net "PV_VDDR_VREF_A")
			(options
				(clearance outline)
				(anchor circle)
			)
			(primitives
				(gr_poly
					(pts
						(arc
							(start -0.2032 -0.2794)
							(mid -0.239121 -0.264521)
							(end -0.254 -0.2286)
						)
						(arc
							(start -0.254 0.2286)
							(mid -0.239121 0.264521)
							(end -0.2032 0.2794)
						)
						(arc
							(start 0.2032 0.2794)
							(mid 0.239121 0.264521)
							(end 0.254 0.2286)
						)
						(arc
							(start 0.254 -0.2286)
							(mid 0.239121 -0.264521)
							(end 0.2032 -0.2794)
						)
					)
					(width 0)
					(fill yes)
				)
			)
		)
		(pad "2" smd custom
			(at 0 0.4318 180)
			(size 0.127 0.127)
			(layers "F.Cu" "F.Mask" "F.Paste")
			(net "DDR3_M_A_VREF_DQ0")
			(options
				(clearance outline)
				(anchor circle)
			)
			(primitives
				(gr_poly
					(pts
						(arc
							(start -0.2032 -0.2794)
							(mid -0.239121 -0.264521)
							(end -0.254 -0.2286)
						)
						(arc
							(start -0.254 0.2286)
							(mid -0.239121 0.264521)
							(end -0.2032 0.2794)
						)
						(arc
							(start 0.2032 0.2794)
							(mid 0.239121 0.264521)
							(end 0.254 0.2286)
						)
						(arc
							(start 0.254 -0.2286)
							(mid 0.239121 -0.264521)
							(end 0.2032 -0.2794)
						)
					)
					(width 0)
					(fill yes)
				)
			)
		)
	)
	(footprint ""
		(layer "F.Cu")
		(at 60.1218 -51.8922)
		(property "Reference" "PC112"
			(at 0 0 0)
			(layer "F.SilkS")
			(hide yes)
			(effects
				(font
					(size 1.27 1.27)
				)
			)
		)
		(property "Value" "SC22U6D3V5MX-2GP"
			(at 0 -4.9022 0)
			(unlocked yes)
			(layer "F.Fab")
			(hide yes)
			(effects
				(font
					(size 1.016 1.016)
					(thickness 0.1524)
				)
			)
		)
		(property "Device Type" "C805H58"
			(at 0 -6.8072 0)
			(unlocked yes)
			(layer "F.Fab")
			(hide yes)
			(effects
				(font
					(size 1.016 1.016)
					(thickness 0.1524)
				)
			)
		)
		(duplicate_pad_numbers_are_jumpers no)
		(fp_line
			(start 0.6096 0)
			(end -0.6096 0)
			(stroke
				(width 0.3048)
				(type default)
			)
			(layer "F.SilkS")
		)
		(fp_poly
			(pts
				(xy -0.9017 1.4351) (xy 0.9017 1.4351) (xy 0.9017 -1.4351) (xy -0.9017 -1.4351)
			)
			(stroke
				(width 0)
				(type default)
			)
			(fill no)
			(layer "F.CrtYd")
		)
		(fp_poly
			(pts
				(xy 0.9017 1.4351) (xy 0.9017 -1.4351) (xy -0.9017 -1.4351) (xy -0.9017 1.4351)
			)
			(stroke
				(width 0)
				(type default)
			)
			(fill no)
			(layer "F.Fab")
		)
		(pad "1" smd rect
			(at 0 -0.8382)
			(size 1.5494 0.9398)
			(layers "F.Cu" "F.Mask" "F.Paste")
			(net "P1V0_STBY_VOUT")
		)
		(pad "2" smd rect
			(at 0 0.8382)
			(size 1.5494 0.9398)
			(layers "F.Cu" "F.Mask" "F.Paste")
			(net "GND")
		)
	)
	(footprint ""
		(layer "F.Cu")
		(at 194.31 -37.0586 -90)
		(property "Reference" "PR133"
			(at 0 0 270)
			(layer "F.SilkS")
			(hide yes)
			(effects
				(font
					(size 1.27 1.27)
				)
			)
		)
		(property "Value" "0R2J-2-GP"
			(at 1.7907 -1.1176 270)
			(unlocked yes)
			(layer "F.Fab")
			(hide yes)
			(effects
				(font
					(size 1.016 1.016)
					(thickness 0.1524)
				)
			)
		)
		(property "Device Type" "R402H16"
			(at 1.7907 -2.6416 270)
			(unlocked yes)
			(layer "F.Fab")
			(hide yes)
			(effects
				(font
					(size 1.016 1.016)
					(thickness 0.1524)
				)
			)
		)
		(duplicate_pad_numbers_are_jumpers no)
		(fp_rect
			(start -0.381 0.8382)
			(end 0.381 -0.8382)
			(stroke
				(width 0)
				(type default)
			)
			(fill no)
			(layer "F.CrtYd")
		)
		(fp_rect
			(start -0.381 0.8382)
			(end 0.381 -0.8382)
			(stroke
				(width 0)
				(type default)
			)
			(fill no)
			(layer "F.Fab")
		)
		(pad "1" smd custom
			(at 0 -0.4318 270)
			(size 0.127 0.127)
			(layers "F.Cu" "F.Mask" "F.Paste")
			(net "VDDR_5VBIAS")
			(options
				(clearance outline)
				(anchor circle)
			)
			(primitives
				(gr_poly
					(pts
						(arc
							(start -0.2032 -0.2794)
							(mid -0.239121 -0.264521)
							(end -0.254 -0.2286)
						)
						(arc
							(start -0.254 0.2286)
							(mid -0.239121 0.264521)
							(end -0.2032 0.2794)
						)
						(arc
							(start 0.2032 0.2794)
							(mid 0.239121 0.264521)
							(end 0.254 0.2286)
						)
						(arc
							(start 0.254 -0.2286)
							(mid 0.239121 -0.264521)
							(end 0.2032 -0.2794)
						)
					)
					(width 0)
					(fill yes)
				)
			)
		)
		(pad "2" smd custom
			(at 0 0.4318 270)
			(size 0.127 0.127)
			(layers "F.Cu" "F.Mask" "F.Paste")
			(net "VR_PVDDR_A_VDDP")
			(options
				(clearance outline)
				(anchor circle)
			)
			(primitives
				(gr_poly
					(pts
						(arc
							(start -0.2032 -0.2794)
							(mid -0.239121 -0.264521)
							(end -0.254 -0.2286)
						)
						(arc
							(start -0.254 0.2286)
							(mid -0.239121 0.264521)
							(end -0.2032 0.2794)
						)
						(arc
							(start 0.2032 0.2794)
							(mid 0.239121 0.264521)
							(end 0.254 0.2286)
						)
						(arc
							(start 0.254 -0.2286)
							(mid 0.239121 -0.264521)
							(end 0.2032 -0.2794)
						)
					)
					(width 0)
					(fill yes)
				)
			)
		)
	)
	(footprint ""
		(layer "F.Cu")
		(at 135.763 -52.959)
		(property "Reference" "PC53"
			(at 0 0 0)
			(layer "F.SilkS")
			(hide yes)
			(effects
				(font
					(size 1.27 1.27)
				)
			)
		)
		(property "Value" "SCD1U16V2KX-3GP"
			(at 1.1811 -2.7051 0)
			(unlocked yes)
			(layer "F.Fab")
			(hide yes)
			(effects
				(font
					(size 1.016 1.016)
					(thickness 0.1524)
				)
			)
		)
		(property "Device Type" "C402H22"
			(at 1.1811 -4.2291 0)
			(unlocked yes)
			(layer "F.Fab")
			(hide yes)
			(effects
				(font
					(size 1.016 1.016)
					(thickness 0.1524)
				)
			)
		)
		(duplicate_pad_numbers_are_jumpers no)
		(fp_rect
			(start -0.381 0.7366)
			(end 0.381 -0.7366)
			(stroke
				(width 0)
				(type default)
			)
			(fill no)
			(layer "F.CrtYd")
		)
		(fp_rect
			(start -0.381 0.7366)
			(end 0.381 -0.7366)
			(stroke
				(width 0)
				(type default)
			)
			(fill no)
			(layer "F.Fab")
		)
		(pad "1" smd custom
			(at 0 -0.4572)
			(size 0.1143 0.1143)
			(layers "F.Cu" "F.Mask" "F.Paste")
			(net "PV_VTT_DDR_REFO")
			(options
				(clearance outline)
				(anchor circle)
			)
			(primitives
				(gr_poly
					(pts
						(arc
							(start -0.254 -0.1778)
							(mid -0.239121 -0.213721)
							(end -0.2032 -0.2286)
						)
						(arc
							(start 0.2032 -0.2286)
							(mid 0.239121 -0.213721)
							(end 0.254 -0.1778)
						)
						(arc
							(start 0.254 0.1778)
							(mid 0.239121 0.213721)
							(end 0.2032 0.2286)
						)
						(arc
							(start -0.2032 0.2286)
							(mid -0.239121 0.213721)
							(end -0.254 0.1778)
						)
					)
					(width 0)
					(fill yes)
				)
			)
		)
		(pad "2" smd custom
			(at 0 0.4572)
			(size 0.1143 0.1143)
			(layers "F.Cu" "F.Mask" "F.Paste")
			(net "GND")
			(options
				(clearance outline)
				(anchor circle)
			)
			(primitives
				(gr_poly
					(pts
						(arc
							(start -0.254 -0.1778)
							(mid -0.239121 -0.213721)
							(end -0.2032 -0.2286)
						)
						(arc
							(start 0.2032 -0.2286)
							(mid 0.239121 -0.213721)
							(end 0.254 -0.1778)
						)
						(arc
							(start 0.254 0.1778)
							(mid 0.239121 0.213721)
							(end 0.2032 0.2286)
						)
						(arc
							(start -0.2032 0.2286)
							(mid -0.239121 0.213721)
							(end -0.254 0.1778)
						)
					)
					(width 0)
					(fill yes)
				)
			)
		)
	)
	(footprint ""
		(layer "F.Cu")
		(at 30.734 -66.294)
		(property "Reference" "PL3"
			(at 0 0 0)
			(layer "F.SilkS")
			(hide yes)
			(effects
				(font
					(size 1.27 1.27)
				)
			)
		)
		(property "Value" "COIL-D22UH-GP"
			(at -3.302 0.0508 0)
			(unlocked yes)
			(layer "F.Fab")
			(hide yes)
			(effects
				(font
					(size 1.016 1.016)
					(thickness 0.1524)
				)
			)
		)
		(property "Device Type" "L4540-1222H79"
			(at -3.302 -1.4732 0)
			(unlocked yes)
			(layer "F.Fab")
			(hide yes)
			(effects
				(font
					(size 1.016 1.016)
					(thickness 0.1524)
				)
			)
		)
		(duplicate_pad_numbers_are_jumpers no)
		(fp_rect
			(start -2.2606 2.7559)
			(end 2.2606 -2.7559)
			(stroke
				(width 0)
				(type default)
			)
			(fill no)
			(layer "F.CrtYd")
		)
		(fp_rect
			(start -2.2606 2.7559)
			(end 2.2606 -2.7559)
			(stroke
				(width 0)
				(type default)
			)
			(fill no)
			(layer "F.Fab")
		)
		(pad "1" smd rect
			(at 0 -1.710436)
			(size 2.4638 1.8288)
			(layers "F.Cu" "F.Mask" "F.Paste")
			(net "P12V")
		)
		(pad "2" smd rect
			(at 0 1.710436)
			(size 2.4638 1.8288)
			(layers "F.Cu" "F.Mask" "F.Paste")
			(net "VR_FET_SW_P12V_PVCCP_PVNN")
		)
	)
	(footprint ""
		(layer "F.Cu")
		(at 167.894 -12.955778 180)
		(property "Reference" "C372"
			(at 0 0 180)
			(layer "F.SilkS")
			(hide yes)
			(effects
				(font
					(size 1.27 1.27)
				)
			)
		)
		(property "Value" "SC47U6D3V5MX-1-GP"
			(at 0 -4.9022 180)
			(unlocked yes)
			(layer "F.Fab")
			(hide yes)
			(effects
				(font
					(size 1.016 1.016)
					(thickness 0.1524)
				)
			)
		)
		(property "Device Type" "C805H54"
			(at 0 -6.8072 180)
			(unlocked yes)
			(layer "F.Fab")
			(hide yes)
			(effects
				(font
					(size 1.016 1.016)
					(thickness 0.1524)
				)
			)
		)
		(duplicate_pad_numbers_are_jumpers no)
		(fp_line
			(start 0.6096 0)
			(end -0.6096 0)
			(stroke
				(width 0.3048)
				(type default)
			)
			(layer "F.SilkS")
		)
		(fp_poly
			(pts
				(xy -0.9017 1.4351) (xy 0.9017 1.4351) (xy 0.9017 -1.4351) (xy -0.9017 -1.4351)
			)
			(stroke
				(width 0)
				(type default)
			)
			(fill no)
			(layer "F.CrtYd")
		)
		(fp_poly
			(pts
				(xy 0.9017 1.4351) (xy 0.9017 -1.4351) (xy -0.9017 -1.4351) (xy -0.9017 1.4351)
			)
			(stroke
				(width 0)
				(type default)
			)
			(fill no)
			(layer "F.Fab")
		)
		(pad "1" smd rect
			(at 0 -0.8382 180)
			(size 1.5494 0.9398)
			(layers "F.Cu" "F.Mask" "F.Paste")
			(net "PV_VDDR")
		)
		(pad "2" smd rect
			(at 0 0.8382 180)
			(size 1.5494 0.9398)
			(layers "F.Cu" "F.Mask" "F.Paste")
			(net "GND")
		)
	)
	(footprint ""
		(layer "F.Cu")
		(at 117.094 -68.326 180)
		(property "Reference" "R16"
			(at 0 0 180)
			(layer "F.SilkS")
			(hide yes)
			(effects
				(font
					(size 1.27 1.27)
				)
			)
		)
		(property "Value" "33R2F-3-GP"
			(at 0.064008 -3.993896 180)
			(unlocked yes)
			(layer "F.Fab")
			(hide yes)
			(effects
				(font
					(size 1.016 1.016)
					(thickness 0.1524)
				)
			)
		)
		(property "Device Type" "R402H16"
			(at 0.064008 -5.517896 180)
			(unlocked yes)
			(layer "F.Fab")
			(hide yes)
			(effects
				(font
					(size 1.016 1.016)
					(thickness 0.1524)
				)
			)
		)
		(duplicate_pad_numbers_are_jumpers no)
		(fp_rect
			(start -0.381 0.8382)
			(end 0.381 -0.8382)
			(stroke
				(width 0)
				(type default)
			)
			(fill no)
			(layer "F.CrtYd")
		)
		(fp_rect
			(start -0.381 0.8382)
			(end 0.381 -0.8382)
			(stroke
				(width 0)
				(type default)
			)
			(fill no)
			(layer "F.Fab")
		)
		(pad "1" smd custom
			(at 0 -0.4318 180)
			(size 0.127 0.127)
			(layers "F.Cu" "F.Mask" "F.Paste")
			(net "CLK_GEN_OUT_R")
			(options
				(clearance outline)
				(anchor circle)
			)
			(primitives
				(gr_poly
					(pts
						(arc
							(start -0.2032 -0.2794)
							(mid -0.239121 -0.264521)
							(end -0.254 -0.2286)
						)
						(arc
							(start -0.254 0.2286)
							(mid -0.239121 0.264521)
							(end -0.2032 0.2794)
						)
						(arc
							(start 0.2032 0.2794)
							(mid 0.239121 0.264521)
							(end 0.254 0.2286)
						)
						(arc
							(start 0.254 -0.2286)
							(mid 0.239121 -0.264521)
							(end 0.2032 -0.2794)
						)
					)
					(width 0)
					(fill yes)
				)
			)
		)
		(pad "2" smd custom
			(at 0 0.4318 180)
			(size 0.127 0.127)
			(layers "F.Cu" "F.Mask" "F.Paste")
			(net "CLK_GEN_OUT")
			(options
				(clearance outline)
				(anchor circle)
			)
			(primitives
				(gr_poly
					(pts
						(arc
							(start -0.2032 -0.2794)
							(mid -0.239121 -0.264521)
							(end -0.254 -0.2286)
						)
						(arc
							(start -0.254 0.2286)
							(mid -0.239121 0.264521)
							(end -0.2032 0.2794)
						)
						(arc
							(start 0.2032 0.2794)
							(mid 0.239121 0.264521)
							(end 0.254 0.2286)
						)
						(arc
							(start 0.254 -0.2286)
							(mid 0.239121 -0.264521)
							(end 0.2032 -0.2794)
						)
					)
					(width 0)
					(fill yes)
				)
			)
		)
	)
	(footprint ""
		(layer "F.Cu")
		(at 98.298 -68.58 180)
		(property "Reference" "TP3"
			(at 0 0 180)
			(layer "F.SilkS")
			(hide yes)
			(effects
				(font
					(size 1.27 1.27)
				)
			)
		)
		(property "Value" "TPAD28-1-GP-U"
			(at 0.0508 -1.9304 180)
			(unlocked yes)
			(layer "F.Fab")
			(hide yes)
			(effects
				(font
					(size 1.016 1.016)
					(thickness 0.1524)
				)
			)
		)
		(property "Device Type" "TPAD28-1-U"
			(at 0.0508 -3.4544 180)
			(unlocked yes)
			(layer "F.Fab")
			(hide yes)
			(effects
				(font
					(size 1.016 1.016)
					(thickness 0.1524)
				)
			)
		)
		(duplicate_pad_numbers_are_jumpers no)
		(fp_poly
			(pts
				(arc
					(start -0.3556 0)
					(mid 0.3556 0)
					(end -0.3556 0)
				)
			)
			(stroke
				(width 0)
				(type default)
			)
			(fill no)
			(layer "F.CrtYd")
		)
		(fp_poly
			(pts
				(arc
					(start -0.9525 0)
					(mid 0.9525 0)
					(end -0.9525 0)
				)
			)
			(stroke
				(width 0)
				(type default)
			)
			(fill no)
			(layer "F.Fab")
		)
		(pad "1" smd circle
			(at 0 0 180)
			(size 0.7112 0.7112)
			(layers "F.Cu" "F.Mask" "F.Paste")
			(net "TP_BGND")
		)
	)
	(footprint ""
		(layer "F.Cu")
		(at 176.5046 -46.5074)
		(property "Reference" "R179"
			(at 0 0 0)
			(layer "F.SilkS")
			(hide yes)
			(effects
				(font
					(size 1.27 1.27)
				)
			)
		)
		(property "Value" "0R2J-2-GP"
			(at 0.064008 -3.993896 0)
			(unlocked yes)
			(layer "F.Fab")
			(hide yes)
			(effects
				(font
					(size 1.016 1.016)
					(thickness 0.1524)
				)
			)
		)
		(property "Device Type" "R402H16"
			(at 0.064008 -5.517896 0)
			(unlocked yes)
			(layer "F.Fab")
			(hide yes)
			(effects
				(font
					(size 1.016 1.016)
					(thickness 0.1524)
				)
			)
		)
		(duplicate_pad_numbers_are_jumpers no)
		(fp_rect
			(start -0.381 0.8382)
			(end 0.381 -0.8382)
			(stroke
				(width 0)
				(type default)
			)
			(fill no)
			(layer "F.CrtYd")
		)
		(fp_rect
			(start -0.381 0.8382)
			(end 0.381 -0.8382)
			(stroke
				(width 0)
				(type default)
			)
			(fill no)
			(layer "F.Fab")
		)
		(pad "1" smd custom
			(at 0 -0.4318)
			(size 0.127 0.127)
			(layers "F.Cu" "F.Mask" "F.Paste")
			(net "EEPROM_WP")
			(options
				(clearance outline)
				(anchor circle)
			)
			(primitives
				(gr_poly
					(pts
						(arc
							(start -0.2032 -0.2794)
							(mid -0.239121 -0.264521)
							(end -0.254 -0.2286)
						)
						(arc
							(start -0.254 0.2286)
							(mid -0.239121 0.264521)
							(end -0.2032 0.2794)
						)
						(arc
							(start 0.2032 0.2794)
							(mid 0.239121 0.264521)
							(end 0.254 0.2286)
						)
						(arc
							(start 0.254 -0.2286)
							(mid 0.239121 -0.264521)
							(end 0.2032 -0.2794)
						)
					)
					(width 0)
					(fill yes)
				)
			)
		)
		(pad "2" smd custom
			(at 0 0.4318)
			(size 0.127 0.127)
			(layers "F.Cu" "F.Mask" "F.Paste")
			(net "GND")
			(options
				(clearance outline)
				(anchor circle)
			)
			(primitives
				(gr_poly
					(pts
						(arc
							(start -0.2032 -0.2794)
							(mid -0.239121 -0.264521)
							(end -0.254 -0.2286)
						)
						(arc
							(start -0.254 0.2286)
							(mid -0.239121 0.264521)
							(end -0.2032 0.2794)
						)
						(arc
							(start 0.2032 0.2794)
							(mid 0.239121 0.264521)
							(end 0.254 0.2286)
						)
						(arc
							(start 0.254 -0.2286)
							(mid 0.239121 -0.264521)
							(end 0.2032 -0.2794)
						)
					)
					(width 0)
					(fill yes)
				)
			)
		)
	)
	(footprint ""
		(layer "F.Cu")
		(at 56.007 -35.306 -90)
		(property "Reference" "R110"
			(at 0 0 270)
			(layer "F.SilkS")
			(hide yes)
			(effects
				(font
					(size 1.27 1.27)
				)
			)
		)
		(property "Value" "33R2F-3-GP"
			(at 0.064008 -3.993896 270)
			(unlocked yes)
			(layer "F.Fab")
			(hide yes)
			(effects
				(font
					(size 1.016 1.016)
					(thickness 0.1524)
				)
			)
		)
		(property "Device Type" "R402H16"
			(at 0.064008 -5.517896 270)
			(unlocked yes)
			(layer "F.Fab")
			(hide yes)
			(effects
				(font
					(size 1.016 1.016)
					(thickness 0.1524)
				)
			)
		)
		(duplicate_pad_numbers_are_jumpers no)
		(fp_rect
			(start -0.381 0.8382)
			(end 0.381 -0.8382)
			(stroke
				(width 0)
				(type default)
			)
			(fill no)
			(layer "F.CrtYd")
		)
		(fp_rect
			(start -0.381 0.8382)
			(end 0.381 -0.8382)
			(stroke
				(width 0)
				(type default)
			)
			(fill no)
			(layer "F.Fab")
		)
		(pad "1" smd custom
			(at 0 -0.4318 270)
			(size 0.127 0.127)
			(layers "F.Cu" "F.Mask" "F.Paste")
			(net "SPI_CPU_WP#")
			(options
				(clearance outline)
				(anchor circle)
			)
			(primitives
				(gr_poly
					(pts
						(arc
							(start -0.2032 -0.2794)
							(mid -0.239121 -0.264521)
							(end -0.254 -0.2286)
						)
						(arc
							(start -0.254 0.2286)
							(mid -0.239121 0.264521)
							(end -0.2032 0.2794)
						)
						(arc
							(start 0.2032 0.2794)
							(mid 0.239121 0.264521)
							(end 0.254 0.2286)
						)
						(arc
							(start 0.254 -0.2286)
							(mid 0.239121 -0.264521)
							(end 0.2032 -0.2794)
						)
					)
					(width 0)
					(fill yes)
				)
			)
		)
		(pad "2" smd custom
			(at 0 0.4318 270)
			(size 0.127 0.127)
			(layers "F.Cu" "F.Mask" "F.Paste")
			(net "SPI_WP_R_N_1")
			(options
				(clearance outline)
				(anchor circle)
			)
			(primitives
				(gr_poly
					(pts
						(arc
							(start -0.2032 -0.2794)
							(mid -0.239121 -0.264521)
							(end -0.254 -0.2286)
						)
						(arc
							(start -0.254 0.2286)
							(mid -0.239121 0.264521)
							(end -0.2032 0.2794)
						)
						(arc
							(start 0.2032 0.2794)
							(mid 0.239121 0.264521)
							(end 0.254 0.2286)
						)
						(arc
							(start 0.254 -0.2286)
							(mid 0.239121 -0.264521)
							(end 0.2032 -0.2794)
						)
					)
					(width 0)
					(fill yes)
				)
			)
		)
	)
	(footprint ""
		(layer "F.Cu")
		(at 198.755 -11.049 180)
		(property "Reference" "R339"
			(at 0 0 180)
			(layer "F.SilkS")
			(hide yes)
			(effects
				(font
					(size 1.27 1.27)
				)
			)
		)
		(property "Value" "1KR2F-3-GP"
			(at 1.7907 -1.1176 180)
			(unlocked yes)
			(layer "F.Fab")
			(hide yes)
			(effects
				(font
					(size 1.016 1.016)
					(thickness 0.1524)
				)
			)
		)
		(property "Device Type" "R402H16"
			(at 1.7907 -2.6416 180)
			(unlocked yes)
			(layer "F.Fab")
			(hide yes)
			(effects
				(font
					(size 1.016 1.016)
					(thickness 0.1524)
				)
			)
		)
		(duplicate_pad_numbers_are_jumpers no)
		(fp_rect
			(start -0.381 0.8382)
			(end 0.381 -0.8382)
			(stroke
				(width 0)
				(type default)
			)
			(fill no)
			(layer "F.CrtYd")
		)
		(fp_rect
			(start -0.381 0.8382)
			(end 0.381 -0.8382)
			(stroke
				(width 0)
				(type default)
			)
			(fill no)
			(layer "F.Fab")
		)
		(pad "1" smd custom
			(at 0 -0.4318 180)
			(size 0.127 0.127)
			(layers "F.Cu" "F.Mask" "F.Paste")
			(net "JTAG_CPU_PLD_TDO")
			(options
				(clearance outline)
				(anchor circle)
			)
			(primitives
				(gr_poly
					(pts
						(arc
							(start -0.2032 -0.2794)
							(mid -0.239121 -0.264521)
							(end -0.254 -0.2286)
						)
						(arc
							(start -0.254 0.2286)
							(mid -0.239121 0.264521)
							(end -0.2032 0.2794)
						)
						(arc
							(start 0.2032 0.2794)
							(mid 0.239121 0.264521)
							(end 0.254 0.2286)
						)
						(arc
							(start 0.254 -0.2286)
							(mid 0.239121 -0.264521)
							(end 0.2032 -0.2794)
						)
					)
					(width 0)
					(fill yes)
				)
			)
		)
		(pad "2" smd custom
			(at 0 0.4318 180)
			(size 0.127 0.127)
			(layers "F.Cu" "F.Mask" "F.Paste")
			(net "GND")
			(options
				(clearance outline)
				(anchor circle)
			)
			(primitives
				(gr_poly
					(pts
						(arc
							(start -0.2032 -0.2794)
							(mid -0.239121 -0.264521)
							(end -0.254 -0.2286)
						)
						(arc
							(start -0.254 0.2286)
							(mid -0.239121 0.264521)
							(end -0.2032 0.2794)
						)
						(arc
							(start 0.2032 0.2794)
							(mid 0.239121 0.264521)
							(end 0.254 0.2286)
						)
						(arc
							(start 0.254 -0.2286)
							(mid 0.239121 -0.264521)
							(end 0.2032 -0.2794)
						)
					)
					(width 0)
					(fill yes)
				)
			)
		)
	)
	(footprint ""
		(layer "F.Cu")
		(at 8.509 -64.516 90)
		(property "Reference" "C184"
			(at 0 0 90)
			(layer "F.SilkS")
			(hide yes)
			(effects
				(font
					(size 1.27 1.27)
				)
			)
		)
		(property "Value" "SCD1U16V2KX-3GP"
			(at 1.1811 -2.7051 90)
			(unlocked yes)
			(layer "F.Fab")
			(hide yes)
			(effects
				(font
					(size 1.016 1.016)
					(thickness 0.1524)
				)
			)
		)
		(property "Device Type" "C402H22"
			(at 1.1811 -4.2291 90)
			(unlocked yes)
			(layer "F.Fab")
			(hide yes)
			(effects
				(font
					(size 1.016 1.016)
					(thickness 0.1524)
				)
			)
		)
		(duplicate_pad_numbers_are_jumpers no)
		(fp_rect
			(start -0.381 0.7366)
			(end 0.381 -0.7366)
			(stroke
				(width 0)
				(type default)
			)
			(fill no)
			(layer "F.CrtYd")
		)
		(fp_rect
			(start -0.381 0.7366)
			(end 0.381 -0.7366)
			(stroke
				(width 0)
				(type default)
			)
			(fill no)
			(layer "F.Fab")
		)
		(pad "1" smd custom
			(at 0 -0.4572 90)
			(size 0.1143 0.1143)
			(layers "F.Cu" "F.Mask" "F.Paste")
			(net "P2E_CPU_NGFF_C_RX_DP15")
			(options
				(clearance outline)
				(anchor circle)
			)
			(primitives
				(gr_poly
					(pts
						(arc
							(start -0.254 -0.1778)
							(mid -0.239121 -0.213721)
							(end -0.2032 -0.2286)
						)
						(arc
							(start 0.2032 -0.2286)
							(mid 0.239121 -0.213721)
							(end 0.254 -0.1778)
						)
						(arc
							(start 0.254 0.1778)
							(mid 0.239121 0.213721)
							(end 0.2032 0.2286)
						)
						(arc
							(start -0.2032 0.2286)
							(mid -0.239121 0.213721)
							(end -0.254 0.1778)
						)
					)
					(width 0)
					(fill yes)
				)
			)
		)
		(pad "2" smd custom
			(at 0 0.4572 90)
			(size 0.1143 0.1143)
			(layers "F.Cu" "F.Mask" "F.Paste")
			(net "P2E_CPU_NGFF_RX_DP15")
			(options
				(clearance outline)
				(anchor circle)
			)
			(primitives
				(gr_poly
					(pts
						(arc
							(start -0.254 -0.1778)
							(mid -0.239121 -0.213721)
							(end -0.2032 -0.2286)
						)
						(arc
							(start 0.2032 -0.2286)
							(mid 0.239121 -0.213721)
							(end 0.254 -0.1778)
						)
						(arc
							(start 0.254 0.1778)
							(mid 0.239121 0.213721)
							(end 0.2032 0.2286)
						)
						(arc
							(start -0.2032 0.2286)
							(mid -0.239121 0.213721)
							(end -0.254 0.1778)
						)
					)
					(width 0)
					(fill yes)
				)
			)
		)
	)
	(footprint ""
		(layer "F.Cu")
		(at 50.1904 -22.987 180)
		(property "Reference" "R441"
			(at 0 0 180)
			(layer "F.SilkS")
			(hide yes)
			(effects
				(font
					(size 1.27 1.27)
				)
			)
		)
		(property "Value" "4K7R2F-GP"
			(at 1.7907 -1.1176 180)
			(unlocked yes)
			(layer "F.Fab")
			(hide yes)
			(effects
				(font
					(size 1.016 1.016)
					(thickness 0.1524)
				)
			)
		)
		(property "Device Type" "R402H16"
			(at 1.7907 -2.6416 180)
			(unlocked yes)
			(layer "F.Fab")
			(hide yes)
			(effects
				(font
					(size 1.016 1.016)
					(thickness 0.1524)
				)
			)
		)
		(duplicate_pad_numbers_are_jumpers no)
		(fp_rect
			(start -0.381 0.8382)
			(end 0.381 -0.8382)
			(stroke
				(width 0)
				(type default)
			)
			(fill no)
			(layer "F.CrtYd")
		)
		(fp_rect
			(start -0.381 0.8382)
			(end 0.381 -0.8382)
			(stroke
				(width 0)
				(type default)
			)
			(fill no)
			(layer "F.Fab")
		)
		(pad "1" smd custom
			(at 0 -0.4318 180)
			(size 0.127 0.127)
			(layers "F.Cu" "F.Mask" "F.Paste")
			(net "P3V3")
			(options
				(clearance outline)
				(anchor circle)
			)
			(primitives
				(gr_poly
					(pts
						(arc
							(start -0.2032 -0.2794)
							(mid -0.239121 -0.264521)
							(end -0.254 -0.2286)
						)
						(arc
							(start -0.254 0.2286)
							(mid -0.239121 0.264521)
							(end -0.2032 0.2794)
						)
						(arc
							(start 0.2032 0.2794)
							(mid 0.239121 0.264521)
							(end 0.254 0.2286)
						)
						(arc
							(start 0.254 -0.2286)
							(mid 0.239121 -0.264521)
							(end 0.2032 -0.2794)
						)
					)
					(width 0)
					(fill yes)
				)
			)
		)
		(pad "2" smd custom
			(at 0 0.4318 180)
			(size 0.127 0.127)
			(layers "F.Cu" "F.Mask" "F.Paste")
			(net "CLKBUFF_OE7#")
			(options
				(clearance outline)
				(anchor circle)
			)
			(primitives
				(gr_poly
					(pts
						(arc
							(start -0.2032 -0.2794)
							(mid -0.239121 -0.264521)
							(end -0.254 -0.2286)
						)
						(arc
							(start -0.254 0.2286)
							(mid -0.239121 0.264521)
							(end -0.2032 0.2794)
						)
						(arc
							(start 0.2032 0.2794)
							(mid 0.239121 0.264521)
							(end 0.254 0.2286)
						)
						(arc
							(start 0.254 -0.2286)
							(mid 0.239121 -0.264521)
							(end 0.2032 -0.2794)
						)
					)
					(width 0)
					(fill yes)
				)
			)
		)
	)
	(footprint ""
		(layer "F.Cu")
		(at 44.958 -34.925)
		(property "Reference" "R245"
			(at 0 0 0)
			(layer "F.SilkS")
			(hide yes)
			(effects
				(font
					(size 1.27 1.27)
				)
			)
		)
		(property "Value" "100R3F-1-GP"
			(at -0.0254 -2.5146 0)
			(unlocked yes)
			(layer "F.Fab")
			(hide yes)
			(effects
				(font
					(size 1.016 1.016)
					(thickness 0.1524)
				)
			)
		)
		(property "Device Type" "R603H22"
			(at -0.0254 -4.0386 0)
			(unlocked yes)
			(layer "F.Fab")
			(hide yes)
			(effects
				(font
					(size 1.016 1.016)
					(thickness 0.1524)
				)
			)
		)
		(duplicate_pad_numbers_are_jumpers no)
		(fp_line
			(start -0.2032 0)
			(end -0.4191 0)
			(stroke
				(width 0.2032)
				(type default)
			)
			(layer "F.SilkS")
		)
		(fp_line
			(start 0.4318 0)
			(end 0.2032 0)
			(stroke
				(width 0.2032)
				(type default)
			)
			(layer "F.SilkS")
		)
		(fp_rect
			(start -0.635 1.1811)
			(end 0.635 -1.1811)
			(stroke
				(width 0)
				(type default)
			)
			(fill no)
			(layer "F.CrtYd")
		)
		(fp_rect
			(start -0.635 1.1811)
			(end 0.635 -1.1811)
			(stroke
				(width 0)
				(type default)
			)
			(fill no)
			(layer "F.Fab")
		)
		(pad "1" smd custom
			(at 0 -0.6604)
			(size 0.19685 0.19685)
			(layers "F.Cu" "F.Mask" "F.Paste")
			(net "XDP_PWRBTN#")
			(options
				(clearance outline)
				(anchor circle)
			)
			(primitives
				(gr_poly
					(pts
						(arc
							(start 0.508 -0.2921)
							(mid 0.478242 -0.363942)
							(end 0.4064 -0.3937)
						)
						(arc
							(start -0.4064 -0.3937)
							(mid -0.478242 -0.363942)
							(end -0.508 -0.2921)
						)
						(arc
							(start -0.508 0.2921)
							(mid -0.478242 0.363942)
							(end -0.4064 0.3937)
						)
						(arc
							(start 0.4064 0.3937)
							(mid 0.478242 0.363942)
							(end 0.508 0.2921)
						)
					)
					(width 0)
					(fill yes)
				)
			)
		)
		(pad "2" smd custom
			(at 0 0.6604)
			(size 0.19685 0.19685)
			(layers "F.Cu" "F.Mask" "F.Paste")
			(net "XDP_PWRBTN_R#")
			(options
				(clearance outline)
				(anchor circle)
			)
			(primitives
				(gr_poly
					(pts
						(arc
							(start 0.508 -0.2921)
							(mid 0.478242 -0.363942)
							(end 0.4064 -0.3937)
						)
						(arc
							(start -0.4064 -0.3937)
							(mid -0.478242 -0.363942)
							(end -0.508 -0.2921)
						)
						(arc
							(start -0.508 0.2921)
							(mid -0.478242 0.363942)
							(end -0.4064 0.3937)
						)
						(arc
							(start 0.4064 0.3937)
							(mid 0.478242 0.363942)
							(end 0.508 0.2921)
						)
					)
					(width 0)
					(fill yes)
				)
			)
		)
	)
	(footprint ""
		(layer "F.Cu")
		(at 24.638 -66.9036)
		(property "Reference" "PR24"
			(at 0 0 0)
			(layer "F.SilkS")
			(hide yes)
			(effects
				(font
					(size 1.27 1.27)
				)
			)
		)
		(property "Value" "10KR2F-2-GP"
			(at 1.7907 -1.1176 0)
			(unlocked yes)
			(layer "F.Fab")
			(hide yes)
			(effects
				(font
					(size 1.016 1.016)
					(thickness 0.1524)
				)
			)
		)
		(property "Device Type" "R402H16"
			(at 1.7907 -2.6416 0)
			(unlocked yes)
			(layer "F.Fab")
			(hide yes)
			(effects
				(font
					(size 1.016 1.016)
					(thickness 0.1524)
				)
			)
		)
		(duplicate_pad_numbers_are_jumpers no)
		(fp_rect
			(start -0.381 0.8382)
			(end 0.381 -0.8382)
			(stroke
				(width 0)
				(type default)
			)
			(fill no)
			(layer "F.CrtYd")
		)
		(fp_rect
			(start -0.381 0.8382)
			(end 0.381 -0.8382)
			(stroke
				(width 0)
				(type default)
			)
			(fill no)
			(layer "F.Fab")
		)
		(pad "1" smd custom
			(at 0 -0.4318)
			(size 0.127 0.127)
			(layers "F.Cu" "F.Mask" "F.Paste")
			(net "VR_PVNN_PHASE")
			(options
				(clearance outline)
				(anchor circle)
			)
			(primitives
				(gr_poly
					(pts
						(arc
							(start -0.2032 -0.2794)
							(mid -0.239121 -0.264521)
							(end -0.254 -0.2286)
						)
						(arc
							(start -0.254 0.2286)
							(mid -0.239121 0.264521)
							(end -0.2032 0.2794)
						)
						(arc
							(start 0.2032 0.2794)
							(mid 0.239121 0.264521)
							(end 0.254 0.2286)
						)
						(arc
							(start 0.254 -0.2286)
							(mid 0.239121 -0.264521)
							(end 0.2032 -0.2794)
						)
					)
					(width 0)
					(fill yes)
				)
			)
		)
		(pad "2" smd custom
			(at 0 0.4318)
			(size 0.127 0.127)
			(layers "F.Cu" "F.Mask" "F.Paste")
			(net "VR_PVNN_GH_R")
			(options
				(clearance outline)
				(anchor circle)
			)
			(primitives
				(gr_poly
					(pts
						(arc
							(start -0.2032 -0.2794)
							(mid -0.239121 -0.264521)
							(end -0.254 -0.2286)
						)
						(arc
							(start -0.254 0.2286)
							(mid -0.239121 0.264521)
							(end -0.2032 0.2794)
						)
						(arc
							(start 0.2032 0.2794)
							(mid 0.239121 0.264521)
							(end 0.254 0.2286)
						)
						(arc
							(start 0.254 -0.2286)
							(mid 0.239121 -0.264521)
							(end 0.2032 -0.2794)
						)
					)
					(width 0)
					(fill yes)
				)
			)
		)
	)
	(footprint ""
		(layer "F.Cu")
		(at 93.472 -13.208)
		(property "Reference" "R444"
			(at 0 0 0)
			(layer "F.SilkS")
			(hide yes)
			(effects
				(font
					(size 1.27 1.27)
				)
			)
		)
		(property "Value" "4K7R2F-GP"
			(at 1.7907 -1.1176 0)
			(unlocked yes)
			(layer "F.Fab")
			(hide yes)
			(effects
				(font
					(size 1.016 1.016)
					(thickness 0.1524)
				)
			)
		)
		(property "Device Type" "R402H16"
			(at 1.7907 -2.6416 0)
			(unlocked yes)
			(layer "F.Fab")
			(hide yes)
			(effects
				(font
					(size 1.016 1.016)
					(thickness 0.1524)
				)
			)
		)
		(duplicate_pad_numbers_are_jumpers no)
		(fp_rect
			(start -0.381 0.8382)
			(end 0.381 -0.8382)
			(stroke
				(width 0)
				(type default)
			)
			(fill no)
			(layer "F.CrtYd")
		)
		(fp_rect
			(start -0.381 0.8382)
			(end 0.381 -0.8382)
			(stroke
				(width 0)
				(type default)
			)
			(fill no)
			(layer "F.Fab")
		)
		(pad "1" smd custom
			(at 0 -0.4318)
			(size 0.127 0.127)
			(layers "F.Cu" "F.Mask" "F.Paste")
			(net "P3V3_STBY")
			(options
				(clearance outline)
				(anchor circle)
			)
			(primitives
				(gr_poly
					(pts
						(arc
							(start -0.2032 -0.2794)
							(mid -0.239121 -0.264521)
							(end -0.254 -0.2286)
						)
						(arc
							(start -0.254 0.2286)
							(mid -0.239121 0.264521)
							(end -0.2032 0.2794)
						)
						(arc
							(start 0.2032 0.2794)
							(mid 0.239121 0.264521)
							(end 0.254 0.2286)
						)
						(arc
							(start 0.254 -0.2286)
							(mid 0.239121 -0.264521)
							(end 0.2032 -0.2794)
						)
					)
					(width 0)
					(fill yes)
				)
			)
		)
		(pad "2" smd custom
			(at 0 0.4318)
			(size 0.127 0.127)
			(layers "F.Cu" "F.Mask" "F.Paste")
			(net "SLOT_ID0")
			(options
				(clearance outline)
				(anchor circle)
			)
			(primitives
				(gr_poly
					(pts
						(arc
							(start -0.2032 -0.2794)
							(mid -0.239121 -0.264521)
							(end -0.254 -0.2286)
						)
						(arc
							(start -0.254 0.2286)
							(mid -0.239121 0.264521)
							(end -0.2032 0.2794)
						)
						(arc
							(start 0.2032 0.2794)
							(mid 0.239121 0.264521)
							(end 0.254 0.2286)
						)
						(arc
							(start 0.254 -0.2286)
							(mid 0.239121 -0.264521)
							(end 0.2032 -0.2794)
						)
					)
					(width 0)
					(fill yes)
				)
			)
		)
	)
	(footprint ""
		(layer "F.Cu")
		(at 148.844 -54.7116 90)
		(property "Reference" "U48"
			(at 0 0 90)
			(layer "F.SilkS")
			(hide yes)
			(effects
				(font
					(size 1.27 1.27)
				)
			)
		)
		(property "Value" "SC18IS602BIPW-GP"
			(at -4.0259 -0.4572 90)
			(unlocked yes)
			(layer "F.Fab")
			(hide yes)
			(effects
				(font
					(size 1.016 1.016)
					(thickness 0.1524)
				)
			)
		)
		(property "Device Type" "TSOIC16H44"
			(at -4.0259 -1.9812 90)
			(unlocked yes)
			(layer "F.Fab")
			(hide yes)
			(effects
				(font
					(size 1.016 1.016)
					(thickness 0.1524)
				)
			)
		)
		(duplicate_pad_numbers_are_jumpers no)
		(fp_line
			(start 2.37617 -1.778)
			(end 2.37617 1.778)
			(stroke
				(width 0.1524)
				(type default)
			)
			(layer "F.SilkS")
		)
		(fp_line
			(start -2.6797 -1.778)
			(end 2.37617 -1.778)
			(stroke
				(width 0.1524)
				(type default)
			)
			(layer "F.SilkS")
		)
		(fp_line
			(start -2.6797 -0.3556)
			(end -2.2987 0.0254)
			(stroke
				(width 0.1524)
				(type default)
			)
			(layer "F.SilkS")
		)
		(fp_line
			(start -2.2987 0.0254)
			(end -2.6797 0.4064)
			(stroke
				(width 0.1524)
				(type default)
			)
			(layer "F.SilkS")
		)
		(fp_line
			(start 2.37617 1.778)
			(end -2.6797 1.778)
			(stroke
				(width 0.1524)
				(type default)
			)
			(layer "F.SilkS")
		)
		(fp_line
			(start -2.6797 1.778)
			(end -2.6797 -1.778)
			(stroke
				(width 0.1524)
				(type default)
			)
			(layer "F.SilkS")
		)
		(fp_line
			(start -2.7305 1.8288)
			(end -2.7305 3.4544)
			(stroke
				(width 0.254)
				(type default)
			)
			(layer "F.SilkS")
		)
		(fp_poly
			(pts
				(xy -2.45237 -1.778) (xy -2.45237 1.778) (xy 2.37617 1.778) (xy 2.37617 -1.778)
			)
			(stroke
				(width 0)
				(type default)
			)
			(fill yes)
			(layer "F.SilkS")
		)
		(fp_rect
			(start -2.7559 3.5814)
			(end 2.7559 -3.5814)
			(stroke
				(width 0)
				(type default)
			)
			(fill no)
			(layer "F.CrtYd")
		)
		(fp_rect
			(start -2.7559 3.5814)
			(end 2.7559 -3.5814)
			(stroke
				(width 0)
				(type default)
			)
			(fill no)
			(layer "F.Fab")
		)
		(pad "1" smd rect
			(at -2.27457 2.7559 90)
			(size 0.3556 1.397)
			(layers "F.Cu" "F.Mask" "F.Paste")
			(net "SPI_SW_CSO#")
		)
		(pad "2" smd rect
			(at -1.6256 2.7559 90)
			(size 0.3556 1.397)
			(layers "F.Cu" "F.Mask" "F.Paste")
			(net "SPI_SW_NCONFIG#")
		)
		(pad "3" smd rect
			(at -0.97536 2.7559 90)
			(size 0.3556 1.397)
			(layers "F.Cu" "F.Mask" "F.Paste")
			(net "SPI_SW_RST#")
		)
		(pad "4" smd rect
			(at -0.32512 2.7559 90)
			(size 0.3556 1.397)
			(layers "F.Cu" "F.Mask" "F.Paste")
			(net "GND")
		)
		(pad "5" smd rect
			(at 0.32512 2.7559 90)
			(size 0.3556 1.397)
			(layers "F.Cu" "F.Mask" "F.Paste")
			(net "SPI_SW_DATA0")
		)
		(pad "6" smd rect
			(at 0.97536 2.7559 90)
			(size 0.3556 1.397)
			(layers "F.Cu" "F.Mask" "F.Paste")
			(net "SPI_SW_ASDO")
		)
		(pad "7" smd rect
			(at 1.6256 2.7559 90)
			(size 0.3556 1.397)
			(layers "F.Cu" "F.Mask" "F.Paste")
			(net "BMC_I2C_DATA")
		)
		(pad "8" smd rect
			(at 2.27457 2.7559 90)
			(size 0.3556 1.397)
			(layers "F.Cu" "F.Mask" "F.Paste")
			(net "BMC_I2C_CLK")
		)
		(pad "9" smd rect
			(at 2.27457 -2.7559 90)
			(size 0.3556 1.397)
			(layers "F.Cu" "F.Mask" "F.Paste")
			(net "SPI_SW_INT#")
		)
		(pad "10" smd rect
			(at 1.6256 -2.7559 90)
			(size 0.3556 1.397)
			(layers "F.Cu" "F.Mask" "F.Paste")
			(net "BUS_SW_SEL")
		)
		(pad "11" smd rect
			(at 0.97536 -2.7559 90)
			(size 0.3556 1.397)
			(layers "F.Cu" "F.Mask" "F.Paste")
			(net "SPI_SW_DCLK")
		)
		(pad "12" smd rect
			(at 0.32512 -2.7559 90)
			(size 0.3556 1.397)
			(layers "F.Cu" "F.Mask" "F.Paste")
			(net "P3V3_STBY")
		)
		(pad "13" smd rect
			(at -0.32512 -2.7559 90)
			(size 0.3556 1.397)
			(layers "F.Cu" "F.Mask" "F.Paste")
			(net "Net_40")
		)
		(pad "14" smd rect
			(at -0.97536 -2.7559 90)
			(size 0.3556 1.397)
			(layers "F.Cu" "F.Mask" "F.Paste")
			(net "SPI_SW_ADDR0")
		)
		(pad "15" smd rect
			(at -1.6256 -2.7559 90)
			(size 0.3556 1.397)
			(layers "F.Cu" "F.Mask" "F.Paste")
			(net "SPI_SW_ADDR1")
		)
		(pad "16" smd rect
			(at -2.27457 -2.7559 90)
			(size 0.3556 1.397)
			(layers "F.Cu" "F.Mask" "F.Paste")
			(net "SPI_SW_ADDR2")
		)
	)
	(footprint ""
		(layer "F.Cu")
		(at 7.2517 -41.9608 180)
		(property "Reference" "PC184"
			(at 0 0 180)
			(layer "F.SilkS")
			(hide yes)
			(effects
				(font
					(size 1.27 1.27)
				)
			)
		)
		(property "Value" "SC22U25V5MX-GP"
			(at 0 -4.9022 180)
			(unlocked yes)
			(layer "F.Fab")
			(hide yes)
			(effects
				(font
					(size 1.016 1.016)
					(thickness 0.1524)
				)
			)
		)
		(property "Device Type" "C805H58"
			(at 0 -6.8072 180)
			(unlocked yes)
			(layer "F.Fab")
			(hide yes)
			(effects
				(font
					(size 1.016 1.016)
					(thickness 0.1524)
				)
			)
		)
		(duplicate_pad_numbers_are_jumpers no)
		(fp_line
			(start 0.6096 0)
			(end -0.6096 0)
			(stroke
				(width 0.3048)
				(type default)
			)
			(layer "F.SilkS")
		)
		(fp_poly
			(pts
				(xy -0.9017 1.4351) (xy 0.9017 1.4351) (xy 0.9017 -1.4351) (xy -0.9017 -1.4351)
			)
			(stroke
				(width 0)
				(type default)
			)
			(fill no)
			(layer "F.CrtYd")
		)
		(fp_poly
			(pts
				(xy 0.9017 1.4351) (xy 0.9017 -1.4351) (xy -0.9017 -1.4351) (xy -0.9017 1.4351)
			)
			(stroke
				(width 0)
				(type default)
			)
			(fill no)
			(layer "F.Fab")
		)
		(pad "1" smd rect
			(at 0 -0.8382 180)
			(size 1.5494 0.9398)
			(layers "F.Cu" "F.Mask" "F.Paste")
			(net "P3V3_STBY_VIN")
		)
		(pad "2" smd rect
			(at 0 0.8382 180)
			(size 1.5494 0.9398)
			(layers "F.Cu" "F.Mask" "F.Paste")
			(net "GND")
		)
	)
	(footprint ""
		(layer "F.Cu")
		(at 9.9822 -28.9814 180)
		(property "Reference" "PC78"
			(at 0 0 180)
			(layer "F.SilkS")
			(hide yes)
			(effects
				(font
					(size 1.27 1.27)
				)
			)
		)
		(property "Value" "SCD1U50V3KX-GP"
			(at -0.0254 -2.0193 180)
			(unlocked yes)
			(layer "F.Fab")
			(hide yes)
			(effects
				(font
					(size 1.016 1.016)
					(thickness 0.1524)
				)
			)
		)
		(property "Device Type" "C603H36"
			(at -0.0254 -3.5433 180)
			(unlocked yes)
			(layer "F.Fab")
			(hide yes)
			(effects
				(font
					(size 1.016 1.016)
					(thickness 0.1524)
				)
			)
		)
		(duplicate_pad_numbers_are_jumpers no)
		(fp_line
			(start -0.4064 0)
			(end 0.4064 0)
			(stroke
				(width 0.2286)
				(type default)
			)
			(layer "F.SilkS")
		)
		(fp_rect
			(start -0.635 1.1811)
			(end 0.635 -1.1811)
			(stroke
				(width 0)
				(type default)
			)
			(fill no)
			(layer "F.CrtYd")
		)
		(fp_rect
			(start -0.635 1.1811)
			(end 0.635 -1.1811)
			(stroke
				(width 0)
				(type default)
			)
			(fill no)
			(layer "F.Fab")
		)
		(pad "1" smd custom
			(at 0 -0.6604 180)
			(size 0.19685 0.19685)
			(layers "F.Cu" "F.Mask" "F.Paste")
			(net "P1V0_VIN")
			(options
				(clearance outline)
				(anchor circle)
			)
			(primitives
				(gr_poly
					(pts
						(arc
							(start 0.508 -0.2921)
							(mid 0.478242 -0.363942)
							(end 0.4064 -0.3937)
						)
						(arc
							(start -0.4064 -0.3937)
							(mid -0.478242 -0.363942)
							(end -0.508 -0.2921)
						)
						(arc
							(start -0.508 0.2921)
							(mid -0.478242 0.363942)
							(end -0.4064 0.3937)
						)
						(arc
							(start 0.4064 0.3937)
							(mid 0.478242 0.363942)
							(end 0.508 0.2921)
						)
					)
					(width 0)
					(fill yes)
				)
			)
		)
		(pad "2" smd custom
			(at 0 0.6604 180)
			(size 0.19685 0.19685)
			(layers "F.Cu" "F.Mask" "F.Paste")
			(net "GND")
			(options
				(clearance outline)
				(anchor circle)
			)
			(primitives
				(gr_poly
					(pts
						(arc
							(start 0.508 -0.2921)
							(mid 0.478242 -0.363942)
							(end 0.4064 -0.3937)
						)
						(arc
							(start -0.4064 -0.3937)
							(mid -0.478242 -0.363942)
							(end -0.508 -0.2921)
						)
						(arc
							(start -0.508 0.2921)
							(mid -0.478242 0.363942)
							(end -0.4064 0.3937)
						)
						(arc
							(start 0.4064 0.3937)
							(mid 0.478242 0.363942)
							(end 0.508 0.2921)
						)
					)
					(width 0)
					(fill yes)
				)
			)
		)
	)
	(footprint ""
		(layer "F.Cu")
		(at 23.8506 -66.9036)
		(property "Reference" "PR23"
			(at 0 0 0)
			(layer "F.SilkS")
			(hide yes)
			(effects
				(font
					(size 1.27 1.27)
				)
			)
		)
		(property "Value" "0R2J-2-GP"
			(at 1.7907 -1.1176 0)
			(unlocked yes)
			(layer "F.Fab")
			(hide yes)
			(effects
				(font
					(size 1.016 1.016)
					(thickness 0.1524)
				)
			)
		)
		(property "Device Type" "R402H16"
			(at 1.7907 -2.6416 0)
			(unlocked yes)
			(layer "F.Fab")
			(hide yes)
			(effects
				(font
					(size 1.016 1.016)
					(thickness 0.1524)
				)
			)
		)
		(duplicate_pad_numbers_are_jumpers no)
		(fp_rect
			(start -0.381 0.8382)
			(end 0.381 -0.8382)
			(stroke
				(width 0)
				(type default)
			)
			(fill no)
			(layer "F.CrtYd")
		)
		(fp_rect
			(start -0.381 0.8382)
			(end 0.381 -0.8382)
			(stroke
				(width 0)
				(type default)
			)
			(fill no)
			(layer "F.Fab")
		)
		(pad "1" smd custom
			(at 0 -0.4318)
			(size 0.127 0.127)
			(layers "F.Cu" "F.Mask" "F.Paste")
			(net "VR_PVNN_PHASE")
			(options
				(clearance outline)
				(anchor circle)
			)
			(primitives
				(gr_poly
					(pts
						(arc
							(start -0.2032 -0.2794)
							(mid -0.239121 -0.264521)
							(end -0.254 -0.2286)
						)
						(arc
							(start -0.254 0.2286)
							(mid -0.239121 0.264521)
							(end -0.2032 0.2794)
						)
						(arc
							(start 0.2032 0.2794)
							(mid 0.239121 0.264521)
							(end 0.254 0.2286)
						)
						(arc
							(start 0.254 -0.2286)
							(mid 0.239121 -0.264521)
							(end 0.2032 -0.2794)
						)
					)
					(width 0)
					(fill yes)
				)
			)
		)
		(pad "2" smd custom
			(at 0 0.4318)
			(size 0.127 0.127)
			(layers "F.Cu" "F.Mask" "F.Paste")
			(net "VR_PVNN_BOOT_R")
			(options
				(clearance outline)
				(anchor circle)
			)
			(primitives
				(gr_poly
					(pts
						(arc
							(start -0.2032 -0.2794)
							(mid -0.239121 -0.264521)
							(end -0.254 -0.2286)
						)
						(arc
							(start -0.254 0.2286)
							(mid -0.239121 0.264521)
							(end -0.2032 0.2794)
						)
						(arc
							(start 0.2032 0.2794)
							(mid 0.239121 0.264521)
							(end 0.254 0.2286)
						)
						(arc
							(start 0.254 -0.2286)
							(mid 0.239121 -0.264521)
							(end 0.2032 -0.2794)
						)
					)
					(width 0)
					(fill yes)
				)
			)
		)
	)
	(footprint ""
		(layer "F.Cu")
		(at 114.046 -71.12 180)
		(property "Reference" "R230"
			(at 0 0 180)
			(layer "F.SilkS")
			(hide yes)
			(effects
				(font
					(size 1.27 1.27)
				)
			)
		)
		(property "Value" "4K7R2F-GP"
			(at 0.064008 -3.993896 180)
			(unlocked yes)
			(layer "F.Fab")
			(hide yes)
			(effects
				(font
					(size 1.016 1.016)
					(thickness 0.1524)
				)
			)
		)
		(property "Device Type" "R402H16"
			(at 0.064008 -5.517896 180)
			(unlocked yes)
			(layer "F.Fab")
			(hide yes)
			(effects
				(font
					(size 1.016 1.016)
					(thickness 0.1524)
				)
			)
		)
		(duplicate_pad_numbers_are_jumpers no)
		(fp_rect
			(start -0.381 0.8382)
			(end 0.381 -0.8382)
			(stroke
				(width 0)
				(type default)
			)
			(fill no)
			(layer "F.CrtYd")
		)
		(fp_rect
			(start -0.381 0.8382)
			(end 0.381 -0.8382)
			(stroke
				(width 0)
				(type default)
			)
			(fill no)
			(layer "F.Fab")
		)
		(pad "1" smd custom
			(at 0 -0.4318 180)
			(size 0.127 0.127)
			(layers "F.Cu" "F.Mask" "F.Paste")
			(net "P3V3_STBY")
			(options
				(clearance outline)
				(anchor circle)
			)
			(primitives
				(gr_poly
					(pts
						(arc
							(start -0.2032 -0.2794)
							(mid -0.239121 -0.264521)
							(end -0.254 -0.2286)
						)
						(arc
							(start -0.254 0.2286)
							(mid -0.239121 0.264521)
							(end -0.2032 0.2794)
						)
						(arc
							(start 0.2032 0.2794)
							(mid 0.239121 0.264521)
							(end 0.254 0.2286)
						)
						(arc
							(start 0.254 -0.2286)
							(mid 0.239121 -0.264521)
							(end 0.2032 -0.2794)
						)
					)
					(width 0)
					(fill yes)
				)
			)
		)
		(pad "2" smd custom
			(at 0 0.4318 180)
			(size 0.127 0.127)
			(layers "F.Cu" "F.Mask" "F.Paste")
			(net "CHA_1_SA1")
			(options
				(clearance outline)
				(anchor circle)
			)
			(primitives
				(gr_poly
					(pts
						(arc
							(start -0.2032 -0.2794)
							(mid -0.239121 -0.264521)
							(end -0.254 -0.2286)
						)
						(arc
							(start -0.254 0.2286)
							(mid -0.239121 0.264521)
							(end -0.2032 0.2794)
						)
						(arc
							(start 0.2032 0.2794)
							(mid 0.239121 0.264521)
							(end 0.254 0.2286)
						)
						(arc
							(start 0.254 -0.2286)
							(mid 0.239121 -0.264521)
							(end 0.2032 -0.2794)
						)
					)
					(width 0)
					(fill yes)
				)
			)
		)
	)
	(footprint ""
		(layer "F.Cu")
		(at 183.2102 -33.5026)
		(property "Reference" "PR142"
			(at 0 0 0)
			(layer "F.SilkS")
			(hide yes)
			(effects
				(font
					(size 1.27 1.27)
				)
			)
		)
		(property "Value" "0R2J-2-GP"
			(at 1.7907 -1.1176 0)
			(unlocked yes)
			(layer "F.Fab")
			(hide yes)
			(effects
				(font
					(size 1.016 1.016)
					(thickness 0.1524)
				)
			)
		)
		(property "Device Type" "R402H16"
			(at 1.7907 -2.6416 0)
			(unlocked yes)
			(layer "F.Fab")
			(hide yes)
			(effects
				(font
					(size 1.016 1.016)
					(thickness 0.1524)
				)
			)
		)
		(duplicate_pad_numbers_are_jumpers no)
		(fp_rect
			(start -0.381 0.8382)
			(end 0.381 -0.8382)
			(stroke
				(width 0)
				(type default)
			)
			(fill no)
			(layer "F.CrtYd")
		)
		(fp_rect
			(start -0.381 0.8382)
			(end 0.381 -0.8382)
			(stroke
				(width 0)
				(type default)
			)
			(fill no)
			(layer "F.Fab")
		)
		(pad "1" smd custom
			(at 0 -0.4318)
			(size 0.127 0.127)
			(layers "F.Cu" "F.Mask" "F.Paste")
			(net "VR_PVDDR_PNN_VRHOT#")
			(options
				(clearance outline)
				(anchor circle)
			)
			(primitives
				(gr_poly
					(pts
						(arc
							(start -0.2032 -0.2794)
							(mid -0.239121 -0.264521)
							(end -0.254 -0.2286)
						)
						(arc
							(start -0.254 0.2286)
							(mid -0.239121 0.264521)
							(end -0.2032 0.2794)
						)
						(arc
							(start 0.2032 0.2794)
							(mid 0.239121 0.264521)
							(end 0.254 0.2286)
						)
						(arc
							(start 0.254 -0.2286)
							(mid 0.239121 -0.264521)
							(end 0.2032 -0.2794)
						)
					)
					(width 0)
					(fill yes)
				)
			)
		)
		(pad "2" smd custom
			(at 0 0.4318)
			(size 0.127 0.127)
			(layers "F.Cu" "F.Mask" "F.Paste")
			(net "PVCCP_PVNN_VRHOT#")
			(options
				(clearance outline)
				(anchor circle)
			)
			(primitives
				(gr_poly
					(pts
						(arc
							(start -0.2032 -0.2794)
							(mid -0.239121 -0.264521)
							(end -0.254 -0.2286)
						)
						(arc
							(start -0.254 0.2286)
							(mid -0.239121 0.264521)
							(end -0.2032 0.2794)
						)
						(arc
							(start 0.2032 0.2794)
							(mid 0.239121 0.264521)
							(end 0.254 0.2286)
						)
						(arc
							(start 0.254 -0.2286)
							(mid 0.239121 -0.264521)
							(end 0.2032 -0.2794)
						)
					)
					(width 0)
					(fill yes)
				)
			)
		)
	)
	(footprint ""
		(layer "F.Cu")
		(at 74.041 -34.417 90)
		(property "Reference" "R112"
			(at 0 0 90)
			(layer "F.SilkS")
			(hide yes)
			(effects
				(font
					(size 1.27 1.27)
				)
			)
		)
		(property "Value" "10KR2F-2-GP"
			(at 0.064008 -3.993896 90)
			(unlocked yes)
			(layer "F.Fab")
			(hide yes)
			(effects
				(font
					(size 1.016 1.016)
					(thickness 0.1524)
				)
			)
		)
		(property "Device Type" "R402H16"
			(at 0.064008 -5.517896 90)
			(unlocked yes)
			(layer "F.Fab")
			(hide yes)
			(effects
				(font
					(size 1.016 1.016)
					(thickness 0.1524)
				)
			)
		)
		(duplicate_pad_numbers_are_jumpers no)
		(fp_rect
			(start -0.381 0.8382)
			(end 0.381 -0.8382)
			(stroke
				(width 0)
				(type default)
			)
			(fill no)
			(layer "F.CrtYd")
		)
		(fp_rect
			(start -0.381 0.8382)
			(end 0.381 -0.8382)
			(stroke
				(width 0)
				(type default)
			)
			(fill no)
			(layer "F.Fab")
		)
		(pad "1" smd custom
			(at 0 -0.4318 90)
			(size 0.127 0.127)
			(layers "F.Cu" "F.Mask" "F.Paste")
			(net "P3V3_CPU")
			(options
				(clearance outline)
				(anchor circle)
			)
			(primitives
				(gr_poly
					(pts
						(arc
							(start -0.2032 -0.2794)
							(mid -0.239121 -0.264521)
							(end -0.254 -0.2286)
						)
						(arc
							(start -0.254 0.2286)
							(mid -0.239121 0.264521)
							(end -0.2032 0.2794)
						)
						(arc
							(start 0.2032 0.2794)
							(mid 0.239121 0.264521)
							(end 0.254 0.2286)
						)
						(arc
							(start 0.254 -0.2286)
							(mid 0.239121 -0.264521)
							(end 0.2032 -0.2794)
						)
					)
					(width 0)
					(fill yes)
				)
			)
		)
		(pad "2" smd custom
			(at 0 0.4318 90)
			(size 0.127 0.127)
			(layers "F.Cu" "F.Mask" "F.Paste")
			(net "PU_PMU_GPE#")
			(options
				(clearance outline)
				(anchor circle)
			)
			(primitives
				(gr_poly
					(pts
						(arc
							(start -0.2032 -0.2794)
							(mid -0.239121 -0.264521)
							(end -0.254 -0.2286)
						)
						(arc
							(start -0.254 0.2286)
							(mid -0.239121 0.264521)
							(end -0.2032 0.2794)
						)
						(arc
							(start 0.2032 0.2794)
							(mid 0.239121 0.264521)
							(end 0.254 0.2286)
						)
						(arc
							(start 0.254 -0.2286)
							(mid 0.239121 -0.264521)
							(end 0.2032 -0.2794)
						)
					)
					(width 0)
					(fill yes)
				)
			)
		)
	)
	(footprint ""
		(layer "F.Cu")
		(at 171.2468 -12.701778 180)
		(property "Reference" "C300"
			(at 0 0 180)
			(layer "F.SilkS")
			(hide yes)
			(effects
				(font
					(size 1.27 1.27)
				)
			)
		)
		(property "Value" "SC10U6D3V3MX-GP"
			(at -0.0254 -2.0193 180)
			(unlocked yes)
			(layer "F.Fab")
			(hide yes)
			(effects
				(font
					(size 1.016 1.016)
					(thickness 0.1524)
				)
			)
		)
		(property "Device Type" "C603H38"
			(at -0.0254 -3.5433 180)
			(unlocked yes)
			(layer "F.Fab")
			(hide yes)
			(effects
				(font
					(size 1.016 1.016)
					(thickness 0.1524)
				)
			)
		)
		(duplicate_pad_numbers_are_jumpers no)
		(fp_line
			(start -0.4064 0)
			(end 0.4064 0)
			(stroke
				(width 0.2286)
				(type default)
			)
			(layer "F.SilkS")
		)
		(fp_rect
			(start -0.635 1.1811)
			(end 0.635 -1.1811)
			(stroke
				(width 0)
				(type default)
			)
			(fill no)
			(layer "F.CrtYd")
		)
		(fp_rect
			(start -0.635 1.1811)
			(end 0.635 -1.1811)
			(stroke
				(width 0)
				(type default)
			)
			(fill no)
			(layer "F.Fab")
		)
		(pad "1" smd custom
			(at 0 -0.6604 180)
			(size 0.19685 0.19685)
			(layers "F.Cu" "F.Mask" "F.Paste")
			(net "PV_VDDR")
			(options
				(clearance outline)
				(anchor circle)
			)
			(primitives
				(gr_poly
					(pts
						(arc
							(start 0.508 -0.2921)
							(mid 0.478242 -0.363942)
							(end 0.4064 -0.3937)
						)
						(arc
							(start -0.4064 -0.3937)
							(mid -0.478242 -0.363942)
							(end -0.508 -0.2921)
						)
						(arc
							(start -0.508 0.2921)
							(mid -0.478242 0.363942)
							(end -0.4064 0.3937)
						)
						(arc
							(start 0.4064 0.3937)
							(mid 0.478242 0.363942)
							(end 0.508 0.2921)
						)
					)
					(width 0)
					(fill yes)
				)
			)
		)
		(pad "2" smd custom
			(at 0 0.6604 180)
			(size 0.19685 0.19685)
			(layers "F.Cu" "F.Mask" "F.Paste")
			(net "GND")
			(options
				(clearance outline)
				(anchor circle)
			)
			(primitives
				(gr_poly
					(pts
						(arc
							(start 0.508 -0.2921)
							(mid 0.478242 -0.363942)
							(end 0.4064 -0.3937)
						)
						(arc
							(start -0.4064 -0.3937)
							(mid -0.478242 -0.363942)
							(end -0.508 -0.2921)
						)
						(arc
							(start -0.508 0.2921)
							(mid -0.478242 0.363942)
							(end -0.4064 0.3937)
						)
						(arc
							(start 0.4064 0.3937)
							(mid 0.478242 0.363942)
							(end 0.508 0.2921)
						)
					)
					(width 0)
					(fill yes)
				)
			)
		)
	)
	(footprint ""
		(layer "F.Cu")
		(at 187.5028 -25.781 90)
		(property "Reference" "PR162"
			(at 0 0 90)
			(layer "F.SilkS")
			(hide yes)
			(effects
				(font
					(size 1.27 1.27)
				)
			)
		)
		(property "Value" "0R2J-2-GP"
			(at 1.7907 -1.1176 90)
			(unlocked yes)
			(layer "F.Fab")
			(hide yes)
			(effects
				(font
					(size 1.016 1.016)
					(thickness 0.1524)
				)
			)
		)
		(property "Device Type" "R402H16"
			(at 1.7907 -2.6416 90)
			(unlocked yes)
			(layer "F.Fab")
			(hide yes)
			(effects
				(font
					(size 1.016 1.016)
					(thickness 0.1524)
				)
			)
		)
		(duplicate_pad_numbers_are_jumpers no)
		(fp_rect
			(start -0.381 0.8382)
			(end 0.381 -0.8382)
			(stroke
				(width 0)
				(type default)
			)
			(fill no)
			(layer "F.CrtYd")
		)
		(fp_rect
			(start -0.381 0.8382)
			(end 0.381 -0.8382)
			(stroke
				(width 0)
				(type default)
			)
			(fill no)
			(layer "F.Fab")
		)
		(pad "1" smd custom
			(at 0 -0.4318 90)
			(size 0.127 0.127)
			(layers "F.Cu" "F.Mask" "F.Paste")
			(net "VSENSE_PVDDR_A_VSEN")
			(options
				(clearance outline)
				(anchor circle)
			)
			(primitives
				(gr_poly
					(pts
						(arc
							(start -0.2032 -0.2794)
							(mid -0.239121 -0.264521)
							(end -0.254 -0.2286)
						)
						(arc
							(start -0.254 0.2286)
							(mid -0.239121 0.264521)
							(end -0.2032 0.2794)
						)
						(arc
							(start 0.2032 0.2794)
							(mid 0.239121 0.264521)
							(end 0.254 0.2286)
						)
						(arc
							(start 0.254 -0.2286)
							(mid 0.239121 -0.264521)
							(end 0.2032 -0.2794)
						)
					)
					(width 0)
					(fill yes)
				)
			)
		)
		(pad "2" smd custom
			(at 0 0.4318 90)
			(size 0.127 0.127)
			(layers "F.Cu" "F.Mask" "F.Paste")
			(net "VR_PVDDR_A_VTT")
			(options
				(clearance outline)
				(anchor circle)
			)
			(primitives
				(gr_poly
					(pts
						(arc
							(start -0.2032 -0.2794)
							(mid -0.239121 -0.264521)
							(end -0.254 -0.2286)
						)
						(arc
							(start -0.254 0.2286)
							(mid -0.239121 0.264521)
							(end -0.2032 0.2794)
						)
						(arc
							(start 0.2032 0.2794)
							(mid 0.239121 0.264521)
							(end 0.254 0.2286)
						)
						(arc
							(start 0.254 -0.2286)
							(mid 0.239121 -0.264521)
							(end 0.2032 -0.2794)
						)
					)
					(width 0)
					(fill yes)
				)
			)
		)
	)
	(footprint ""
		(layer "F.Cu")
		(at 132.715 -56.388)
		(property "Reference" "PR80"
			(at 0 0 0)
			(layer "F.SilkS")
			(hide yes)
			(effects
				(font
					(size 1.27 1.27)
				)
			)
		)
		(property "Value" "0R3J-0-U-GP"
			(at -0.0254 -2.5146 0)
			(unlocked yes)
			(layer "F.Fab")
			(hide yes)
			(effects
				(font
					(size 1.016 1.016)
					(thickness 0.1524)
				)
			)
		)
		(property "Device Type" "R603H22"
			(at -0.0254 -4.0386 0)
			(unlocked yes)
			(layer "F.Fab")
			(hide yes)
			(effects
				(font
					(size 1.016 1.016)
					(thickness 0.1524)
				)
			)
		)
		(duplicate_pad_numbers_are_jumpers no)
		(fp_line
			(start -0.2032 0)
			(end -0.4191 0)
			(stroke
				(width 0.2032)
				(type default)
			)
			(layer "F.SilkS")
		)
		(fp_line
			(start 0.4318 0)
			(end 0.2032 0)
			(stroke
				(width 0.2032)
				(type default)
			)
			(layer "F.SilkS")
		)
		(fp_rect
			(start -0.635 1.1811)
			(end 0.635 -1.1811)
			(stroke
				(width 0)
				(type default)
			)
			(fill no)
			(layer "F.CrtYd")
		)
		(fp_rect
			(start -0.635 1.1811)
			(end 0.635 -1.1811)
			(stroke
				(width 0)
				(type default)
			)
			(fill no)
			(layer "F.Fab")
		)
		(pad "1" smd custom
			(at 0 -0.6604)
			(size 0.19685 0.19685)
			(layers "F.Cu" "F.Mask" "F.Paste")
			(net "PV_VTT_DDR_A")
			(options
				(clearance outline)
				(anchor circle)
			)
			(primitives
				(gr_poly
					(pts
						(arc
							(start 0.508 -0.2921)
							(mid 0.478242 -0.363942)
							(end 0.4064 -0.3937)
						)
						(arc
							(start -0.4064 -0.3937)
							(mid -0.478242 -0.363942)
							(end -0.508 -0.2921)
						)
						(arc
							(start -0.508 0.2921)
							(mid -0.478242 0.363942)
							(end -0.4064 0.3937)
						)
						(arc
							(start 0.4064 0.3937)
							(mid 0.478242 0.363942)
							(end 0.508 0.2921)
						)
					)
					(width 0)
					(fill yes)
				)
			)
		)
		(pad "2" smd custom
			(at 0 0.6604)
			(size 0.19685 0.19685)
			(layers "F.Cu" "F.Mask" "F.Paste")
			(net "PV_VTT_DDR_SNS")
			(options
				(clearance outline)
				(anchor circle)
			)
			(primitives
				(gr_poly
					(pts
						(arc
							(start 0.508 -0.2921)
							(mid 0.478242 -0.363942)
							(end 0.4064 -0.3937)
						)
						(arc
							(start -0.4064 -0.3937)
							(mid -0.478242 -0.363942)
							(end -0.508 -0.2921)
						)
						(arc
							(start -0.508 0.2921)
							(mid -0.478242 0.363942)
							(end -0.4064 0.3937)
						)
						(arc
							(start 0.4064 0.3937)
							(mid 0.478242 0.363942)
							(end 0.508 0.2921)
						)
					)
					(width 0)
					(fill yes)
				)
			)
		)
	)
	(footprint ""
		(layer "F.Cu")
		(at 111.887 -67.691 180)
		(property "Reference" "U3"
			(at 0 0 180)
			(layer "F.SilkS")
			(hide yes)
			(effects
				(font
					(size 1.27 1.27)
				)
			)
		)
		(property "Value" "2N7002DW-7F-GP"
			(at -2.3622 -8.2042 180)
			(unlocked yes)
			(layer "F.Fab")
			(hide yes)
			(effects
				(font
					(size 1.016 1.016)
					(thickness 0.1524)
				)
			)
		)
		(property "Device Type" "SOT-363H44"
			(at -2.3622 -10.1092 180)
			(unlocked yes)
			(layer "F.Fab")
			(hide yes)
			(effects
				(font
					(size 1.016 1.016)
					(thickness 0.1524)
				)
			)
		)
		(duplicate_pad_numbers_are_jumpers no)
		(fp_poly
			(pts
				(xy -0.6731 1.4351) (xy -0.9779 1.7399) (xy -0.381 1.7399) (xy -0.3683 1.7399) (xy -0.381 1.7272)
			)
			(stroke
				(width 0)
				(type default)
			)
			(fill yes)
			(layer "F.SilkS")
		)
		(fp_poly
			(pts
				(xy 1.2573 0.8763) (xy 1.2573 -0.8763) (xy 0.9525 -0.8763) (xy 0.9525 -1.4351) (xy -0.9525 -1.4351)
				(xy -0.9525 -0.8763) (xy -1.2573 -0.8763) (xy -1.2573 0.8763) (xy -0.9525 0.8763) (xy -0.9525 1.4351)
				(xy 0.9525 1.4351) (xy 0.9525 0.8763)
			)
			(stroke
				(width 0)
				(type default)
			)
			(fill no)
			(layer "F.CrtYd")
		)
		(fp_poly
			(pts
				(xy 1.2573 0.8763) (xy 1.2573 -0.8763) (xy 0.9525 -0.8763) (xy 0.9525 -1.4351) (xy -0.9525 -1.4351)
				(xy -0.9525 -0.8763) (xy -1.2573 -0.8763) (xy -1.2573 0.8763) (xy -0.9525 0.8763) (xy -0.9525 1.4351)
				(xy 0.9525 1.4351) (xy 0.9525 0.8763)
			)
			(stroke
				(width 0)
				(type default)
			)
			(fill no)
			(layer "F.Fab")
		)
		(pad "1" smd rect
			(at -0.65024 0.8255 180)
			(size 0.3556 0.9652)
			(layers "F.Cu" "F.Mask" "F.Paste")
			(net "GND")
		)
		(pad "2" smd rect
			(at 0 0.8255 180)
			(size 0.3556 0.9652)
			(layers "F.Cu" "F.Mask" "F.Paste")
			(net "CLK_GEN_OUT_R")
		)
		(pad "3" smd rect
			(at 0.65024 0.8255 180)
			(size 0.3556 0.9652)
			(layers "F.Cu" "F.Mask" "F.Paste")
			(net "CORE_PWROK")
		)
		(pad "4" smd rect
			(at 0.65024 -0.8255 180)
			(size 0.3556 0.9652)
			(layers "F.Cu" "F.Mask" "F.Paste")
			(net "GND")
		)
		(pad "5" smd rect
			(at 0 -0.8255 180)
			(size 0.3556 0.9652)
			(layers "F.Cu" "F.Mask" "F.Paste")
			(net "CLK_GEN_OUT_R")
		)
		(pad "6" smd rect
			(at -0.65024 -0.8255 180)
			(size 0.3556 0.9652)
			(layers "F.Cu" "F.Mask" "F.Paste")
			(net "PWRGD_DDR3_VCCA")
		)
	)
	(footprint ""
		(layer "F.Cu")
		(at 133.731 -19.431)
		(property "Reference" "R395"
			(at 0 0 0)
			(layer "F.SilkS")
			(hide yes)
			(effects
				(font
					(size 1.27 1.27)
				)
			)
		)
		(property "Value" "0R2J-2-GP"
			(at 1.7907 -1.1176 0)
			(unlocked yes)
			(layer "F.Fab")
			(hide yes)
			(effects
				(font
					(size 1.016 1.016)
					(thickness 0.1524)
				)
			)
		)
		(property "Device Type" "R402H16"
			(at 1.7907 -2.6416 0)
			(unlocked yes)
			(layer "F.Fab")
			(hide yes)
			(effects
				(font
					(size 1.016 1.016)
					(thickness 0.1524)
				)
			)
		)
		(duplicate_pad_numbers_are_jumpers no)
		(fp_rect
			(start -0.381 0.8382)
			(end 0.381 -0.8382)
			(stroke
				(width 0)
				(type default)
			)
			(fill no)
			(layer "F.CrtYd")
		)
		(fp_rect
			(start -0.381 0.8382)
			(end 0.381 -0.8382)
			(stroke
				(width 0)
				(type default)
			)
			(fill no)
			(layer "F.Fab")
		)
		(pad "1" smd custom
			(at 0 -0.4318)
			(size 0.127 0.127)
			(layers "F.Cu" "F.Mask" "F.Paste")
			(net "POWER_GOOD_R")
			(options
				(clearance outline)
				(anchor circle)
			)
			(primitives
				(gr_poly
					(pts
						(arc
							(start -0.2032 -0.2794)
							(mid -0.239121 -0.264521)
							(end -0.254 -0.2286)
						)
						(arc
							(start -0.254 0.2286)
							(mid -0.239121 0.264521)
							(end -0.2032 0.2794)
						)
						(arc
							(start 0.2032 0.2794)
							(mid 0.239121 0.264521)
							(end 0.254 0.2286)
						)
						(arc
							(start 0.254 -0.2286)
							(mid 0.239121 -0.264521)
							(end 0.2032 -0.2794)
						)
					)
					(width 0)
					(fill yes)
				)
			)
		)
		(pad "2" smd custom
			(at 0 0.4318)
			(size 0.127 0.127)
			(layers "F.Cu" "F.Mask" "F.Paste")
			(net "POWER_GOOD")
			(options
				(clearance outline)
				(anchor circle)
			)
			(primitives
				(gr_poly
					(pts
						(arc
							(start -0.2032 -0.2794)
							(mid -0.239121 -0.264521)
							(end -0.254 -0.2286)
						)
						(arc
							(start -0.254 0.2286)
							(mid -0.239121 0.264521)
							(end -0.2032 0.2794)
						)
						(arc
							(start 0.2032 0.2794)
							(mid 0.239121 0.264521)
							(end 0.254 0.2286)
						)
						(arc
							(start 0.254 -0.2286)
							(mid 0.239121 -0.264521)
							(end 0.2032 -0.2794)
						)
					)
					(width 0)
					(fill yes)
				)
			)
		)
	)
	(footprint ""
		(layer "F.Cu")
		(at 61.468 -44.704 180)
		(property "Reference" "C72"
			(at 0 0 180)
			(layer "F.SilkS")
			(hide yes)
			(effects
				(font
					(size 1.27 1.27)
				)
			)
		)
		(property "Value" "SCD1U10V2KX-5GP"
			(at 1.8923 -1.2065 180)
			(unlocked yes)
			(layer "F.Fab")
			(hide yes)
			(effects
				(font
					(size 1.016 1.016)
					(thickness 0.1524)
				)
			)
		)
		(property "Device Type" "C402H22"
			(at 1.8923 -2.7305 180)
			(unlocked yes)
			(layer "F.Fab")
			(hide yes)
			(effects
				(font
					(size 1.016 1.016)
					(thickness 0.1524)
				)
			)
		)
		(duplicate_pad_numbers_are_jumpers no)
		(fp_rect
			(start -0.381 0.7366)
			(end 0.381 -0.7366)
			(stroke
				(width 0)
				(type default)
			)
			(fill no)
			(layer "F.CrtYd")
		)
		(fp_rect
			(start -0.381 0.7366)
			(end 0.381 -0.7366)
			(stroke
				(width 0)
				(type default)
			)
			(fill no)
			(layer "F.Fab")
		)
		(pad "1" smd custom
			(at 0 -0.4572 180)
			(size 0.1143 0.1143)
			(layers "F.Cu" "F.Mask" "F.Paste")
			(net "P3V3_STBY")
			(options
				(clearance outline)
				(anchor circle)
			)
			(primitives
				(gr_poly
					(pts
						(arc
							(start -0.254 -0.1778)
							(mid -0.239121 -0.213721)
							(end -0.2032 -0.2286)
						)
						(arc
							(start 0.2032 -0.2286)
							(mid 0.239121 -0.213721)
							(end 0.254 -0.1778)
						)
						(arc
							(start 0.254 0.1778)
							(mid 0.239121 0.213721)
							(end 0.2032 0.2286)
						)
						(arc
							(start -0.2032 0.2286)
							(mid -0.239121 0.213721)
							(end -0.254 0.1778)
						)
					)
					(width 0)
					(fill yes)
				)
			)
		)
		(pad "2" smd custom
			(at 0 0.4572 180)
			(size 0.1143 0.1143)
			(layers "F.Cu" "F.Mask" "F.Paste")
			(net "GND")
			(options
				(clearance outline)
				(anchor circle)
			)
			(primitives
				(gr_poly
					(pts
						(arc
							(start -0.254 -0.1778)
							(mid -0.239121 -0.213721)
							(end -0.2032 -0.2286)
						)
						(arc
							(start 0.2032 -0.2286)
							(mid 0.239121 -0.213721)
							(end 0.254 -0.1778)
						)
						(arc
							(start 0.254 0.1778)
							(mid 0.239121 0.213721)
							(end 0.2032 0.2286)
						)
						(arc
							(start -0.2032 0.2286)
							(mid -0.239121 0.213721)
							(end -0.254 0.1778)
						)
					)
					(width 0)
					(fill yes)
				)
			)
		)
	)
	(footprint ""
		(layer "F.Cu")
		(at 48.514 -50.165 -90)
		(property "Reference" "C24"
			(at 0 0 270)
			(layer "F.SilkS")
			(hide yes)
			(effects
				(font
					(size 1.27 1.27)
				)
			)
		)
		(property "Value" "SC10U6D3V3MX-GP"
			(at 0 -2.8194 270)
			(unlocked yes)
			(layer "F.Fab")
			(hide yes)
			(effects
				(font
					(size 1.016 1.016)
					(thickness 0.1524)
				)
			)
		)
		(property "Device Type" "C603H38"
			(at 0 -4.3434 270)
			(unlocked yes)
			(layer "F.Fab")
			(hide yes)
			(effects
				(font
					(size 1.016 1.016)
					(thickness 0.1524)
				)
			)
		)
		(duplicate_pad_numbers_are_jumpers no)
		(fp_line
			(start -0.4064 0)
			(end 0.4064 0)
			(stroke
				(width 0.2286)
				(type default)
			)
			(layer "F.SilkS")
		)
		(fp_rect
			(start -0.635 1.1811)
			(end 0.635 -1.1811)
			(stroke
				(width 0)
				(type default)
			)
			(fill no)
			(layer "F.CrtYd")
		)
		(fp_rect
			(start -0.635 1.1811)
			(end 0.635 -1.1811)
			(stroke
				(width 0)
				(type default)
			)
			(fill no)
			(layer "F.Fab")
		)
		(pad "1" smd custom
			(at 0 -0.6604 270)
			(size 0.19685 0.19685)
			(layers "F.Cu" "F.Mask" "F.Paste")
			(net "P1V5_CLK_SCR_LVIO")
			(options
				(clearance outline)
				(anchor circle)
			)
			(primitives
				(gr_poly
					(pts
						(arc
							(start 0.508 -0.2921)
							(mid 0.478242 -0.363942)
							(end 0.4064 -0.3937)
						)
						(arc
							(start -0.4064 -0.3937)
							(mid -0.478242 -0.363942)
							(end -0.508 -0.2921)
						)
						(arc
							(start -0.508 0.2921)
							(mid -0.478242 0.363942)
							(end -0.4064 0.3937)
						)
						(arc
							(start 0.4064 0.3937)
							(mid 0.478242 0.363942)
							(end 0.508 0.2921)
						)
					)
					(width 0)
					(fill yes)
				)
			)
		)
		(pad "2" smd custom
			(at 0 0.6604 270)
			(size 0.19685 0.19685)
			(layers "F.Cu" "F.Mask" "F.Paste")
			(net "GND")
			(options
				(clearance outline)
				(anchor circle)
			)
			(primitives
				(gr_poly
					(pts
						(arc
							(start 0.508 -0.2921)
							(mid 0.478242 -0.363942)
							(end 0.4064 -0.3937)
						)
						(arc
							(start -0.4064 -0.3937)
							(mid -0.478242 -0.363942)
							(end -0.508 -0.2921)
						)
						(arc
							(start -0.508 0.2921)
							(mid -0.478242 0.363942)
							(end -0.4064 0.3937)
						)
						(arc
							(start 0.4064 0.3937)
							(mid 0.478242 0.363942)
							(end 0.508 0.2921)
						)
					)
					(width 0)
					(fill yes)
				)
			)
		)
	)
	(footprint ""
		(layer "F.Cu")
		(at 155.575 -59.309)
		(property "Reference" "C328"
			(at 0 0 0)
			(layer "F.SilkS")
			(hide yes)
			(effects
				(font
					(size 1.27 1.27)
				)
			)
		)
		(property "Value" "SCD1U16V2KX-3GP"
			(at 1.8923 -1.2065 0)
			(unlocked yes)
			(layer "F.Fab")
			(hide yes)
			(effects
				(font
					(size 1.016 1.016)
					(thickness 0.1524)
				)
			)
		)
		(property "Device Type" "C402H22"
			(at 1.8923 -2.7305 0)
			(unlocked yes)
			(layer "F.Fab")
			(hide yes)
			(effects
				(font
					(size 1.016 1.016)
					(thickness 0.1524)
				)
			)
		)
		(duplicate_pad_numbers_are_jumpers no)
		(fp_rect
			(start -0.381 0.7366)
			(end 0.381 -0.7366)
			(stroke
				(width 0)
				(type default)
			)
			(fill no)
			(layer "F.CrtYd")
		)
		(fp_rect
			(start -0.381 0.7366)
			(end 0.381 -0.7366)
			(stroke
				(width 0)
				(type default)
			)
			(fill no)
			(layer "F.Fab")
		)
		(pad "1" smd custom
			(at 0 -0.4572)
			(size 0.1143 0.1143)
			(layers "F.Cu" "F.Mask" "F.Paste")
			(net "PV_VDDR")
			(options
				(clearance outline)
				(anchor circle)
			)
			(primitives
				(gr_poly
					(pts
						(arc
							(start -0.254 -0.1778)
							(mid -0.239121 -0.213721)
							(end -0.2032 -0.2286)
						)
						(arc
							(start 0.2032 -0.2286)
							(mid 0.239121 -0.213721)
							(end 0.254 -0.1778)
						)
						(arc
							(start 0.254 0.1778)
							(mid 0.239121 0.213721)
							(end 0.2032 0.2286)
						)
						(arc
							(start -0.2032 0.2286)
							(mid -0.239121 0.213721)
							(end -0.254 0.1778)
						)
					)
					(width 0)
					(fill yes)
				)
			)
		)
		(pad "2" smd custom
			(at 0 0.4572)
			(size 0.1143 0.1143)
			(layers "F.Cu" "F.Mask" "F.Paste")
			(net "GND")
			(options
				(clearance outline)
				(anchor circle)
			)
			(primitives
				(gr_poly
					(pts
						(arc
							(start -0.254 -0.1778)
							(mid -0.239121 -0.213721)
							(end -0.2032 -0.2286)
						)
						(arc
							(start 0.2032 -0.2286)
							(mid 0.239121 -0.213721)
							(end 0.254 -0.1778)
						)
						(arc
							(start 0.254 0.1778)
							(mid 0.239121 0.213721)
							(end 0.2032 0.2286)
						)
						(arc
							(start -0.2032 0.2286)
							(mid -0.239121 0.213721)
							(end -0.254 0.1778)
						)
					)
					(width 0)
					(fill yes)
				)
			)
		)
	)
	(footprint ""
		(layer "F.Cu")
		(at 34.9504 -54.9656)
		(property "Reference" "PC20"
			(at 0 0 0)
			(layer "F.SilkS")
			(hide yes)
			(effects
				(font
					(size 1.27 1.27)
				)
			)
		)
		(property "Value" "SC10U25V5KX-GP"
			(at 0 -4.9022 0)
			(unlocked yes)
			(layer "F.Fab")
			(hide yes)
			(effects
				(font
					(size 1.016 1.016)
					(thickness 0.1524)
				)
			)
		)
		(property "Device Type" "C805H56"
			(at 0 -6.8072 0)
			(unlocked yes)
			(layer "F.Fab")
			(hide yes)
			(effects
				(font
					(size 1.016 1.016)
					(thickness 0.1524)
				)
			)
		)
		(duplicate_pad_numbers_are_jumpers no)
		(fp_line
			(start 0.6096 0)
			(end -0.6096 0)
			(stroke
				(width 0.3048)
				(type default)
			)
			(layer "F.SilkS")
		)
		(fp_poly
			(pts
				(xy -0.9017 1.4351) (xy 0.9017 1.4351) (xy 0.9017 -1.4351) (xy -0.9017 -1.4351)
			)
			(stroke
				(width 0)
				(type default)
			)
			(fill no)
			(layer "F.CrtYd")
		)
		(fp_poly
			(pts
				(xy 0.9017 1.4351) (xy 0.9017 -1.4351) (xy -0.9017 -1.4351) (xy -0.9017 1.4351)
			)
			(stroke
				(width 0)
				(type default)
			)
			(fill no)
			(layer "F.Fab")
		)
		(pad "1" smd rect
			(at 0 -0.8382)
			(size 1.5494 0.9398)
			(layers "F.Cu" "F.Mask" "F.Paste")
			(net "VR_FET_SW_P12V_PVCCP_PVNN")
		)
		(pad "2" smd rect
			(at 0 0.8382)
			(size 1.5494 0.9398)
			(layers "F.Cu" "F.Mask" "F.Paste")
			(net "GND")
		)
	)
	(footprint ""
		(layer "F.Cu")
		(at 31.4198 -38.7604 180)
		(property "Reference" "R491"
			(at 0 0 180)
			(layer "F.SilkS")
			(hide yes)
			(effects
				(font
					(size 1.27 1.27)
				)
			)
		)
		(property "Value" "51R2F-2-GP"
			(at 1.7907 -1.1176 180)
			(unlocked yes)
			(layer "F.Fab")
			(hide yes)
			(effects
				(font
					(size 1.016 1.016)
					(thickness 0.1524)
				)
			)
		)
		(property "Device Type" "R402H16"
			(at 1.7907 -2.6416 180)
			(unlocked yes)
			(layer "F.Fab")
			(hide yes)
			(effects
				(font
					(size 1.016 1.016)
					(thickness 0.1524)
				)
			)
		)
		(duplicate_pad_numbers_are_jumpers no)
		(fp_rect
			(start -0.381 0.8382)
			(end 0.381 -0.8382)
			(stroke
				(width 0)
				(type default)
			)
			(fill no)
			(layer "F.CrtYd")
		)
		(fp_rect
			(start -0.381 0.8382)
			(end 0.381 -0.8382)
			(stroke
				(width 0)
				(type default)
			)
			(fill no)
			(layer "F.Fab")
		)
		(pad "1" smd custom
			(at 0 -0.4318 180)
			(size 0.127 0.127)
			(layers "F.Cu" "F.Mask" "F.Paste")
			(net "P1V0_STBY")
			(options
				(clearance outline)
				(anchor circle)
			)
			(primitives
				(gr_poly
					(pts
						(arc
							(start -0.2032 -0.2794)
							(mid -0.239121 -0.264521)
							(end -0.254 -0.2286)
						)
						(arc
							(start -0.254 0.2286)
							(mid -0.239121 0.264521)
							(end -0.2032 0.2794)
						)
						(arc
							(start 0.2032 0.2794)
							(mid 0.239121 0.264521)
							(end 0.254 0.2286)
						)
						(arc
							(start 0.254 -0.2286)
							(mid 0.239121 -0.264521)
							(end 0.2032 -0.2794)
						)
					)
					(width 0)
					(fill yes)
				)
			)
		)
		(pad "2" smd custom
			(at 0 0.4318 180)
			(size 0.127 0.127)
			(layers "F.Cu" "F.Mask" "F.Paste")
			(net "XDP_SOC_CPU_TCK")
			(options
				(clearance outline)
				(anchor circle)
			)
			(primitives
				(gr_poly
					(pts
						(arc
							(start -0.2032 -0.2794)
							(mid -0.239121 -0.264521)
							(end -0.254 -0.2286)
						)
						(arc
							(start -0.254 0.2286)
							(mid -0.239121 0.264521)
							(end -0.2032 0.2794)
						)
						(arc
							(start 0.2032 0.2794)
							(mid 0.239121 0.264521)
							(end 0.254 0.2286)
						)
						(arc
							(start 0.254 -0.2286)
							(mid 0.239121 -0.264521)
							(end 0.2032 -0.2794)
						)
					)
					(width 0)
					(fill yes)
				)
			)
		)
	)
	(footprint ""
		(layer "F.Cu")
		(at 23.368 -43.307 180)
		(property "Reference" "PC149"
			(at 0 0 180)
			(layer "F.SilkS")
			(hide yes)
			(effects
				(font
					(size 1.27 1.27)
				)
			)
		)
		(property "Value" "SC22U6D3V3MX-1-GP"
			(at -0.0254 -2.0193 180)
			(unlocked yes)
			(layer "F.Fab")
			(hide yes)
			(effects
				(font
					(size 1.016 1.016)
					(thickness 0.1524)
				)
			)
		)
		(property "Device Type" "C603H40"
			(at -0.0254 -3.5433 180)
			(unlocked yes)
			(layer "F.Fab")
			(hide yes)
			(effects
				(font
					(size 1.016 1.016)
					(thickness 0.1524)
				)
			)
		)
		(duplicate_pad_numbers_are_jumpers no)
		(fp_line
			(start -0.4064 0)
			(end 0.4064 0)
			(stroke
				(width 0.2286)
				(type default)
			)
			(layer "F.SilkS")
		)
		(fp_rect
			(start -0.635 1.1811)
			(end 0.635 -1.1811)
			(stroke
				(width 0)
				(type default)
			)
			(fill no)
			(layer "F.CrtYd")
		)
		(fp_rect
			(start -0.635 1.1811)
			(end 0.635 -1.1811)
			(stroke
				(width 0)
				(type default)
			)
			(fill no)
			(layer "F.Fab")
		)
		(pad "1" smd custom
			(at 0 -0.6604 180)
			(size 0.19685 0.19685)
			(layers "F.Cu" "F.Mask" "F.Paste")
			(net "P3V3_STBY_OUT")
			(options
				(clearance outline)
				(anchor circle)
			)
			(primitives
				(gr_poly
					(pts
						(arc
							(start 0.508 -0.2921)
							(mid 0.478242 -0.363942)
							(end 0.4064 -0.3937)
						)
						(arc
							(start -0.4064 -0.3937)
							(mid -0.478242 -0.363942)
							(end -0.508 -0.2921)
						)
						(arc
							(start -0.508 0.2921)
							(mid -0.478242 0.363942)
							(end -0.4064 0.3937)
						)
						(arc
							(start 0.4064 0.3937)
							(mid 0.478242 0.363942)
							(end 0.508 0.2921)
						)
					)
					(width 0)
					(fill yes)
				)
			)
		)
		(pad "2" smd custom
			(at 0 0.6604 180)
			(size 0.19685 0.19685)
			(layers "F.Cu" "F.Mask" "F.Paste")
			(net "GND")
			(options
				(clearance outline)
				(anchor circle)
			)
			(primitives
				(gr_poly
					(pts
						(arc
							(start 0.508 -0.2921)
							(mid 0.478242 -0.363942)
							(end 0.4064 -0.3937)
						)
						(arc
							(start -0.4064 -0.3937)
							(mid -0.478242 -0.363942)
							(end -0.508 -0.2921)
						)
						(arc
							(start -0.508 0.2921)
							(mid -0.478242 0.363942)
							(end -0.4064 0.3937)
						)
						(arc
							(start 0.4064 0.3937)
							(mid 0.478242 0.363942)
							(end 0.508 0.2921)
						)
					)
					(width 0)
					(fill yes)
				)
			)
		)
	)
	(footprint ""
		(layer "F.Cu")
		(at 156.845 -45.339 90)
		(property "Reference" "R213"
			(at 0 0 90)
			(layer "F.SilkS")
			(hide yes)
			(effects
				(font
					(size 1.27 1.27)
				)
			)
		)
		(property "Value" "0R2J-2-GP"
			(at 1.7907 -1.1176 90)
			(unlocked yes)
			(layer "F.Fab")
			(hide yes)
			(effects
				(font
					(size 1.016 1.016)
					(thickness 0.1524)
				)
			)
		)
		(property "Device Type" "R402H16"
			(at 1.7907 -2.6416 90)
			(unlocked yes)
			(layer "F.Fab")
			(hide yes)
			(effects
				(font
					(size 1.016 1.016)
					(thickness 0.1524)
				)
			)
		)
		(duplicate_pad_numbers_are_jumpers no)
		(fp_rect
			(start -0.381 0.8382)
			(end 0.381 -0.8382)
			(stroke
				(width 0)
				(type default)
			)
			(fill no)
			(layer "F.CrtYd")
		)
		(fp_rect
			(start -0.381 0.8382)
			(end 0.381 -0.8382)
			(stroke
				(width 0)
				(type default)
			)
			(fill no)
			(layer "F.Fab")
		)
		(pad "1" smd custom
			(at 0 -0.4318 90)
			(size 0.127 0.127)
			(layers "F.Cu" "F.Mask" "F.Paste")
			(net "JTAG_CPU_PLD_TDO")
			(options
				(clearance outline)
				(anchor circle)
			)
			(primitives
				(gr_poly
					(pts
						(arc
							(start -0.2032 -0.2794)
							(mid -0.239121 -0.264521)
							(end -0.254 -0.2286)
						)
						(arc
							(start -0.254 0.2286)
							(mid -0.239121 0.264521)
							(end -0.2032 0.2794)
						)
						(arc
							(start 0.2032 0.2794)
							(mid 0.239121 0.264521)
							(end 0.254 0.2286)
						)
						(arc
							(start 0.254 -0.2286)
							(mid 0.239121 -0.264521)
							(end 0.2032 -0.2794)
						)
					)
					(width 0)
					(fill yes)
				)
			)
		)
		(pad "2" smd custom
			(at 0 0.4318 90)
			(size 0.127 0.127)
			(layers "F.Cu" "F.Mask" "F.Paste")
			(net "JTAG_CPU_PLD_TDO_D")
			(options
				(clearance outline)
				(anchor circle)
			)
			(primitives
				(gr_poly
					(pts
						(arc
							(start -0.2032 -0.2794)
							(mid -0.239121 -0.264521)
							(end -0.254 -0.2286)
						)
						(arc
							(start -0.254 0.2286)
							(mid -0.239121 0.264521)
							(end -0.2032 0.2794)
						)
						(arc
							(start 0.2032 0.2794)
							(mid 0.239121 0.264521)
							(end 0.254 0.2286)
						)
						(arc
							(start 0.254 -0.2286)
							(mid 0.239121 -0.264521)
							(end 0.2032 -0.2794)
						)
					)
					(width 0)
					(fill yes)
				)
			)
		)
	)
	(footprint ""
		(layer "F.Cu")
		(at 21.463 -58.42 90)
		(property "Reference" "PU3"
			(at 0 0 90)
			(layer "F.SilkS")
			(hide yes)
			(effects
				(font
					(size 1.27 1.27)
				)
			)
		)
		(property "Value" "ISL95831HRTZ-T-GP"
			(at 4.2164 1.2954 90)
			(unlocked yes)
			(layer "F.Fab")
			(hide yes)
			(effects
				(font
					(size 1.016 1.016)
					(thickness 0.1524)
				)
			)
		)
		(property "Device Type" "QFN48J6-G4D55H32"
			(at 4.2164 -0.2286 90)
			(unlocked yes)
			(layer "F.Fab")
			(hide yes)
			(effects
				(font
					(size 1.016 1.016)
					(thickness 0.1524)
				)
			)
		)
		(duplicate_pad_numbers_are_jumpers no)
		(fp_poly
			(pts
				(xy 2.180844 -3.38963) (xy 2.601214 -3.81) (xy 1.760474 -3.81)
			)
			(stroke
				(width 0)
				(type default)
			)
			(fill yes)
			(layer "F.SilkS")
		)
		(fp_rect
			(start -3.3782 3.3782)
			(end 3.3782 -3.3782)
			(stroke
				(width 0)
				(type default)
			)
			(fill no)
			(layer "F.CrtYd")
		)
		(fp_rect
			(start -3.3782 3.3782)
			(end 3.3782 -3.3782)
			(stroke
				(width 0)
				(type default)
			)
			(fill no)
			(layer "F.Fab")
		)
		(pad "1" smd rect
			(at 2.199894 -2.872994 90)
			(size 0.2032 0.762)
			(layers "F.Cu" "F.Mask" "F.Paste")
			(net "VR_PVNN_VW")
		)
		(pad "2" smd rect
			(at 1.800098 -2.872994 90)
			(size 0.2032 0.762)
			(layers "F.Cu" "F.Mask" "F.Paste")
			(net "VR_PVNN_IMON")
		)
		(pad "3" smd rect
			(at 1.400048 -2.872994 90)
			(size 0.2032 0.762)
			(layers "F.Cu" "F.Mask" "F.Paste")
			(net "PWRGD_R_PVNN")
		)
		(pad "4" smd rect
			(at 0.999998 -2.872994 90)
			(size 0.2032 0.762)
			(layers "F.Cu" "F.Mask" "F.Paste")
			(net "VR_95831_SDA")
		)
		(pad "5" smd rect
			(at 0.599948 -2.872994 90)
			(size 0.2032 0.762)
			(layers "F.Cu" "F.Mask" "F.Paste")
			(net "VR_95831_ALERT_N")
		)
		(pad "6" smd rect
			(at 0.199898 -2.872994 90)
			(size 0.2032 0.762)
			(layers "F.Cu" "F.Mask" "F.Paste")
			(net "VR_95831_SCLK")
		)
		(pad "7" smd rect
			(at -0.199898 -2.872994 90)
			(size 0.2032 0.762)
			(layers "F.Cu" "F.Mask" "F.Paste")
			(net "PVCC_PVNN_EN_R")
		)
		(pad "8" smd rect
			(at -0.599948 -2.872994 90)
			(size 0.2032 0.762)
			(layers "F.Cu" "F.Mask" "F.Paste")
			(net "PWRGD_R_PVCCP")
		)
		(pad "9" smd rect
			(at -0.999998 -2.872994 90)
			(size 0.2032 0.762)
			(layers "F.Cu" "F.Mask" "F.Paste")
			(net "VR_PVCCP_IMON")
		)
		(pad "10" smd rect
			(at -1.400048 -2.872994 90)
			(size 0.2032 0.762)
			(layers "F.Cu" "F.Mask" "F.Paste")
			(net "PVCCP_PVNN_R_VRHOT#")
		)
		(pad "11" smd rect
			(at -1.800098 -2.872994 90)
			(size 0.2032 0.762)
			(layers "F.Cu" "F.Mask" "F.Paste")
			(net "Net_315")
		)
		(pad "12" smd rect
			(at -2.199894 -2.872994 90)
			(size 0.2032 0.762)
			(layers "F.Cu" "F.Mask" "F.Paste")
			(net "VR_PVCCP_VW")
		)
		(pad "13" smd rect
			(at -2.872994 -2.199894 90)
			(size 0.762 0.2032)
			(layers "F.Cu" "F.Mask" "F.Paste")
			(net "VR_PVCCP_COMP")
		)
		(pad "14" smd rect
			(at -2.872994 -1.800098 90)
			(size 0.762 0.2032)
			(layers "F.Cu" "F.Mask" "F.Paste")
			(net "VR_PVCCP_FB")
		)
		(pad "15" smd rect
			(at -2.872994 -1.400048 90)
			(size 0.762 0.2032)
			(layers "F.Cu" "F.Mask" "F.Paste")
			(net "Net_322")
		)
		(pad "16" smd rect
			(at -2.872994 -0.999998 90)
			(size 0.762 0.2032)
			(layers "F.Cu" "F.Mask" "F.Paste")
			(net "PVCCP_ISEN2")
		)
		(pad "17" smd rect
			(at -2.872994 -0.599948 90)
			(size 0.762 0.2032)
			(layers "F.Cu" "F.Mask" "F.Paste")
			(net "VR_PVCCP_ISEN1_R")
		)
		(pad "18" smd rect
			(at -2.872994 -0.199898 90)
			(size 0.762 0.2032)
			(layers "F.Cu" "F.Mask" "F.Paste")
			(net "VR_PVCCP_VSEN")
		)
		(pad "19" smd rect
			(at -2.872994 0.199898 90)
			(size 0.762 0.2032)
			(layers "F.Cu" "F.Mask" "F.Paste")
			(net "VR_PVCCP_RTN")
		)
		(pad "20" smd rect
			(at -2.872994 0.599948 90)
			(size 0.762 0.2032)
			(layers "F.Cu" "F.Mask" "F.Paste")
			(net "VR_PVCCP_ISUMN_R")
		)
		(pad "21" smd rect
			(at -2.872994 0.999998 90)
			(size 0.762 0.2032)
			(layers "F.Cu" "F.Mask" "F.Paste")
			(net "VR_PVCCP_ISUMP")
		)
		(pad "22" smd rect
			(at -2.872994 1.400048 90)
			(size 0.762 0.2032)
			(layers "F.Cu" "F.Mask" "F.Paste")
			(net "VR_PVCCP_PVNN_VDD")
		)
		(pad "23" smd rect
			(at -2.872994 1.800098 90)
			(size 0.762 0.2032)
			(layers "F.Cu" "F.Mask" "F.Paste")
			(net "VR_PVCCP_PVNN_VIN")
		)
		(pad "24" smd rect
			(at -2.872994 2.199894 90)
			(size 0.762 0.2032)
			(layers "F.Cu" "F.Mask" "F.Paste")
			(net "VR_PVCCP_PROG1")
		)
		(pad "25" smd rect
			(at -2.199894 2.872994 90)
			(size 0.2032 0.762)
			(layers "F.Cu" "F.Mask" "F.Paste")
			(net "VR_PVCCP_BOOT")
		)
		(pad "26" smd rect
			(at -1.800098 2.872994 90)
			(size 0.2032 0.762)
			(layers "F.Cu" "F.Mask" "F.Paste")
			(net "VR_PVCCP_GH")
		)
		(pad "27" smd rect
			(at -1.400048 2.872994 90)
			(size 0.2032 0.762)
			(layers "F.Cu" "F.Mask" "F.Paste")
			(net "VR_PVCCP_PHASE")
		)
		(pad "28" smd rect
			(at -0.999998 2.872994 90)
			(size 0.2032 0.762)
			(layers "F.Cu" "F.Mask" "F.Paste")
			(net "GND")
		)
		(pad "29" smd rect
			(at -0.599948 2.872994 90)
			(size 0.2032 0.762)
			(layers "F.Cu" "F.Mask" "F.Paste")
			(net "VR_PVCCP_GL")
		)
		(pad "30" smd rect
			(at -0.199898 2.872994 90)
			(size 0.2032 0.762)
			(layers "F.Cu" "F.Mask" "F.Paste")
			(net "VR_PVCCP_PWM3")
		)
		(pad "31" smd rect
			(at 0.199898 2.872994 90)
			(size 0.2032 0.762)
			(layers "F.Cu" "F.Mask" "F.Paste")
			(net "VR_PVCCP_PVNN_VCCP")
		)
		(pad "32" smd rect
			(at 0.599948 2.872994 90)
			(size 0.2032 0.762)
			(layers "F.Cu" "F.Mask" "F.Paste")
			(net "Net_311")
		)
		(pad "33" smd rect
			(at 0.999998 2.872994 90)
			(size 0.2032 0.762)
			(layers "F.Cu" "F.Mask" "F.Paste")
			(net "GND")
		)
		(pad "34" smd rect
			(at 1.400048 2.872994 90)
			(size 0.2032 0.762)
			(layers "F.Cu" "F.Mask" "F.Paste")
			(net "Net_312")
		)
		(pad "35" smd rect
			(at 1.800098 2.872994 90)
			(size 0.2032 0.762)
			(layers "F.Cu" "F.Mask" "F.Paste")
			(net "Net_313")
		)
		(pad "36" smd rect
			(at 2.199894 2.872994 90)
			(size 0.2032 0.762)
			(layers "F.Cu" "F.Mask" "F.Paste")
			(net "Net_314")
		)
		(pad "37" smd rect
			(at 2.872994 2.199894 90)
			(size 0.762 0.2032)
			(layers "F.Cu" "F.Mask" "F.Paste")
			(net "VR_PVNN_GL")
		)
		(pad "38" smd rect
			(at 2.872994 1.800098 90)
			(size 0.762 0.2032)
			(layers "F.Cu" "F.Mask" "F.Paste")
			(net "VR_PVNN_PHASE")
		)
		(pad "39" smd rect
			(at 2.872994 1.400048 90)
			(size 0.762 0.2032)
			(layers "F.Cu" "F.Mask" "F.Paste")
			(net "VR_PVNN_GH")
		)
		(pad "40" smd rect
			(at 2.872994 0.999998 90)
			(size 0.762 0.2032)
			(layers "F.Cu" "F.Mask" "F.Paste")
			(net "VR_PVNN_BOOT")
		)
		(pad "41" smd rect
			(at 2.872994 0.599948 90)
			(size 0.762 0.2032)
			(layers "F.Cu" "F.Mask" "F.Paste")
			(net "VR_PVNN_PROG2")
		)
		(pad "42" smd rect
			(at 2.872994 0.199898 90)
			(size 0.762 0.2032)
			(layers "F.Cu" "F.Mask" "F.Paste")
			(net "VR_PVNN_NTC")
		)
		(pad "43" smd rect
			(at 2.872994 -0.199898 90)
			(size 0.762 0.2032)
			(layers "F.Cu" "F.Mask" "F.Paste")
			(net "VR_PVNN_ISUMN_R")
		)
		(pad "44" smd rect
			(at 2.872994 -0.599948 90)
			(size 0.762 0.2032)
			(layers "F.Cu" "F.Mask" "F.Paste")
			(net "VR_PVNN_ISUMP")
		)
		(pad "45" smd rect
			(at 2.872994 -0.999998 90)
			(size 0.762 0.2032)
			(layers "F.Cu" "F.Mask" "F.Paste")
			(net "VR_PVNN_RTN")
		)
		(pad "46" smd rect
			(at 2.872994 -1.400048 90)
			(size 0.762 0.2032)
			(layers "F.Cu" "F.Mask" "F.Paste")
			(net "VR_PVNN_VSEN")
		)
		(pad "47" smd rect
			(at 2.872994 -1.800098 90)
			(size 0.762 0.2032)
			(layers "F.Cu" "F.Mask" "F.Paste")
			(net "VR_PVNN_FB")
		)
		(pad "48" smd rect
			(at 2.872994 -2.199894 90)
			(size 0.762 0.2032)
			(layers "F.Cu" "F.Mask" "F.Paste")
			(net "VR_PVNN_COMP")
		)
		(pad "49" smd rect
			(at 0 0 90)
			(size 4.5466 4.5466)
			(layers "F.Cu" "F.Mask" "F.Paste")
			(net "GND")
		)
	)
	(footprint ""
		(layer "F.Cu")
		(at 25.654 -62.5094 180)
		(property "Reference" "PR25"
			(at 0 0 180)
			(layer "F.SilkS")
			(hide yes)
			(effects
				(font
					(size 1.27 1.27)
				)
			)
		)
		(property "Value" "0R3J-0-U-GP"
			(at -0.0254 -2.0193 180)
			(unlocked yes)
			(layer "F.Fab")
			(hide yes)
			(effects
				(font
					(size 1.016 1.016)
					(thickness 0.1524)
				)
			)
		)
		(property "Device Type" "R603H22"
			(at -0.0254 -3.5433 180)
			(unlocked yes)
			(layer "F.Fab")
			(hide yes)
			(effects
				(font
					(size 1.016 1.016)
					(thickness 0.1524)
				)
			)
		)
		(duplicate_pad_numbers_are_jumpers no)
		(fp_line
			(start 0.4318 0)
			(end 0.2032 0)
			(stroke
				(width 0.2032)
				(type default)
			)
			(layer "F.SilkS")
		)
		(fp_line
			(start -0.2032 0)
			(end -0.4191 0)
			(stroke
				(width 0.2032)
				(type default)
			)
			(layer "F.SilkS")
		)
		(fp_rect
			(start -0.635 1.1811)
			(end 0.635 -1.1811)
			(stroke
				(width 0)
				(type default)
			)
			(fill no)
			(layer "F.CrtYd")
		)
		(fp_rect
			(start -0.635 1.1811)
			(end 0.635 -1.1811)
			(stroke
				(width 0)
				(type default)
			)
			(fill no)
			(layer "F.Fab")
		)
		(pad "1" smd custom
			(at 0 -0.6604 180)
			(size 0.19685 0.19685)
			(layers "F.Cu" "F.Mask" "F.Paste")
			(net "VR_PVNN_GL")
			(options
				(clearance outline)
				(anchor circle)
			)
			(primitives
				(gr_poly
					(pts
						(arc
							(start 0.508 -0.2921)
							(mid 0.478242 -0.363942)
							(end 0.4064 -0.3937)
						)
						(arc
							(start -0.4064 -0.3937)
							(mid -0.478242 -0.363942)
							(end -0.508 -0.2921)
						)
						(arc
							(start -0.508 0.2921)
							(mid -0.478242 0.363942)
							(end -0.4064 0.3937)
						)
						(arc
							(start 0.4064 0.3937)
							(mid 0.478242 0.363942)
							(end 0.508 0.2921)
						)
					)
					(width 0)
					(fill yes)
				)
			)
		)
		(pad "2" smd custom
			(at 0 0.6604 180)
			(size 0.19685 0.19685)
			(layers "F.Cu" "F.Mask" "F.Paste")
			(net "VR_PVNN_LH_R")
			(options
				(clearance outline)
				(anchor circle)
			)
			(primitives
				(gr_poly
					(pts
						(arc
							(start 0.508 -0.2921)
							(mid 0.478242 -0.363942)
							(end 0.4064 -0.3937)
						)
						(arc
							(start -0.4064 -0.3937)
							(mid -0.478242 -0.363942)
							(end -0.508 -0.2921)
						)
						(arc
							(start -0.508 0.2921)
							(mid -0.478242 0.363942)
							(end -0.4064 0.3937)
						)
						(arc
							(start 0.4064 0.3937)
							(mid 0.478242 0.363942)
							(end 0.508 0.2921)
						)
					)
					(width 0)
					(fill yes)
				)
			)
		)
	)
	(footprint ""
		(layer "F.Cu")
		(at 48.5902 -34.925 180)
		(property "Reference" "R115"
			(at 0 0 180)
			(layer "F.SilkS")
			(hide yes)
			(effects
				(font
					(size 1.27 1.27)
				)
			)
		)
		(property "Value" "33R2F-3-GP"
			(at 0.064008 -3.993896 180)
			(unlocked yes)
			(layer "F.Fab")
			(hide yes)
			(effects
				(font
					(size 1.016 1.016)
					(thickness 0.1524)
				)
			)
		)
		(property "Device Type" "R402H16"
			(at 0.064008 -5.517896 180)
			(unlocked yes)
			(layer "F.Fab")
			(hide yes)
			(effects
				(font
					(size 1.016 1.016)
					(thickness 0.1524)
				)
			)
		)
		(duplicate_pad_numbers_are_jumpers no)
		(fp_rect
			(start -0.381 0.8382)
			(end 0.381 -0.8382)
			(stroke
				(width 0)
				(type default)
			)
			(fill no)
			(layer "F.CrtYd")
		)
		(fp_rect
			(start -0.381 0.8382)
			(end 0.381 -0.8382)
			(stroke
				(width 0)
				(type default)
			)
			(fill no)
			(layer "F.Fab")
		)
		(pad "1" smd custom
			(at 0 -0.4318 180)
			(size 0.127 0.127)
			(layers "F.Cu" "F.Mask" "F.Paste")
			(net "SPI_MOSI_R_1")
			(options
				(clearance outline)
				(anchor circle)
			)
			(primitives
				(gr_poly
					(pts
						(arc
							(start -0.2032 -0.2794)
							(mid -0.239121 -0.264521)
							(end -0.254 -0.2286)
						)
						(arc
							(start -0.254 0.2286)
							(mid -0.239121 0.264521)
							(end -0.2032 0.2794)
						)
						(arc
							(start 0.2032 0.2794)
							(mid 0.239121 0.264521)
							(end 0.254 0.2286)
						)
						(arc
							(start 0.254 -0.2286)
							(mid 0.239121 -0.264521)
							(end 0.2032 -0.2794)
						)
					)
					(width 0)
					(fill yes)
				)
			)
		)
		(pad "2" smd custom
			(at 0 0.4318 180)
			(size 0.127 0.127)
			(layers "F.Cu" "F.Mask" "F.Paste")
			(net "SPI_CPU_MOSI")
			(options
				(clearance outline)
				(anchor circle)
			)
			(primitives
				(gr_poly
					(pts
						(arc
							(start -0.2032 -0.2794)
							(mid -0.239121 -0.264521)
							(end -0.254 -0.2286)
						)
						(arc
							(start -0.254 0.2286)
							(mid -0.239121 0.264521)
							(end -0.2032 0.2794)
						)
						(arc
							(start 0.2032 0.2794)
							(mid 0.239121 0.264521)
							(end 0.254 0.2286)
						)
						(arc
							(start 0.254 -0.2286)
							(mid 0.239121 -0.264521)
							(end 0.2032 -0.2794)
						)
					)
					(width 0)
					(fill yes)
				)
			)
		)
	)
	(footprint ""
		(layer "F.Cu")
		(at 16.1544 -43.6626 -90)
		(property "Reference" "PR197"
			(at 0 0 270)
			(layer "F.SilkS")
			(hide yes)
			(effects
				(font
					(size 1.27 1.27)
				)
			)
		)
		(property "Value" "3D01R5F-GP"
			(at 0 -4.9022 270)
			(unlocked yes)
			(layer "F.Fab")
			(hide yes)
			(effects
				(font
					(size 1.016 1.016)
					(thickness 0.1524)
				)
			)
		)
		(property "Device Type" "R805H24"
			(at 0 -6.8072 270)
			(unlocked yes)
			(layer "F.Fab")
			(hide yes)
			(effects
				(font
					(size 1.016 1.016)
					(thickness 0.1524)
				)
			)
		)
		(duplicate_pad_numbers_are_jumpers no)
		(fp_line
			(start -0.2794 0)
			(end -0.6096 0)
			(stroke
				(width 0.3048)
				(type default)
			)
			(layer "F.SilkS")
		)
		(fp_line
			(start 0.6096 0)
			(end 0.2794 0)
			(stroke
				(width 0.3048)
				(type default)
			)
			(layer "F.SilkS")
		)
		(fp_poly
			(pts
				(xy -0.9017 1.4351) (xy 0.9017 1.4351) (xy 0.9017 -1.4351) (xy -0.9017 -1.4351)
			)
			(stroke
				(width 0)
				(type default)
			)
			(fill no)
			(layer "F.CrtYd")
		)
		(fp_poly
			(pts
				(xy 0.9017 1.4351) (xy 0.9017 -1.4351) (xy -0.9017 -1.4351) (xy -0.9017 1.4351)
			)
			(stroke
				(width 0)
				(type default)
			)
			(fill no)
			(layer "F.Fab")
		)
		(pad "1" smd rect
			(at 0 -0.8382 270)
			(size 1.5494 0.9398)
			(layers "F.Cu" "F.Mask" "F.Paste")
			(net "P3V3_STBY_SNB")
		)
		(pad "2" smd rect
			(at 0 0.8382 270)
			(size 1.5494 0.9398)
			(layers "F.Cu" "F.Mask" "F.Paste")
			(net "GND")
		)
	)
	(footprint ""
		(layer "F.Cu")
		(at 26.162 -47.879 -90)
		(property "Reference" "PR95"
			(at 0 0 270)
			(layer "F.SilkS")
			(hide yes)
			(effects
				(font
					(size 1.27 1.27)
				)
			)
		)
		(property "Value" "2K61R2F-1-GP"
			(at 1.7907 -1.1176 270)
			(unlocked yes)
			(layer "F.Fab")
			(hide yes)
			(effects
				(font
					(size 1.016 1.016)
					(thickness 0.1524)
				)
			)
		)
		(property "Device Type" "R402H16"
			(at 1.7907 -2.6416 270)
			(unlocked yes)
			(layer "F.Fab")
			(hide yes)
			(effects
				(font
					(size 1.016 1.016)
					(thickness 0.1524)
				)
			)
		)
		(duplicate_pad_numbers_are_jumpers no)
		(fp_rect
			(start -0.381 0.8382)
			(end 0.381 -0.8382)
			(stroke
				(width 0)
				(type default)
			)
			(fill no)
			(layer "F.CrtYd")
		)
		(fp_rect
			(start -0.381 0.8382)
			(end 0.381 -0.8382)
			(stroke
				(width 0)
				(type default)
			)
			(fill no)
			(layer "F.Fab")
		)
		(pad "1" smd custom
			(at 0 -0.4318 270)
			(size 0.127 0.127)
			(layers "F.Cu" "F.Mask" "F.Paste")
			(net "VR_PVCCP_ISUMP")
			(options
				(clearance outline)
				(anchor circle)
			)
			(primitives
				(gr_poly
					(pts
						(arc
							(start -0.2032 -0.2794)
							(mid -0.239121 -0.264521)
							(end -0.254 -0.2286)
						)
						(arc
							(start -0.254 0.2286)
							(mid -0.239121 0.264521)
							(end -0.2032 0.2794)
						)
						(arc
							(start 0.2032 0.2794)
							(mid 0.239121 0.264521)
							(end 0.254 0.2286)
						)
						(arc
							(start 0.254 -0.2286)
							(mid 0.239121 -0.264521)
							(end 0.2032 -0.2794)
						)
					)
					(width 0)
					(fill yes)
				)
			)
		)
		(pad "2" smd custom
			(at 0 0.4318 270)
			(size 0.127 0.127)
			(layers "F.Cu" "F.Mask" "F.Paste")
			(net "VR_PVCCP_NTC")
			(options
				(clearance outline)
				(anchor circle)
			)
			(primitives
				(gr_poly
					(pts
						(arc
							(start -0.2032 -0.2794)
							(mid -0.239121 -0.264521)
							(end -0.254 -0.2286)
						)
						(arc
							(start -0.254 0.2286)
							(mid -0.239121 0.264521)
							(end -0.2032 0.2794)
						)
						(arc
							(start 0.2032 0.2794)
							(mid 0.239121 0.264521)
							(end 0.254 0.2286)
						)
						(arc
							(start 0.254 -0.2286)
							(mid 0.239121 -0.264521)
							(end 0.2032 -0.2794)
						)
					)
					(width 0)
					(fill yes)
				)
			)
		)
	)
	(footprint ""
		(layer "F.Cu")
		(at 185.674 -39.878)
		(property "Reference" "PR122"
			(at 0 0 0)
			(layer "F.SilkS")
			(hide yes)
			(effects
				(font
					(size 1.27 1.27)
				)
			)
		)
		(property "Value" "10KR2F-2-GP"
			(at 1.7907 -1.1176 0)
			(unlocked yes)
			(layer "F.Fab")
			(hide yes)
			(effects
				(font
					(size 1.016 1.016)
					(thickness 0.1524)
				)
			)
		)
		(property "Device Type" "R402H16"
			(at 1.7907 -2.6416 0)
			(unlocked yes)
			(layer "F.Fab")
			(hide yes)
			(effects
				(font
					(size 1.016 1.016)
					(thickness 0.1524)
				)
			)
		)
		(duplicate_pad_numbers_are_jumpers no)
		(fp_rect
			(start -0.381 0.8382)
			(end 0.381 -0.8382)
			(stroke
				(width 0)
				(type default)
			)
			(fill no)
			(layer "F.CrtYd")
		)
		(fp_rect
			(start -0.381 0.8382)
			(end 0.381 -0.8382)
			(stroke
				(width 0)
				(type default)
			)
			(fill no)
			(layer "F.Fab")
		)
		(pad "1" smd custom
			(at 0 -0.4318)
			(size 0.127 0.127)
			(layers "F.Cu" "F.Mask" "F.Paste")
			(net "GND")
			(options
				(clearance outline)
				(anchor circle)
			)
			(primitives
				(gr_poly
					(pts
						(arc
							(start -0.2032 -0.2794)
							(mid -0.239121 -0.264521)
							(end -0.254 -0.2286)
						)
						(arc
							(start -0.254 0.2286)
							(mid -0.239121 0.264521)
							(end -0.2032 0.2794)
						)
						(arc
							(start 0.2032 0.2794)
							(mid 0.239121 0.264521)
							(end 0.254 0.2286)
						)
						(arc
							(start 0.254 -0.2286)
							(mid 0.239121 -0.264521)
							(end 0.2032 -0.2794)
						)
					)
					(width 0)
					(fill yes)
				)
			)
		)
		(pad "2" smd custom
			(at 0 0.4318)
			(size 0.127 0.127)
			(layers "F.Cu" "F.Mask" "F.Paste")
			(net "VR_PVDDR_A_OCP")
			(options
				(clearance outline)
				(anchor circle)
			)
			(primitives
				(gr_poly
					(pts
						(arc
							(start -0.2032 -0.2794)
							(mid -0.239121 -0.264521)
							(end -0.254 -0.2286)
						)
						(arc
							(start -0.254 0.2286)
							(mid -0.239121 0.264521)
							(end -0.2032 0.2794)
						)
						(arc
							(start 0.2032 0.2794)
							(mid 0.239121 0.264521)
							(end 0.254 0.2286)
						)
						(arc
							(start 0.254 -0.2286)
							(mid 0.239121 -0.264521)
							(end 0.2032 -0.2794)
						)
					)
					(width 0)
					(fill yes)
				)
			)
		)
	)
	(footprint ""
		(layer "F.Cu")
		(at 13.716 -56.5404)
		(property "Reference" "PR55"
			(at 0 0 0)
			(layer "F.SilkS")
			(hide yes)
			(effects
				(font
					(size 1.27 1.27)
				)
			)
		)
		(property "Value" "1K91R2F-1-GP"
			(at 1.7907 -1.1176 0)
			(unlocked yes)
			(layer "F.Fab")
			(hide yes)
			(effects
				(font
					(size 1.016 1.016)
					(thickness 0.1524)
				)
			)
		)
		(property "Device Type" "R402H16"
			(at 1.7907 -2.6416 0)
			(unlocked yes)
			(layer "F.Fab")
			(hide yes)
			(effects
				(font
					(size 1.016 1.016)
					(thickness 0.1524)
				)
			)
		)
		(duplicate_pad_numbers_are_jumpers no)
		(fp_rect
			(start -0.381 0.8382)
			(end 0.381 -0.8382)
			(stroke
				(width 0)
				(type default)
			)
			(fill no)
			(layer "F.CrtYd")
		)
		(fp_rect
			(start -0.381 0.8382)
			(end 0.381 -0.8382)
			(stroke
				(width 0)
				(type default)
			)
			(fill no)
			(layer "F.Fab")
		)
		(pad "1" smd custom
			(at 0 -0.4318)
			(size 0.127 0.127)
			(layers "F.Cu" "F.Mask" "F.Paste")
			(net "P3V3_STBY")
			(options
				(clearance outline)
				(anchor circle)
			)
			(primitives
				(gr_poly
					(pts
						(arc
							(start -0.2032 -0.2794)
							(mid -0.239121 -0.264521)
							(end -0.254 -0.2286)
						)
						(arc
							(start -0.254 0.2286)
							(mid -0.239121 0.264521)
							(end -0.2032 0.2794)
						)
						(arc
							(start 0.2032 0.2794)
							(mid 0.239121 0.264521)
							(end 0.254 0.2286)
						)
						(arc
							(start 0.254 -0.2286)
							(mid 0.239121 -0.264521)
							(end 0.2032 -0.2794)
						)
					)
					(width 0)
					(fill yes)
				)
			)
		)
		(pad "2" smd custom
			(at 0 0.4318)
			(size 0.127 0.127)
			(layers "F.Cu" "F.Mask" "F.Paste")
			(net "PWRGD_PVCCP_VNN_PG")
			(options
				(clearance outline)
				(anchor circle)
			)
			(primitives
				(gr_poly
					(pts
						(arc
							(start -0.2032 -0.2794)
							(mid -0.239121 -0.264521)
							(end -0.254 -0.2286)
						)
						(arc
							(start -0.254 0.2286)
							(mid -0.239121 0.264521)
							(end -0.2032 0.2794)
						)
						(arc
							(start 0.2032 0.2794)
							(mid 0.239121 0.264521)
							(end 0.254 0.2286)
						)
						(arc
							(start 0.254 -0.2286)
							(mid 0.239121 -0.264521)
							(end 0.2032 -0.2794)
						)
					)
					(width 0)
					(fill yes)
				)
			)
		)
	)
	(footprint ""
		(layer "F.Cu")
		(at 59.436 -25.908 -90)
		(property "Reference" "R255"
			(at 0 0 270)
			(layer "F.SilkS")
			(hide yes)
			(effects
				(font
					(size 1.27 1.27)
				)
			)
		)
		(property "Value" "1KR2F-3-GP"
			(at 0.064008 -3.993896 270)
			(unlocked yes)
			(layer "F.Fab")
			(hide yes)
			(effects
				(font
					(size 1.016 1.016)
					(thickness 0.1524)
				)
			)
		)
		(property "Device Type" "R402H16"
			(at 0.064008 -5.517896 270)
			(unlocked yes)
			(layer "F.Fab")
			(hide yes)
			(effects
				(font
					(size 1.016 1.016)
					(thickness 0.1524)
				)
			)
		)
		(duplicate_pad_numbers_are_jumpers no)
		(fp_rect
			(start -0.381 0.8382)
			(end 0.381 -0.8382)
			(stroke
				(width 0)
				(type default)
			)
			(fill no)
			(layer "F.CrtYd")
		)
		(fp_rect
			(start -0.381 0.8382)
			(end 0.381 -0.8382)
			(stroke
				(width 0)
				(type default)
			)
			(fill no)
			(layer "F.Fab")
		)
		(pad "1" smd custom
			(at 0 -0.4318 270)
			(size 0.127 0.127)
			(layers "F.Cu" "F.Mask" "F.Paste")
			(net "P3V3_STBY")
			(options
				(clearance outline)
				(anchor circle)
			)
			(primitives
				(gr_poly
					(pts
						(arc
							(start -0.2032 -0.2794)
							(mid -0.239121 -0.264521)
							(end -0.254 -0.2286)
						)
						(arc
							(start -0.254 0.2286)
							(mid -0.239121 0.264521)
							(end -0.2032 0.2794)
						)
						(arc
							(start 0.2032 0.2794)
							(mid 0.239121 0.264521)
							(end 0.254 0.2286)
						)
						(arc
							(start 0.254 -0.2286)
							(mid 0.239121 -0.264521)
							(end 0.2032 -0.2794)
						)
					)
					(width 0)
					(fill yes)
				)
			)
		)
		(pad "2" smd custom
			(at 0 0.4318 270)
			(size 0.127 0.127)
			(layers "F.Cu" "F.Mask" "F.Paste")
			(net "PWRGD_P1V8_PG")
			(options
				(clearance outline)
				(anchor circle)
			)
			(primitives
				(gr_poly
					(pts
						(arc
							(start -0.2032 -0.2794)
							(mid -0.239121 -0.264521)
							(end -0.254 -0.2286)
						)
						(arc
							(start -0.254 0.2286)
							(mid -0.239121 0.264521)
							(end -0.2032 0.2794)
						)
						(arc
							(start 0.2032 0.2794)
							(mid 0.239121 0.264521)
							(end 0.254 0.2286)
						)
						(arc
							(start 0.254 -0.2286)
							(mid 0.239121 -0.264521)
							(end 0.2032 -0.2794)
						)
					)
					(width 0)
					(fill yes)
				)
			)
		)
	)
	(footprint ""
		(layer "F.Cu")
		(at 52.767992 -28.796234 90)
		(property "Reference" "U18"
			(at 0 0 90)
			(layer "F.SilkS")
			(hide yes)
			(effects
				(font
					(size 1.27 1.27)
				)
			)
		)
		(property "Value" "W25Q64FVSSIG-GP"
			(at 0 -13.1572 90)
			(unlocked yes)
			(layer "F.Fab")
			(hide yes)
			(effects
				(font
					(size 1.016 1.016)
					(thickness 0.1524)
				)
			)
		)
		(property "Device Type" "SOIC8-1H86"
			(at 0 -14.6812 90)
			(unlocked yes)
			(layer "F.Fab")
			(hide yes)
			(effects
				(font
					(size 1.016 1.016)
					(thickness 0.1524)
				)
			)
		)
		(duplicate_pad_numbers_are_jumpers no)
		(fp_line
			(start 2.1336 -2.4003)
			(end -2.8194 -2.4003)
			(stroke
				(width 0.1524)
				(type default)
			)
			(layer "F.SilkS")
		)
		(fp_line
			(start -2.8194 -2.4003)
			(end -2.8194 2.4003)
			(stroke
				(width 0.1524)
				(type default)
			)
			(layer "F.SilkS")
		)
		(fp_line
			(start 2.1336 -2.3876)
			(end 2.1336 -2.4003)
			(stroke
				(width 0.1524)
				(type default)
			)
			(layer "F.SilkS")
		)
		(fp_line
			(start -2.8194 -0.508)
			(end -2.8194 2.4003)
			(stroke
				(width 0.1524)
				(type default)
			)
			(layer "F.SilkS")
		)
		(fp_line
			(start -2.3114 0)
			(end -2.8194 -0.508)
			(stroke
				(width 0.1524)
				(type default)
			)
			(layer "F.SilkS")
		)
		(fp_line
			(start -2.8194 0.508)
			(end -2.3114 0)
			(stroke
				(width 0.1524)
				(type default)
			)
			(layer "F.SilkS")
		)
		(fp_line
			(start -2.6416 2.3114)
			(end -2.6416 4.0767)
			(stroke
				(width 0.508)
				(type default)
			)
			(layer "F.SilkS")
		)
		(fp_line
			(start 2.1336 2.4003)
			(end 2.1336 -2.4003)
			(stroke
				(width 0.1524)
				(type default)
			)
			(layer "F.SilkS")
		)
		(fp_line
			(start -2.8194 2.4003)
			(end 2.1336 2.4003)
			(stroke
				(width 0.1524)
				(type default)
			)
			(layer "F.SilkS")
		)
		(fp_poly
			(pts
				(xy -2.2352 2.4003) (xy 2.1336 2.4003) (xy 2.1336 -2.4003) (xy -2.2352 -2.4003)
			)
			(stroke
				(width 0)
				(type default)
			)
			(fill yes)
			(layer "F.SilkS")
		)
		(fp_rect
			(start -2.8956 4.3307)
			(end 2.8956 -4.3307)
			(stroke
				(width 0)
				(type default)
			)
			(fill no)
			(layer "F.CrtYd")
		)
		(fp_rect
			(start -2.8956 4.3307)
			(end 2.8956 -4.3307)
			(stroke
				(width 0)
				(type default)
			)
			(fill no)
			(layer "F.Fab")
		)
		(pad "1" smd rect
			(at -1.905 3.441954 90)
			(size 0.635 1.524)
			(layers "F.Cu" "F.Mask" "F.Paste")
			(net "SPI_CS0_N_M_1")
		)
		(pad "2" smd rect
			(at -0.635 3.441954 90)
			(size 0.635 1.524)
			(layers "F.Cu" "F.Mask" "F.Paste")
			(net "SPI_MISO_R_1")
		)
		(pad "3" smd rect
			(at 0.635 3.441954 90)
			(size 0.635 1.524)
			(layers "F.Cu" "F.Mask" "F.Paste")
			(net "SPI_WP_R_N_1")
		)
		(pad "4" smd rect
			(at 1.905 3.441954 90)
			(size 0.635 1.524)
			(layers "F.Cu" "F.Mask" "F.Paste")
			(net "GND")
		)
		(pad "5" smd rect
			(at 1.905 -3.441954 90)
			(size 0.635 1.524)
			(layers "F.Cu" "F.Mask" "F.Paste")
			(net "SPI_MOSI_R_1")
		)
		(pad "6" smd rect
			(at 0.635 -3.441954 90)
			(size 0.635 1.524)
			(layers "F.Cu" "F.Mask" "F.Paste")
			(net "SPI_SCLK_R_1")
		)
		(pad "7" smd rect
			(at -0.635 -3.441954 90)
			(size 0.635 1.524)
			(layers "F.Cu" "F.Mask" "F.Paste")
			(net "SPI_HOLD#")
		)
		(pad "8" smd rect
			(at -1.905 -3.441954 90)
			(size 0.635 1.524)
			(layers "F.Cu" "F.Mask" "F.Paste")
			(net "P3V3_CPU")
		)
	)
	(footprint ""
		(layer "F.Cu")
		(at 197.2818 -33.782 90)
		(property "Reference" "PR109"
			(at 0 0 90)
			(layer "F.SilkS")
			(hide yes)
			(effects
				(font
					(size 1.27 1.27)
				)
			)
		)
		(property "Value" "0R3J-0-U-GP"
			(at -0.0254 -2.0193 90)
			(unlocked yes)
			(layer "F.Fab")
			(hide yes)
			(effects
				(font
					(size 1.016 1.016)
					(thickness 0.1524)
				)
			)
		)
		(property "Device Type" "R603H22"
			(at -0.0254 -3.5433 90)
			(unlocked yes)
			(layer "F.Fab")
			(hide yes)
			(effects
				(font
					(size 1.016 1.016)
					(thickness 0.1524)
				)
			)
		)
		(duplicate_pad_numbers_are_jumpers no)
		(fp_line
			(start 0.4318 0)
			(end 0.2032 0)
			(stroke
				(width 0.2032)
				(type default)
			)
			(layer "F.SilkS")
		)
		(fp_line
			(start -0.2032 0)
			(end -0.4191 0)
			(stroke
				(width 0.2032)
				(type default)
			)
			(layer "F.SilkS")
		)
		(fp_rect
			(start -0.635 1.1811)
			(end 0.635 -1.1811)
			(stroke
				(width 0)
				(type default)
			)
			(fill no)
			(layer "F.CrtYd")
		)
		(fp_rect
			(start -0.635 1.1811)
			(end 0.635 -1.1811)
			(stroke
				(width 0)
				(type default)
			)
			(fill no)
			(layer "F.Fab")
		)
		(pad "1" smd custom
			(at 0 -0.6604 90)
			(size 0.19685 0.19685)
			(layers "F.Cu" "F.Mask" "F.Paste")
			(net "VR_PVDDR_A_GH1")
			(options
				(clearance outline)
				(anchor circle)
			)
			(primitives
				(gr_poly
					(pts
						(arc
							(start 0.508 -0.2921)
							(mid 0.478242 -0.363942)
							(end 0.4064 -0.3937)
						)
						(arc
							(start -0.4064 -0.3937)
							(mid -0.478242 -0.363942)
							(end -0.508 -0.2921)
						)
						(arc
							(start -0.508 0.2921)
							(mid -0.478242 0.363942)
							(end -0.4064 0.3937)
						)
						(arc
							(start 0.4064 0.3937)
							(mid 0.478242 0.363942)
							(end 0.508 0.2921)
						)
					)
					(width 0)
					(fill yes)
				)
			)
		)
		(pad "2" smd custom
			(at 0 0.6604 90)
			(size 0.19685 0.19685)
			(layers "F.Cu" "F.Mask" "F.Paste")
			(net "VR_PVDDR_A_GH1_R")
			(options
				(clearance outline)
				(anchor circle)
			)
			(primitives
				(gr_poly
					(pts
						(arc
							(start 0.508 -0.2921)
							(mid 0.478242 -0.363942)
							(end 0.4064 -0.3937)
						)
						(arc
							(start -0.4064 -0.3937)
							(mid -0.478242 -0.363942)
							(end -0.508 -0.2921)
						)
						(arc
							(start -0.508 0.2921)
							(mid -0.478242 0.363942)
							(end -0.4064 0.3937)
						)
						(arc
							(start 0.4064 0.3937)
							(mid 0.478242 0.363942)
							(end 0.508 0.2921)
						)
					)
					(width 0)
					(fill yes)
				)
			)
		)
	)
	(footprint ""
		(layer "F.Cu")
		(at 46.2788 -34.417 180)
		(property "Reference" "C339"
			(at 0 0 180)
			(layer "F.SilkS")
			(hide yes)
			(effects
				(font
					(size 1.27 1.27)
				)
			)
		)
		(property "Value" "SCD1U10V2KX-5GP"
			(at 1.8923 -1.2065 180)
			(unlocked yes)
			(layer "F.Fab")
			(hide yes)
			(effects
				(font
					(size 1.016 1.016)
					(thickness 0.1524)
				)
			)
		)
		(property "Device Type" "C402H22"
			(at 1.8923 -2.7305 180)
			(unlocked yes)
			(layer "F.Fab")
			(hide yes)
			(effects
				(font
					(size 1.016 1.016)
					(thickness 0.1524)
				)
			)
		)
		(duplicate_pad_numbers_are_jumpers no)
		(fp_rect
			(start -0.381 0.7366)
			(end 0.381 -0.7366)
			(stroke
				(width 0)
				(type default)
			)
			(fill no)
			(layer "F.CrtYd")
		)
		(fp_rect
			(start -0.381 0.7366)
			(end 0.381 -0.7366)
			(stroke
				(width 0)
				(type default)
			)
			(fill no)
			(layer "F.Fab")
		)
		(pad "1" smd custom
			(at 0 -0.4572 180)
			(size 0.1143 0.1143)
			(layers "F.Cu" "F.Mask" "F.Paste")
			(net "P3V3_CPU")
			(options
				(clearance outline)
				(anchor circle)
			)
			(primitives
				(gr_poly
					(pts
						(arc
							(start -0.254 -0.1778)
							(mid -0.239121 -0.213721)
							(end -0.2032 -0.2286)
						)
						(arc
							(start 0.2032 -0.2286)
							(mid 0.239121 -0.213721)
							(end 0.254 -0.1778)
						)
						(arc
							(start 0.254 0.1778)
							(mid 0.239121 0.213721)
							(end 0.2032 0.2286)
						)
						(arc
							(start -0.2032 0.2286)
							(mid -0.239121 0.213721)
							(end -0.254 0.1778)
						)
					)
					(width 0)
					(fill yes)
				)
			)
		)
		(pad "2" smd custom
			(at 0 0.4572 180)
			(size 0.1143 0.1143)
			(layers "F.Cu" "F.Mask" "F.Paste")
			(net "GND")
			(options
				(clearance outline)
				(anchor circle)
			)
			(primitives
				(gr_poly
					(pts
						(arc
							(start -0.254 -0.1778)
							(mid -0.239121 -0.213721)
							(end -0.2032 -0.2286)
						)
						(arc
							(start 0.2032 -0.2286)
							(mid 0.239121 -0.213721)
							(end 0.254 -0.1778)
						)
						(arc
							(start 0.254 0.1778)
							(mid 0.239121 0.213721)
							(end 0.2032 0.2286)
						)
						(arc
							(start -0.2032 0.2286)
							(mid -0.239121 0.213721)
							(end -0.254 0.1778)
						)
					)
					(width 0)
					(fill yes)
				)
			)
		)
	)
	(footprint ""
		(layer "F.Cu")
		(at 74.0664 -47.9552 90)
		(property "Reference" "R66"
			(at 0 0 90)
			(layer "F.SilkS")
			(hide yes)
			(effects
				(font
					(size 1.27 1.27)
				)
			)
		)
		(property "Value" "4K7R2F-GP"
			(at 0.064008 -3.993896 90)
			(unlocked yes)
			(layer "F.Fab")
			(hide yes)
			(effects
				(font
					(size 1.016 1.016)
					(thickness 0.1524)
				)
			)
		)
		(property "Device Type" "R402H16"
			(at 0.064008 -5.517896 90)
			(unlocked yes)
			(layer "F.Fab")
			(hide yes)
			(effects
				(font
					(size 1.016 1.016)
					(thickness 0.1524)
				)
			)
		)
		(duplicate_pad_numbers_are_jumpers no)
		(fp_rect
			(start -0.381 0.8382)
			(end 0.381 -0.8382)
			(stroke
				(width 0)
				(type default)
			)
			(fill no)
			(layer "F.CrtYd")
		)
		(fp_rect
			(start -0.381 0.8382)
			(end 0.381 -0.8382)
			(stroke
				(width 0)
				(type default)
			)
			(fill no)
			(layer "F.Fab")
		)
		(pad "1" smd custom
			(at 0 -0.4318 90)
			(size 0.127 0.127)
			(layers "F.Cu" "F.Mask" "F.Paste")
			(net "P3V3")
			(options
				(clearance outline)
				(anchor circle)
			)
			(primitives
				(gr_poly
					(pts
						(arc
							(start -0.2032 -0.2794)
							(mid -0.239121 -0.264521)
							(end -0.254 -0.2286)
						)
						(arc
							(start -0.254 0.2286)
							(mid -0.239121 0.264521)
							(end -0.2032 0.2794)
						)
						(arc
							(start 0.2032 0.2794)
							(mid 0.239121 0.264521)
							(end 0.254 0.2286)
						)
						(arc
							(start 0.254 -0.2286)
							(mid 0.239121 -0.264521)
							(end 0.2032 -0.2794)
						)
					)
					(width 0)
					(fill yes)
				)
			)
		)
		(pad "2" smd custom
			(at 0 0.4318 90)
			(size 0.127 0.127)
			(layers "F.Cu" "F.Mask" "F.Paste")
			(net "SMB_CLK1_SPKR")
			(options
				(clearance outline)
				(anchor circle)
			)
			(primitives
				(gr_poly
					(pts
						(arc
							(start -0.2032 -0.2794)
							(mid -0.239121 -0.264521)
							(end -0.254 -0.2286)
						)
						(arc
							(start -0.254 0.2286)
							(mid -0.239121 0.264521)
							(end -0.2032 0.2794)
						)
						(arc
							(start 0.2032 0.2794)
							(mid 0.239121 0.264521)
							(end 0.254 0.2286)
						)
						(arc
							(start 0.254 -0.2286)
							(mid 0.239121 -0.264521)
							(end 0.2032 -0.2794)
						)
					)
					(width 0)
					(fill yes)
				)
			)
		)
	)
	(footprint ""
		(layer "F.Cu")
		(at 186.0042 -26.5938 180)
		(property "Reference" "PC109"
			(at 0 0 180)
			(layer "F.SilkS")
			(hide yes)
			(effects
				(font
					(size 1.27 1.27)
				)
			)
		)
		(property "Value" "SCD22U16V3KX-2-GP"
			(at -0.0254 -2.0193 180)
			(unlocked yes)
			(layer "F.Fab")
			(hide yes)
			(effects
				(font
					(size 1.016 1.016)
					(thickness 0.1524)
				)
			)
		)
		(property "Device Type" "C603H36"
			(at -0.0254 -3.5433 180)
			(unlocked yes)
			(layer "F.Fab")
			(hide yes)
			(effects
				(font
					(size 1.016 1.016)
					(thickness 0.1524)
				)
			)
		)
		(duplicate_pad_numbers_are_jumpers no)
		(fp_line
			(start -0.4064 0)
			(end 0.4064 0)
			(stroke
				(width 0.2286)
				(type default)
			)
			(layer "F.SilkS")
		)
		(fp_rect
			(start -0.635 1.1811)
			(end 0.635 -1.1811)
			(stroke
				(width 0)
				(type default)
			)
			(fill no)
			(layer "F.CrtYd")
		)
		(fp_rect
			(start -0.635 1.1811)
			(end 0.635 -1.1811)
			(stroke
				(width 0)
				(type default)
			)
			(fill no)
			(layer "F.Fab")
		)
		(pad "1" smd custom
			(at 0 -0.6604 180)
			(size 0.19685 0.19685)
			(layers "F.Cu" "F.Mask" "F.Paste")
			(net "VR_PVDDRA_ISUMN1")
			(options
				(clearance outline)
				(anchor circle)
			)
			(primitives
				(gr_poly
					(pts
						(arc
							(start 0.508 -0.2921)
							(mid 0.478242 -0.363942)
							(end 0.4064 -0.3937)
						)
						(arc
							(start -0.4064 -0.3937)
							(mid -0.478242 -0.363942)
							(end -0.508 -0.2921)
						)
						(arc
							(start -0.508 0.2921)
							(mid -0.478242 0.363942)
							(end -0.4064 0.3937)
						)
						(arc
							(start 0.4064 0.3937)
							(mid 0.478242 0.363942)
							(end 0.508 0.2921)
						)
					)
					(width 0)
					(fill yes)
				)
			)
		)
		(pad "2" smd custom
			(at 0 0.6604 180)
			(size 0.19685 0.19685)
			(layers "F.Cu" "F.Mask" "F.Paste")
			(net "ISENSE_PVDDR_A_ISEN1")
			(options
				(clearance outline)
				(anchor circle)
			)
			(primitives
				(gr_poly
					(pts
						(arc
							(start 0.508 -0.2921)
							(mid 0.478242 -0.363942)
							(end 0.4064 -0.3937)
						)
						(arc
							(start -0.4064 -0.3937)
							(mid -0.478242 -0.363942)
							(end -0.508 -0.2921)
						)
						(arc
							(start -0.508 0.2921)
							(mid -0.478242 0.363942)
							(end -0.4064 0.3937)
						)
						(arc
							(start 0.4064 0.3937)
							(mid 0.478242 0.363942)
							(end 0.508 0.2921)
						)
					)
					(width 0)
					(fill yes)
				)
			)
		)
	)
	(footprint ""
		(layer "F.Cu")
		(at 42.1386 -53.848 180)
		(property "Reference" "PR32"
			(at 0 0 180)
			(layer "F.SilkS")
			(hide yes)
			(effects
				(font
					(size 1.27 1.27)
				)
			)
		)
		(property "Value" "2D2R5F-2-GP"
			(at 0 -4.9022 180)
			(unlocked yes)
			(layer "F.Fab")
			(hide yes)
			(effects
				(font
					(size 1.016 1.016)
					(thickness 0.1524)
				)
			)
		)
		(property "Device Type" "R805H24"
			(at 0 -6.8072 180)
			(unlocked yes)
			(layer "F.Fab")
			(hide yes)
			(effects
				(font
					(size 1.016 1.016)
					(thickness 0.1524)
				)
			)
		)
		(duplicate_pad_numbers_are_jumpers no)
		(fp_line
			(start 0.6096 0)
			(end 0.2794 0)
			(stroke
				(width 0.3048)
				(type default)
			)
			(layer "F.SilkS")
		)
		(fp_line
			(start -0.2794 0)
			(end -0.6096 0)
			(stroke
				(width 0.3048)
				(type default)
			)
			(layer "F.SilkS")
		)
		(fp_poly
			(pts
				(xy -0.9017 1.4351) (xy 0.9017 1.4351) (xy 0.9017 -1.4351) (xy -0.9017 -1.4351)
			)
			(stroke
				(width 0)
				(type default)
			)
			(fill no)
			(layer "F.CrtYd")
		)
		(fp_poly
			(pts
				(xy 0.9017 1.4351) (xy 0.9017 -1.4351) (xy -0.9017 -1.4351) (xy -0.9017 1.4351)
			)
			(stroke
				(width 0)
				(type default)
			)
			(fill no)
			(layer "F.Fab")
		)
		(pad "1" smd rect
			(at 0 -0.8382 180)
			(size 1.5494 0.9398)
			(layers "F.Cu" "F.Mask" "F.Paste")
			(net "VR_PVCCP_VSW_R")
		)
		(pad "2" smd rect
			(at 0 0.8382 180)
			(size 1.5494 0.9398)
			(layers "F.Cu" "F.Mask" "F.Paste")
			(net "GND")
		)
	)
	(footprint ""
		(layer "F.Cu")
		(at 147.828 -18.796)
		(property "Reference" "TP8"
			(at 0 0 0)
			(layer "F.SilkS")
			(hide yes)
			(effects
				(font
					(size 1.27 1.27)
				)
			)
		)
		(property "Value" "TPAD28-1-GP-U"
			(at 0.0508 -1.9304 0)
			(unlocked yes)
			(layer "F.Fab")
			(hide yes)
			(effects
				(font
					(size 1.016 1.016)
					(thickness 0.1524)
				)
			)
		)
		(property "Device Type" "TPAD28-1-U"
			(at 0.0508 -3.4544 0)
			(unlocked yes)
			(layer "F.Fab")
			(hide yes)
			(effects
				(font
					(size 1.016 1.016)
					(thickness 0.1524)
				)
			)
		)
		(duplicate_pad_numbers_are_jumpers no)
		(fp_poly
			(pts
				(arc
					(start 0.3556 0)
					(mid -0.3556 0)
					(end 0.3556 0)
				)
			)
			(stroke
				(width 0)
				(type default)
			)
			(fill no)
			(layer "F.CrtYd")
		)
		(fp_poly
			(pts
				(arc
					(start 0.9525 0)
					(mid -0.9525 0)
					(end 0.9525 0)
				)
			)
			(stroke
				(width 0)
				(type default)
			)
			(fill no)
			(layer "F.Fab")
		)
		(pad "1" smd circle
			(at 0 0)
			(size 0.7112 0.7112)
			(layers "F.Cu" "F.Mask" "F.Paste")
			(net "C_CEO#")
		)
	)
	(footprint ""
		(layer "F.Cu")
		(at 44.831 -27.8384 -90)
		(property "Reference" "R248"
			(at 0 0 270)
			(layer "F.SilkS")
			(hide yes)
			(effects
				(font
					(size 1.27 1.27)
				)
			)
		)
		(property "Value" "1KR2F-3-GP"
			(at 0.064008 -3.993896 270)
			(unlocked yes)
			(layer "F.Fab")
			(hide yes)
			(effects
				(font
					(size 1.016 1.016)
					(thickness 0.1524)
				)
			)
		)
		(property "Device Type" "R402H16"
			(at 0.064008 -5.517896 270)
			(unlocked yes)
			(layer "F.Fab")
			(hide yes)
			(effects
				(font
					(size 1.016 1.016)
					(thickness 0.1524)
				)
			)
		)
		(duplicate_pad_numbers_are_jumpers no)
		(fp_rect
			(start -0.381 0.8382)
			(end 0.381 -0.8382)
			(stroke
				(width 0)
				(type default)
			)
			(fill no)
			(layer "F.CrtYd")
		)
		(fp_rect
			(start -0.381 0.8382)
			(end 0.381 -0.8382)
			(stroke
				(width 0)
				(type default)
			)
			(fill no)
			(layer "F.Fab")
		)
		(pad "1" smd custom
			(at 0 -0.4318 270)
			(size 0.127 0.127)
			(layers "F.Cu" "F.Mask" "F.Paste")
			(net "CPU_RSMRST#")
			(options
				(clearance outline)
				(anchor circle)
			)
			(primitives
				(gr_poly
					(pts
						(arc
							(start -0.2032 -0.2794)
							(mid -0.239121 -0.264521)
							(end -0.254 -0.2286)
						)
						(arc
							(start -0.254 0.2286)
							(mid -0.239121 0.264521)
							(end -0.2032 0.2794)
						)
						(arc
							(start 0.2032 0.2794)
							(mid 0.239121 0.264521)
							(end 0.254 0.2286)
						)
						(arc
							(start 0.254 -0.2286)
							(mid 0.239121 -0.264521)
							(end 0.2032 -0.2794)
						)
					)
					(width 0)
					(fill yes)
				)
			)
		)
		(pad "2" smd custom
			(at 0 0.4318 270)
			(size 0.127 0.127)
			(layers "F.Cu" "F.Mask" "F.Paste")
			(net "XDP_RSMRST_R#")
			(options
				(clearance outline)
				(anchor circle)
			)
			(primitives
				(gr_poly
					(pts
						(arc
							(start -0.2032 -0.2794)
							(mid -0.239121 -0.264521)
							(end -0.254 -0.2286)
						)
						(arc
							(start -0.254 0.2286)
							(mid -0.239121 0.264521)
							(end -0.2032 0.2794)
						)
						(arc
							(start 0.2032 0.2794)
							(mid 0.239121 0.264521)
							(end 0.254 0.2286)
						)
						(arc
							(start 0.254 -0.2286)
							(mid 0.239121 -0.264521)
							(end 0.2032 -0.2794)
						)
					)
					(width 0)
					(fill yes)
				)
			)
		)
	)
	(footprint ""
		(layer "F.Cu")
		(at 54.737 -54.356)
		(property "Reference" "PR147"
			(at 0 0 0)
			(layer "F.SilkS")
			(hide yes)
			(effects
				(font
					(size 1.27 1.27)
				)
			)
		)
		(property "Value" "348KR2F-GP"
			(at 1.7907 -1.1176 0)
			(unlocked yes)
			(layer "F.Fab")
			(hide yes)
			(effects
				(font
					(size 1.016 1.016)
					(thickness 0.1524)
				)
			)
		)
		(property "Device Type" "R402H16"
			(at 1.7907 -2.6416 0)
			(unlocked yes)
			(layer "F.Fab")
			(hide yes)
			(effects
				(font
					(size 1.016 1.016)
					(thickness 0.1524)
				)
			)
		)
		(duplicate_pad_numbers_are_jumpers no)
		(fp_rect
			(start -0.381 0.8382)
			(end 0.381 -0.8382)
			(stroke
				(width 0)
				(type default)
			)
			(fill no)
			(layer "F.CrtYd")
		)
		(fp_rect
			(start -0.381 0.8382)
			(end 0.381 -0.8382)
			(stroke
				(width 0)
				(type default)
			)
			(fill no)
			(layer "F.Fab")
		)
		(pad "1" smd custom
			(at 0 -0.4318)
			(size 0.127 0.127)
			(layers "F.Cu" "F.Mask" "F.Paste")
			(net "VR_FB_P1V0_STBY")
			(options
				(clearance outline)
				(anchor circle)
			)
			(primitives
				(gr_poly
					(pts
						(arc
							(start -0.2032 -0.2794)
							(mid -0.239121 -0.264521)
							(end -0.254 -0.2286)
						)
						(arc
							(start -0.254 0.2286)
							(mid -0.239121 0.264521)
							(end -0.2032 0.2794)
						)
						(arc
							(start 0.2032 0.2794)
							(mid 0.239121 0.264521)
							(end 0.254 0.2286)
						)
						(arc
							(start 0.254 -0.2286)
							(mid 0.239121 -0.264521)
							(end 0.2032 -0.2794)
						)
					)
					(width 0)
					(fill yes)
				)
			)
		)
		(pad "2" smd custom
			(at 0 0.4318)
			(size 0.127 0.127)
			(layers "F.Cu" "F.Mask" "F.Paste")
			(net "AGND_P1V0_STBY")
			(options
				(clearance outline)
				(anchor circle)
			)
			(primitives
				(gr_poly
					(pts
						(arc
							(start -0.2032 -0.2794)
							(mid -0.239121 -0.264521)
							(end -0.254 -0.2286)
						)
						(arc
							(start -0.254 0.2286)
							(mid -0.239121 0.264521)
							(end -0.2032 0.2794)
						)
						(arc
							(start 0.2032 0.2794)
							(mid 0.239121 0.264521)
							(end 0.254 0.2286)
						)
						(arc
							(start 0.254 -0.2286)
							(mid 0.239121 -0.264521)
							(end 0.2032 -0.2794)
						)
					)
					(width 0)
					(fill yes)
				)
			)
		)
	)
	(footprint ""
		(layer "F.Cu")
		(at 11.3792 -54.0258 90)
		(property "Reference" "C56"
			(at 0 0 90)
			(layer "F.SilkS")
			(hide yes)
			(effects
				(font
					(size 1.27 1.27)
				)
			)
		)
		(property "Value" "SCD01U16V2KX-3GP"
			(at 1.1811 -2.7051 90)
			(unlocked yes)
			(layer "F.Fab")
			(hide yes)
			(effects
				(font
					(size 1.016 1.016)
					(thickness 0.1524)
				)
			)
		)
		(property "Device Type" "C402H22"
			(at 1.1811 -4.2291 90)
			(unlocked yes)
			(layer "F.Fab")
			(hide yes)
			(effects
				(font
					(size 1.016 1.016)
					(thickness 0.1524)
				)
			)
		)
		(duplicate_pad_numbers_are_jumpers no)
		(fp_rect
			(start -0.381 0.7366)
			(end 0.381 -0.7366)
			(stroke
				(width 0)
				(type default)
			)
			(fill no)
			(layer "F.CrtYd")
		)
		(fp_rect
			(start -0.381 0.7366)
			(end 0.381 -0.7366)
			(stroke
				(width 0)
				(type default)
			)
			(fill no)
			(layer "F.Fab")
		)
		(pad "1" smd custom
			(at 0 -0.4572 90)
			(size 0.1143 0.1143)
			(layers "F.Cu" "F.Mask" "F.Paste")
			(net "SATA3_RX_DP1")
			(options
				(clearance outline)
				(anchor circle)
			)
			(primitives
				(gr_poly
					(pts
						(arc
							(start -0.254 -0.1778)
							(mid -0.239121 -0.213721)
							(end -0.2032 -0.2286)
						)
						(arc
							(start 0.2032 -0.2286)
							(mid 0.239121 -0.213721)
							(end 0.254 -0.1778)
						)
						(arc
							(start 0.254 0.1778)
							(mid 0.239121 0.213721)
							(end 0.2032 0.2286)
						)
						(arc
							(start -0.2032 0.2286)
							(mid -0.239121 0.213721)
							(end -0.254 0.1778)
						)
					)
					(width 0)
					(fill yes)
				)
			)
		)
		(pad "2" smd custom
			(at 0 0.4572 90)
			(size 0.1143 0.1143)
			(layers "F.Cu" "F.Mask" "F.Paste")
			(net "P2E_CPU_NGFF_C_RX_DN12")
			(options
				(clearance outline)
				(anchor circle)
			)
			(primitives
				(gr_poly
					(pts
						(arc
							(start -0.254 -0.1778)
							(mid -0.239121 -0.213721)
							(end -0.2032 -0.2286)
						)
						(arc
							(start 0.2032 -0.2286)
							(mid 0.239121 -0.213721)
							(end 0.254 -0.1778)
						)
						(arc
							(start 0.254 0.1778)
							(mid 0.239121 0.213721)
							(end 0.2032 0.2286)
						)
						(arc
							(start -0.2032 0.2286)
							(mid -0.239121 0.213721)
							(end -0.254 0.1778)
						)
					)
					(width 0)
					(fill yes)
				)
			)
		)
	)
	(footprint ""
		(layer "F.Cu")
		(at 203.073 -54.0512 90)
		(property "Reference" "PC180"
			(at 0 0 90)
			(layer "F.SilkS")
			(hide yes)
			(effects
				(font
					(size 1.27 1.27)
				)
			)
		)
		(property "Value" "SC100U6D3V0MX-2GP"
			(at -2.3368 -3.5052 90)
			(unlocked yes)
			(layer "F.Fab")
			(hide yes)
			(effects
				(font
					(size 1.016 1.016)
					(thickness 0.1524)
				)
			)
		)
		(property "Device Type" "C1210H107"
			(at -2.3368 -5.0292 90)
			(unlocked yes)
			(layer "F.Fab")
			(hide yes)
			(effects
				(font
					(size 1.016 1.016)
					(thickness 0.1524)
				)
			)
		)
		(duplicate_pad_numbers_are_jumpers no)
		(fp_rect
			(start -1.4986 1.9685)
			(end 1.4986 -1.9685)
			(stroke
				(width 0)
				(type default)
			)
			(fill no)
			(layer "F.CrtYd")
		)
		(fp_rect
			(start -1.4986 1.9685)
			(end 1.4986 -1.9685)
			(stroke
				(width 0)
				(type default)
			)
			(fill no)
			(layer "F.Fab")
		)
		(pad "1" smd rect
			(at 0 -1.2446 90)
			(size 2.7432 1.1938)
			(layers "F.Cu" "F.Mask" "F.Paste")
			(net "PV_VDDR")
		)
		(pad "2" smd rect
			(at 0 1.2446 90)
			(size 2.7432 1.1938)
			(layers "F.Cu" "F.Mask" "F.Paste")
			(net "GND")
		)
	)
	(footprint ""
		(layer "F.Cu")
		(at 157.226 -32.639 90)
		(property "Reference" "R142"
			(at 0 0 90)
			(layer "F.SilkS")
			(hide yes)
			(effects
				(font
					(size 1.27 1.27)
				)
			)
		)
		(property "Value" "0R2J-2-GP"
			(at 0.064008 -3.993896 90)
			(unlocked yes)
			(layer "F.Fab")
			(hide yes)
			(effects
				(font
					(size 1.016 1.016)
					(thickness 0.1524)
				)
			)
		)
		(property "Device Type" "R402H16"
			(at 0.064008 -5.517896 90)
			(unlocked yes)
			(layer "F.Fab")
			(hide yes)
			(effects
				(font
					(size 1.016 1.016)
					(thickness 0.1524)
				)
			)
		)
		(duplicate_pad_numbers_are_jumpers no)
		(fp_rect
			(start -0.381 0.8382)
			(end 0.381 -0.8382)
			(stroke
				(width 0)
				(type default)
			)
			(fill no)
			(layer "F.CrtYd")
		)
		(fp_rect
			(start -0.381 0.8382)
			(end 0.381 -0.8382)
			(stroke
				(width 0)
				(type default)
			)
			(fill no)
			(layer "F.Fab")
		)
		(pad "1" smd custom
			(at 0 -0.4318 90)
			(size 0.127 0.127)
			(layers "F.Cu" "F.Mask" "F.Paste")
			(net "READY_R#")
			(options
				(clearance outline)
				(anchor circle)
			)
			(primitives
				(gr_poly
					(pts
						(arc
							(start -0.2032 -0.2794)
							(mid -0.239121 -0.264521)
							(end -0.254 -0.2286)
						)
						(arc
							(start -0.254 0.2286)
							(mid -0.239121 0.264521)
							(end -0.2032 0.2794)
						)
						(arc
							(start 0.2032 0.2794)
							(mid 0.239121 0.264521)
							(end 0.254 0.2286)
						)
						(arc
							(start 0.254 -0.2286)
							(mid 0.239121 -0.264521)
							(end 0.2032 -0.2794)
						)
					)
					(width 0)
					(fill yes)
				)
			)
		)
		(pad "2" smd custom
			(at 0 0.4318 90)
			(size 0.127 0.127)
			(layers "F.Cu" "F.Mask" "F.Paste")
			(net "FPGA_READY#")
			(options
				(clearance outline)
				(anchor circle)
			)
			(primitives
				(gr_poly
					(pts
						(arc
							(start -0.2032 -0.2794)
							(mid -0.239121 -0.264521)
							(end -0.254 -0.2286)
						)
						(arc
							(start -0.254 0.2286)
							(mid -0.239121 0.264521)
							(end -0.2032 0.2794)
						)
						(arc
							(start 0.2032 0.2794)
							(mid 0.239121 0.264521)
							(end 0.254 0.2286)
						)
						(arc
							(start 0.254 -0.2286)
							(mid 0.239121 -0.264521)
							(end 0.2032 -0.2794)
						)
					)
					(width 0)
					(fill yes)
				)
			)
		)
	)
	(footprint ""
		(layer "F.Cu")
		(at 49.4284 -22.987 180)
		(property "Reference" "R440"
			(at 0 0 180)
			(layer "F.SilkS")
			(hide yes)
			(effects
				(font
					(size 1.27 1.27)
				)
			)
		)
		(property "Value" "4K7R2F-GP"
			(at 1.7907 -1.1176 180)
			(unlocked yes)
			(layer "F.Fab")
			(hide yes)
			(effects
				(font
					(size 1.016 1.016)
					(thickness 0.1524)
				)
			)
		)
		(property "Device Type" "R402H16"
			(at 1.7907 -2.6416 180)
			(unlocked yes)
			(layer "F.Fab")
			(hide yes)
			(effects
				(font
					(size 1.016 1.016)
					(thickness 0.1524)
				)
			)
		)
		(duplicate_pad_numbers_are_jumpers no)
		(fp_rect
			(start -0.381 0.8382)
			(end 0.381 -0.8382)
			(stroke
				(width 0)
				(type default)
			)
			(fill no)
			(layer "F.CrtYd")
		)
		(fp_rect
			(start -0.381 0.8382)
			(end 0.381 -0.8382)
			(stroke
				(width 0)
				(type default)
			)
			(fill no)
			(layer "F.Fab")
		)
		(pad "1" smd custom
			(at 0 -0.4318 180)
			(size 0.127 0.127)
			(layers "F.Cu" "F.Mask" "F.Paste")
			(net "P3V3")
			(options
				(clearance outline)
				(anchor circle)
			)
			(primitives
				(gr_poly
					(pts
						(arc
							(start -0.2032 -0.2794)
							(mid -0.239121 -0.264521)
							(end -0.254 -0.2286)
						)
						(arc
							(start -0.254 0.2286)
							(mid -0.239121 0.264521)
							(end -0.2032 0.2794)
						)
						(arc
							(start 0.2032 0.2794)
							(mid 0.239121 0.264521)
							(end 0.254 0.2286)
						)
						(arc
							(start 0.254 -0.2286)
							(mid 0.239121 -0.264521)
							(end 0.2032 -0.2794)
						)
					)
					(width 0)
					(fill yes)
				)
			)
		)
		(pad "2" smd custom
			(at 0 0.4318 180)
			(size 0.127 0.127)
			(layers "F.Cu" "F.Mask" "F.Paste")
			(net "CLKBUFF_OE4#")
			(options
				(clearance outline)
				(anchor circle)
			)
			(primitives
				(gr_poly
					(pts
						(arc
							(start -0.2032 -0.2794)
							(mid -0.239121 -0.264521)
							(end -0.254 -0.2286)
						)
						(arc
							(start -0.254 0.2286)
							(mid -0.239121 0.264521)
							(end -0.2032 0.2794)
						)
						(arc
							(start 0.2032 0.2794)
							(mid 0.239121 0.264521)
							(end 0.254 0.2286)
						)
						(arc
							(start 0.254 -0.2286)
							(mid 0.239121 -0.264521)
							(end 0.2032 -0.2794)
						)
					)
					(width 0)
					(fill yes)
				)
			)
		)
	)
	(footprint ""
		(layer "F.Cu")
		(at 109.601 -64.643 -90)
		(property "Reference" "U4"
			(at 0 0 270)
			(layer "F.SilkS")
			(hide yes)
			(effects
				(font
					(size 1.27 1.27)
				)
			)
		)
		(property "Value" "SN74LVC1G07DCKRG4-2-GP"
			(at -2.3368 -8.6868 270)
			(unlocked yes)
			(layer "F.Fab")
			(hide yes)
			(effects
				(font
					(size 1.016 1.016)
					(thickness 0.1524)
				)
			)
		)
		(property "Device Type" "SC70-5H44"
			(at -2.3114 -10.414 270)
			(unlocked yes)
			(layer "F.Fab")
			(hide yes)
			(effects
				(font
					(size 1.016 1.016)
					(thickness 0.1524)
				)
			)
		)
		(duplicate_pad_numbers_are_jumpers no)
		(fp_line
			(start -1.0033 0.3302)
			(end -1.0033 -0.3302)
			(stroke
				(width 0.1524)
				(type default)
			)
			(layer "F.SilkS")
		)
		(fp_line
			(start 1.0033 0.3302)
			(end -1.0033 0.3302)
			(stroke
				(width 0.1524)
				(type default)
			)
			(layer "F.SilkS")
		)
		(fp_line
			(start -1.0033 -0.3302)
			(end 1.0033 -0.3302)
			(stroke
				(width 0.1524)
				(type default)
			)
			(layer "F.SilkS")
		)
		(fp_line
			(start 1.0033 -0.3302)
			(end 1.0033 0.3302)
			(stroke
				(width 0.1524)
				(type default)
			)
			(layer "F.SilkS")
		)
		(fp_poly
			(pts
				(xy -1.0033 1.4859) (xy -1.0033 0.8001) (xy -1.1811 0.8001) (xy -1.1811 -0.8001) (xy -1.0033 -0.8001)
				(xy -1.0033 -1.4859) (xy 1.0033 -1.4859) (xy 1.0033 -0.8001) (xy 1.1811 -0.8001) (xy 1.1811 0.8001)
				(xy 1.0033 0.8001) (xy 1.0033 1.4859) (xy 0.2921 1.4859) (xy 0.2921 0.8001) (xy -0.2921 0.8001)
				(xy -0.2921 1.4859)
			)
			(stroke
				(width 0)
				(type default)
			)
			(fill no)
			(layer "F.CrtYd")
		)
		(fp_poly
			(pts
				(xy -1.0033 1.4859) (xy -1.0033 0.8001) (xy -1.1811 0.8001) (xy -1.1811 -0.8001) (xy -1.0033 -0.8001)
				(xy -1.0033 -1.4859) (xy 1.0033 -1.4859) (xy 1.0033 -0.8001) (xy 1.1811 -0.8001) (xy 1.1811 0.8001)
				(xy 1.0033 0.8001) (xy 1.0033 1.4859) (xy 0.2921 1.4859) (xy 0.2921 0.8001) (xy -0.2921 0.8001)
				(xy -0.2921 1.4859)
			)
			(stroke
				(width 0)
				(type default)
			)
			(fill no)
			(layer "F.Fab")
		)
		(pad "1" smd rect
			(at 0.65024 -0.93472 270)
			(size 0.3556 0.762)
			(layers "F.Cu" "F.Mask" "F.Paste")
			(net "Net_445")
		)
		(pad "2" smd rect
			(at 0 -0.93472 270)
			(size 0.3556 0.762)
			(layers "F.Cu" "F.Mask" "F.Paste")
			(net "DDR3_DRAM_PWROK")
		)
		(pad "3" smd rect
			(at -0.65024 -0.93472 270)
			(size 0.3556 0.762)
			(layers "F.Cu" "F.Mask" "F.Paste")
			(net "GND")
		)
		(pad "4" smd rect
			(at -0.65024 0.93472 270)
			(size 0.3556 0.762)
			(layers "F.Cu" "F.Mask" "F.Paste")
			(net "M_DRAM_PWROK")
		)
		(pad "5" smd rect
			(at 0.65024 0.93472 270)
			(size 0.3556 0.762)
			(layers "F.Cu" "F.Mask" "F.Paste")
			(net "P3V3_STBY")
		)
	)
	(footprint ""
		(layer "F.Cu")
		(at 57.277 -48.514 90)
		(property "Reference" "PC100"
			(at 0 0 90)
			(layer "F.SilkS")
			(hide yes)
			(effects
				(font
					(size 1.27 1.27)
				)
			)
		)
		(property "Value" "SC22U6D3V5MX-2GP"
			(at 0 -4.9022 90)
			(unlocked yes)
			(layer "F.Fab")
			(hide yes)
			(effects
				(font
					(size 1.016 1.016)
					(thickness 0.1524)
				)
			)
		)
		(property "Device Type" "C805H58"
			(at 0 -6.8072 90)
			(unlocked yes)
			(layer "F.Fab")
			(hide yes)
			(effects
				(font
					(size 1.016 1.016)
					(thickness 0.1524)
				)
			)
		)
		(duplicate_pad_numbers_are_jumpers no)
		(fp_line
			(start 0.6096 0)
			(end -0.6096 0)
			(stroke
				(width 0.3048)
				(type default)
			)
			(layer "F.SilkS")
		)
		(fp_poly
			(pts
				(xy -0.9017 1.4351) (xy 0.9017 1.4351) (xy 0.9017 -1.4351) (xy -0.9017 -1.4351)
			)
			(stroke
				(width 0)
				(type default)
			)
			(fill no)
			(layer "F.CrtYd")
		)
		(fp_poly
			(pts
				(xy 0.9017 1.4351) (xy 0.9017 -1.4351) (xy -0.9017 -1.4351) (xy -0.9017 1.4351)
			)
			(stroke
				(width 0)
				(type default)
			)
			(fill no)
			(layer "F.Fab")
		)
		(pad "1" smd rect
			(at 0 -0.8382 90)
			(size 1.5494 0.9398)
			(layers "F.Cu" "F.Mask" "F.Paste")
			(net "VR_PVIN_P1V0_STBY")
		)
		(pad "2" smd rect
			(at 0 0.8382 90)
			(size 1.5494 0.9398)
			(layers "F.Cu" "F.Mask" "F.Paste")
			(net "GND")
		)
	)
	(footprint ""
		(layer "F.Cu")
		(at 15.8496 -57.6072 -90)
		(property "Reference" "PR62"
			(at 0 0 270)
			(layer "F.SilkS")
			(hide yes)
			(effects
				(font
					(size 1.27 1.27)
				)
			)
		)
		(property "Value" "0R2J-2-GP"
			(at 1.7907 -1.1176 270)
			(unlocked yes)
			(layer "F.Fab")
			(hide yes)
			(effects
				(font
					(size 1.016 1.016)
					(thickness 0.1524)
				)
			)
		)
		(property "Device Type" "R402H16"
			(at 1.7907 -2.6416 270)
			(unlocked yes)
			(layer "F.Fab")
			(hide yes)
			(effects
				(font
					(size 1.016 1.016)
					(thickness 0.1524)
				)
			)
		)
		(duplicate_pad_numbers_are_jumpers no)
		(fp_rect
			(start -0.381 0.8382)
			(end 0.381 -0.8382)
			(stroke
				(width 0)
				(type default)
			)
			(fill no)
			(layer "F.CrtYd")
		)
		(fp_rect
			(start -0.381 0.8382)
			(end 0.381 -0.8382)
			(stroke
				(width 0)
				(type default)
			)
			(fill no)
			(layer "F.Fab")
		)
		(pad "1" smd custom
			(at 0 -0.4318 270)
			(size 0.127 0.127)
			(layers "F.Cu" "F.Mask" "F.Paste")
			(net "PVCC_PVNN_EN_R")
			(options
				(clearance outline)
				(anchor circle)
			)
			(primitives
				(gr_poly
					(pts
						(arc
							(start -0.2032 -0.2794)
							(mid -0.239121 -0.264521)
							(end -0.254 -0.2286)
						)
						(arc
							(start -0.254 0.2286)
							(mid -0.239121 0.264521)
							(end -0.2032 0.2794)
						)
						(arc
							(start 0.2032 0.2794)
							(mid 0.239121 0.264521)
							(end 0.254 0.2286)
						)
						(arc
							(start 0.254 -0.2286)
							(mid 0.239121 -0.264521)
							(end 0.2032 -0.2794)
						)
					)
					(width 0)
					(fill yes)
				)
			)
		)
		(pad "2" smd custom
			(at 0 0.4318 270)
			(size 0.127 0.127)
			(layers "F.Cu" "F.Mask" "F.Paste")
			(net "PWRGD_PVTT_PG")
			(options
				(clearance outline)
				(anchor circle)
			)
			(primitives
				(gr_poly
					(pts
						(arc
							(start -0.2032 -0.2794)
							(mid -0.239121 -0.264521)
							(end -0.254 -0.2286)
						)
						(arc
							(start -0.254 0.2286)
							(mid -0.239121 0.264521)
							(end -0.2032 0.2794)
						)
						(arc
							(start 0.2032 0.2794)
							(mid 0.239121 0.264521)
							(end 0.254 0.2286)
						)
						(arc
							(start 0.254 -0.2286)
							(mid 0.239121 -0.264521)
							(end 0.2032 -0.2794)
						)
					)
					(width 0)
					(fill yes)
				)
			)
		)
	)
	(footprint ""
		(layer "F.Cu")
		(at 159.7406 -44.8818 180)
		(property "Reference" "R215"
			(at 0 0 180)
			(layer "F.SilkS")
			(hide yes)
			(effects
				(font
					(size 1.27 1.27)
				)
			)
		)
		(property "Value" "0R2J-2-GP"
			(at 1.7907 -1.1176 180)
			(unlocked yes)
			(layer "F.Fab")
			(hide yes)
			(effects
				(font
					(size 1.016 1.016)
					(thickness 0.1524)
				)
			)
		)
		(property "Device Type" "R402H16"
			(at 1.7907 -2.6416 180)
			(unlocked yes)
			(layer "F.Fab")
			(hide yes)
			(effects
				(font
					(size 1.016 1.016)
					(thickness 0.1524)
				)
			)
		)
		(duplicate_pad_numbers_are_jumpers no)
		(fp_rect
			(start -0.381 0.8382)
			(end 0.381 -0.8382)
			(stroke
				(width 0)
				(type default)
			)
			(fill no)
			(layer "F.CrtYd")
		)
		(fp_rect
			(start -0.381 0.8382)
			(end 0.381 -0.8382)
			(stroke
				(width 0)
				(type default)
			)
			(fill no)
			(layer "F.Fab")
		)
		(pad "1" smd custom
			(at 0 -0.4318 180)
			(size 0.127 0.127)
			(layers "F.Cu" "F.Mask" "F.Paste")
			(net "JTAG_PLD_TCK")
			(options
				(clearance outline)
				(anchor circle)
			)
			(primitives
				(gr_poly
					(pts
						(arc
							(start -0.2032 -0.2794)
							(mid -0.239121 -0.264521)
							(end -0.254 -0.2286)
						)
						(arc
							(start -0.254 0.2286)
							(mid -0.239121 0.264521)
							(end -0.2032 0.2794)
						)
						(arc
							(start 0.2032 0.2794)
							(mid 0.239121 0.264521)
							(end 0.254 0.2286)
						)
						(arc
							(start 0.254 -0.2286)
							(mid 0.239121 -0.264521)
							(end 0.2032 -0.2794)
						)
					)
					(width 0)
					(fill yes)
				)
			)
		)
		(pad "2" smd custom
			(at 0 0.4318 180)
			(size 0.127 0.127)
			(layers "F.Cu" "F.Mask" "F.Paste")
			(net "JTAG_PLD_TCK_D")
			(options
				(clearance outline)
				(anchor circle)
			)
			(primitives
				(gr_poly
					(pts
						(arc
							(start -0.2032 -0.2794)
							(mid -0.239121 -0.264521)
							(end -0.254 -0.2286)
						)
						(arc
							(start -0.254 0.2286)
							(mid -0.239121 0.264521)
							(end -0.2032 0.2794)
						)
						(arc
							(start 0.2032 0.2794)
							(mid 0.239121 0.264521)
							(end 0.254 0.2286)
						)
						(arc
							(start 0.254 -0.2286)
							(mid 0.239121 -0.264521)
							(end 0.2032 -0.2794)
						)
					)
					(width 0)
					(fill yes)
				)
			)
		)
	)
	(footprint ""
		(layer "F.Cu")
		(at 74.041 -32.893 -90)
		(property "Reference" "R111"
			(at 0 0 270)
			(layer "F.SilkS")
			(hide yes)
			(effects
				(font
					(size 1.27 1.27)
				)
			)
		)
		(property "Value" "1KR2F-3-GP"
			(at 0.064008 -3.993896 270)
			(unlocked yes)
			(layer "F.Fab")
			(hide yes)
			(effects
				(font
					(size 1.016 1.016)
					(thickness 0.1524)
				)
			)
		)
		(property "Device Type" "R402H16"
			(at 0.064008 -5.517896 270)
			(unlocked yes)
			(layer "F.Fab")
			(hide yes)
			(effects
				(font
					(size 1.016 1.016)
					(thickness 0.1524)
				)
			)
		)
		(duplicate_pad_numbers_are_jumpers no)
		(fp_rect
			(start -0.381 0.8382)
			(end 0.381 -0.8382)
			(stroke
				(width 0)
				(type default)
			)
			(fill no)
			(layer "F.CrtYd")
		)
		(fp_rect
			(start -0.381 0.8382)
			(end 0.381 -0.8382)
			(stroke
				(width 0)
				(type default)
			)
			(fill no)
			(layer "F.Fab")
		)
		(pad "1" smd custom
			(at 0 -0.4318 270)
			(size 0.127 0.127)
			(layers "F.Cu" "F.Mask" "F.Paste")
			(net "SPI_CPU_CS0#")
			(options
				(clearance outline)
				(anchor circle)
			)
			(primitives
				(gr_poly
					(pts
						(arc
							(start -0.2032 -0.2794)
							(mid -0.239121 -0.264521)
							(end -0.254 -0.2286)
						)
						(arc
							(start -0.254 0.2286)
							(mid -0.239121 0.264521)
							(end -0.2032 0.2794)
						)
						(arc
							(start 0.2032 0.2794)
							(mid 0.239121 0.264521)
							(end 0.254 0.2286)
						)
						(arc
							(start 0.254 -0.2286)
							(mid 0.239121 -0.264521)
							(end 0.2032 -0.2794)
						)
					)
					(width 0)
					(fill yes)
				)
			)
		)
		(pad "2" smd custom
			(at 0 0.4318 270)
			(size 0.127 0.127)
			(layers "F.Cu" "F.Mask" "F.Paste")
			(net "GND")
			(options
				(clearance outline)
				(anchor circle)
			)
			(primitives
				(gr_poly
					(pts
						(arc
							(start -0.2032 -0.2794)
							(mid -0.239121 -0.264521)
							(end -0.254 -0.2286)
						)
						(arc
							(start -0.254 0.2286)
							(mid -0.239121 0.264521)
							(end -0.2032 0.2794)
						)
						(arc
							(start 0.2032 0.2794)
							(mid 0.239121 0.264521)
							(end 0.254 0.2286)
						)
						(arc
							(start 0.254 -0.2286)
							(mid 0.239121 -0.264521)
							(end 0.2032 -0.2794)
						)
					)
					(width 0)
					(fill yes)
				)
			)
		)
	)
	(footprint ""
		(layer "F.Cu")
		(at 46.863 -65.151)
		(property "Reference" "PC27"
			(at 0 0 0)
			(layer "F.SilkS")
			(hide yes)
			(effects
				(font
					(size 1.27 1.27)
				)
			)
		)
		(property "Value" "SC47U6D3V5MX-1-GP"
			(at 0 -4.9022 0)
			(unlocked yes)
			(layer "F.Fab")
			(hide yes)
			(effects
				(font
					(size 1.016 1.016)
					(thickness 0.1524)
				)
			)
		)
		(property "Device Type" "C805H54"
			(at 0 -6.8072 0)
			(unlocked yes)
			(layer "F.Fab")
			(hide yes)
			(effects
				(font
					(size 1.016 1.016)
					(thickness 0.1524)
				)
			)
		)
		(duplicate_pad_numbers_are_jumpers no)
		(fp_line
			(start 0.6096 0)
			(end -0.6096 0)
			(stroke
				(width 0.3048)
				(type default)
			)
			(layer "F.SilkS")
		)
		(fp_poly
			(pts
				(xy -0.9017 1.4351) (xy 0.9017 1.4351) (xy 0.9017 -1.4351) (xy -0.9017 -1.4351)
			)
			(stroke
				(width 0)
				(type default)
			)
			(fill no)
			(layer "F.CrtYd")
		)
		(fp_poly
			(pts
				(xy 0.9017 1.4351) (xy 0.9017 -1.4351) (xy -0.9017 -1.4351) (xy -0.9017 1.4351)
			)
			(stroke
				(width 0)
				(type default)
			)
			(fill no)
			(layer "F.Fab")
		)
		(pad "1" smd rect
			(at 0 -0.8382)
			(size 1.5494 0.9398)
			(layers "F.Cu" "F.Mask" "F.Paste")
			(net "PVNN")
		)
		(pad "2" smd rect
			(at 0 0.8382)
			(size 1.5494 0.9398)
			(layers "F.Cu" "F.Mask" "F.Paste")
			(net "GND")
		)
	)
	(footprint ""
		(layer "F.Cu")
		(at 136.271 -18.796)
		(property "Reference" "R58"
			(at 0 0 0)
			(layer "F.SilkS")
			(hide yes)
			(effects
				(font
					(size 1.27 1.27)
				)
			)
		)
		(property "Value" "0R2J-2-GP"
			(at 0.064008 -3.993896 0)
			(unlocked yes)
			(layer "F.Fab")
			(hide yes)
			(effects
				(font
					(size 1.016 1.016)
					(thickness 0.1524)
				)
			)
		)
		(property "Device Type" "R402H16"
			(at 0.064008 -5.517896 0)
			(unlocked yes)
			(layer "F.Fab")
			(hide yes)
			(effects
				(font
					(size 1.016 1.016)
					(thickness 0.1524)
				)
			)
		)
		(duplicate_pad_numbers_are_jumpers no)
		(fp_rect
			(start -0.381 0.8382)
			(end 0.381 -0.8382)
			(stroke
				(width 0)
				(type default)
			)
			(fill no)
			(layer "F.CrtYd")
		)
		(fp_rect
			(start -0.381 0.8382)
			(end 0.381 -0.8382)
			(stroke
				(width 0)
				(type default)
			)
			(fill no)
			(layer "F.Fab")
		)
		(pad "1" smd custom
			(at 0 -0.4318)
			(size 0.127 0.127)
			(layers "F.Cu" "F.Mask" "F.Paste")
			(net "HOST_RSTBTN#")
			(options
				(clearance outline)
				(anchor circle)
			)
			(primitives
				(gr_poly
					(pts
						(arc
							(start -0.2032 -0.2794)
							(mid -0.239121 -0.264521)
							(end -0.254 -0.2286)
						)
						(arc
							(start -0.254 0.2286)
							(mid -0.239121 0.264521)
							(end -0.2032 0.2794)
						)
						(arc
							(start 0.2032 0.2794)
							(mid 0.239121 0.264521)
							(end 0.254 0.2286)
						)
						(arc
							(start 0.254 -0.2286)
							(mid 0.239121 -0.264521)
							(end 0.2032 -0.2794)
						)
					)
					(width 0)
					(fill yes)
				)
			)
		)
		(pad "2" smd custom
			(at 0 0.4318)
			(size 0.127 0.127)
			(layers "F.Cu" "F.Mask" "F.Paste")
			(net "HOST_R_RSTBTN#")
			(options
				(clearance outline)
				(anchor circle)
			)
			(primitives
				(gr_poly
					(pts
						(arc
							(start -0.2032 -0.2794)
							(mid -0.239121 -0.264521)
							(end -0.254 -0.2286)
						)
						(arc
							(start -0.254 0.2286)
							(mid -0.239121 0.264521)
							(end -0.2032 0.2794)
						)
						(arc
							(start 0.2032 0.2794)
							(mid 0.239121 0.264521)
							(end 0.254 0.2286)
						)
						(arc
							(start 0.254 -0.2286)
							(mid 0.239121 -0.264521)
							(end 0.2032 -0.2794)
						)
					)
					(width 0)
					(fill yes)
				)
			)
		)
	)
	(footprint ""
		(layer "F.Cu")
		(at 186.309 -43.307)
		(property "Reference" "C96"
			(at 0 0 0)
			(layer "F.SilkS")
			(hide yes)
			(effects
				(font
					(size 1.27 1.27)
				)
			)
		)
		(property "Value" "SC1U6D3V2KX-GP"
			(at 1.1811 -2.7051 0)
			(unlocked yes)
			(layer "F.Fab")
			(hide yes)
			(effects
				(font
					(size 1.016 1.016)
					(thickness 0.1524)
				)
			)
		)
		(property "Device Type" "C402H22"
			(at 1.1811 -4.2291 0)
			(unlocked yes)
			(layer "F.Fab")
			(hide yes)
			(effects
				(font
					(size 1.016 1.016)
					(thickness 0.1524)
				)
			)
		)
		(duplicate_pad_numbers_are_jumpers no)
		(fp_rect
			(start -0.381 0.7366)
			(end 0.381 -0.7366)
			(stroke
				(width 0)
				(type default)
			)
			(fill no)
			(layer "F.CrtYd")
		)
		(fp_rect
			(start -0.381 0.7366)
			(end 0.381 -0.7366)
			(stroke
				(width 0)
				(type default)
			)
			(fill no)
			(layer "F.Fab")
		)
		(pad "1" smd custom
			(at 0 -0.4572)
			(size 0.1143 0.1143)
			(layers "F.Cu" "F.Mask" "F.Paste")
			(net "PV_VDDR_VREF_B")
			(options
				(clearance outline)
				(anchor circle)
			)
			(primitives
				(gr_poly
					(pts
						(arc
							(start -0.254 -0.1778)
							(mid -0.239121 -0.213721)
							(end -0.2032 -0.2286)
						)
						(arc
							(start 0.2032 -0.2286)
							(mid 0.239121 -0.213721)
							(end 0.254 -0.1778)
						)
						(arc
							(start 0.254 0.1778)
							(mid 0.239121 0.213721)
							(end 0.2032 0.2286)
						)
						(arc
							(start -0.2032 0.2286)
							(mid -0.239121 0.213721)
							(end -0.254 0.1778)
						)
					)
					(width 0)
					(fill yes)
				)
			)
		)
		(pad "2" smd custom
			(at 0 0.4572)
			(size 0.1143 0.1143)
			(layers "F.Cu" "F.Mask" "F.Paste")
			(net "GND")
			(options
				(clearance outline)
				(anchor circle)
			)
			(primitives
				(gr_poly
					(pts
						(arc
							(start -0.254 -0.1778)
							(mid -0.239121 -0.213721)
							(end -0.2032 -0.2286)
						)
						(arc
							(start 0.2032 -0.2286)
							(mid 0.239121 -0.213721)
							(end 0.254 -0.1778)
						)
						(arc
							(start 0.254 0.1778)
							(mid 0.239121 0.213721)
							(end 0.2032 0.2286)
						)
						(arc
							(start -0.2032 0.2286)
							(mid -0.239121 0.213721)
							(end -0.254 0.1778)
						)
					)
					(width 0)
					(fill yes)
				)
			)
		)
	)
	(footprint ""
		(layer "F.Cu")
		(at 183.3118 -31.7246)
		(property "Reference" "PR150"
			(at 0 0 0)
			(layer "F.SilkS")
			(hide yes)
			(effects
				(font
					(size 1.27 1.27)
				)
			)
		)
		(property "Value" "15KR2J-1-GP"
			(at 1.7907 -1.1176 0)
			(unlocked yes)
			(layer "F.Fab")
			(hide yes)
			(effects
				(font
					(size 1.016 1.016)
					(thickness 0.1524)
				)
			)
		)
		(property "Device Type" "R402H16"
			(at 1.7907 -2.6416 0)
			(unlocked yes)
			(layer "F.Fab")
			(hide yes)
			(effects
				(font
					(size 1.016 1.016)
					(thickness 0.1524)
				)
			)
		)
		(duplicate_pad_numbers_are_jumpers no)
		(fp_rect
			(start -0.381 0.8382)
			(end 0.381 -0.8382)
			(stroke
				(width 0)
				(type default)
			)
			(fill no)
			(layer "F.CrtYd")
		)
		(fp_rect
			(start -0.381 0.8382)
			(end 0.381 -0.8382)
			(stroke
				(width 0)
				(type default)
			)
			(fill no)
			(layer "F.Fab")
		)
		(pad "1" smd custom
			(at 0 -0.4318)
			(size 0.127 0.127)
			(layers "F.Cu" "F.Mask" "F.Paste")
			(net "VR_PVDDR_A_VW")
			(options
				(clearance outline)
				(anchor circle)
			)
			(primitives
				(gr_poly
					(pts
						(arc
							(start -0.2032 -0.2794)
							(mid -0.239121 -0.264521)
							(end -0.254 -0.2286)
						)
						(arc
							(start -0.254 0.2286)
							(mid -0.239121 0.264521)
							(end -0.2032 0.2794)
						)
						(arc
							(start 0.2032 0.2794)
							(mid 0.239121 0.264521)
							(end 0.254 0.2286)
						)
						(arc
							(start 0.254 -0.2286)
							(mid 0.239121 -0.264521)
							(end 0.2032 -0.2794)
						)
					)
					(width 0)
					(fill yes)
				)
			)
		)
		(pad "2" smd custom
			(at 0 0.4318)
			(size 0.127 0.127)
			(layers "F.Cu" "F.Mask" "F.Paste")
			(net "VR_PVDDR_A_COMP")
			(options
				(clearance outline)
				(anchor circle)
			)
			(primitives
				(gr_poly
					(pts
						(arc
							(start -0.2032 -0.2794)
							(mid -0.239121 -0.264521)
							(end -0.254 -0.2286)
						)
						(arc
							(start -0.254 0.2286)
							(mid -0.239121 0.264521)
							(end -0.2032 0.2794)
						)
						(arc
							(start 0.2032 0.2794)
							(mid 0.239121 0.264521)
							(end 0.254 0.2286)
						)
						(arc
							(start 0.254 -0.2286)
							(mid 0.239121 -0.264521)
							(end 0.2032 -0.2794)
						)
					)
					(width 0)
					(fill yes)
				)
			)
		)
	)
	(footprint ""
		(layer "F.Cu")
		(at 150.241 -20.701)
		(property "Reference" "C49"
			(at 0 0 0)
			(layer "F.SilkS")
			(hide yes)
			(effects
				(font
					(size 1.27 1.27)
				)
			)
		)
		(property "Value" "SCD1U10V2KX-5GP"
			(at 1.1811 -2.7051 0)
			(unlocked yes)
			(layer "F.Fab")
			(hide yes)
			(effects
				(font
					(size 1.016 1.016)
					(thickness 0.1524)
				)
			)
		)
		(property "Device Type" "C402H22"
			(at 1.1811 -4.2291 0)
			(unlocked yes)
			(layer "F.Fab")
			(hide yes)
			(effects
				(font
					(size 1.016 1.016)
					(thickness 0.1524)
				)
			)
		)
		(duplicate_pad_numbers_are_jumpers no)
		(fp_rect
			(start -0.381 0.7366)
			(end 0.381 -0.7366)
			(stroke
				(width 0)
				(type default)
			)
			(fill no)
			(layer "F.CrtYd")
		)
		(fp_rect
			(start -0.381 0.7366)
			(end 0.381 -0.7366)
			(stroke
				(width 0)
				(type default)
			)
			(fill no)
			(layer "F.Fab")
		)
		(pad "1" smd custom
			(at 0 -0.4572)
			(size 0.1143 0.1143)
			(layers "F.Cu" "F.Mask" "F.Paste")
			(net "P2V5_STBY")
			(options
				(clearance outline)
				(anchor circle)
			)
			(primitives
				(gr_poly
					(pts
						(arc
							(start -0.254 -0.1778)
							(mid -0.239121 -0.213721)
							(end -0.2032 -0.2286)
						)
						(arc
							(start 0.2032 -0.2286)
							(mid 0.239121 -0.213721)
							(end 0.254 -0.1778)
						)
						(arc
							(start 0.254 0.1778)
							(mid 0.239121 0.213721)
							(end 0.2032 0.2286)
						)
						(arc
							(start -0.2032 0.2286)
							(mid -0.239121 0.213721)
							(end -0.254 0.1778)
						)
					)
					(width 0)
					(fill yes)
				)
			)
		)
		(pad "2" smd custom
			(at 0 0.4572)
			(size 0.1143 0.1143)
			(layers "F.Cu" "F.Mask" "F.Paste")
			(net "GND")
			(options
				(clearance outline)
				(anchor circle)
			)
			(primitives
				(gr_poly
					(pts
						(arc
							(start -0.254 -0.1778)
							(mid -0.239121 -0.213721)
							(end -0.2032 -0.2286)
						)
						(arc
							(start 0.2032 -0.2286)
							(mid 0.239121 -0.213721)
							(end 0.254 -0.1778)
						)
						(arc
							(start 0.254 0.1778)
							(mid 0.239121 0.213721)
							(end 0.2032 0.2286)
						)
						(arc
							(start -0.2032 0.2286)
							(mid -0.239121 0.213721)
							(end -0.254 0.1778)
						)
					)
					(width 0)
					(fill yes)
				)
			)
		)
	)
	(footprint ""
		(layer "F.Cu")
		(at 54.2544 -19.6596 -90)
		(property "Reference" "U21"
			(at 0 0 270)
			(layer "F.SilkS")
			(hide yes)
			(effects
				(font
					(size 1.27 1.27)
				)
			)
		)
		(property "Value" "AT25256B-SSHL-T-GP"
			(at -3.707384 -1.5367 270)
			(unlocked yes)
			(layer "F.Fab")
			(hide yes)
			(effects
				(font
					(size 1.016 1.016)
					(thickness 0.1524)
				)
			)
		)
		(property "Device Type" "SOIC8H69"
			(at -3.707384 -3.0607 270)
			(unlocked yes)
			(layer "F.Fab")
			(hide yes)
			(effects
				(font
					(size 1.016 1.016)
					(thickness 0.1524)
				)
			)
		)
		(duplicate_pad_numbers_are_jumpers no)
		(fp_line
			(start -2.6797 1.4351)
			(end 2.1463 1.4351)
			(stroke
				(width 0.1524)
				(type default)
			)
			(layer "F.SilkS")
		)
		(fp_line
			(start 2.1463 1.4351)
			(end 2.1463 -1.4351)
			(stroke
				(width 0.1524)
				(type default)
			)
			(layer "F.SilkS")
		)
		(fp_line
			(start -2.502154 1.4224)
			(end -2.502154 3.1115)
			(stroke
				(width 0.508)
				(type default)
			)
			(layer "F.SilkS")
		)
		(fp_line
			(start -2.6797 0.508)
			(end -2.1717 0)
			(stroke
				(width 0.1524)
				(type default)
			)
			(layer "F.SilkS")
		)
		(fp_line
			(start -2.1717 0)
			(end -2.6797 -0.508)
			(stroke
				(width 0.1524)
				(type default)
			)
			(layer "F.SilkS")
		)
		(fp_line
			(start -2.6797 -0.508)
			(end -2.6797 0.508)
			(stroke
				(width 0.1524)
				(type default)
			)
			(layer "F.SilkS")
		)
		(fp_line
			(start -2.6797 -1.4351)
			(end -2.6797 1.4351)
			(stroke
				(width 0.1524)
				(type default)
			)
			(layer "F.SilkS")
		)
		(fp_line
			(start 2.1463 -1.4351)
			(end -2.6797 -1.4351)
			(stroke
				(width 0.1524)
				(type default)
			)
			(layer "F.SilkS")
		)
		(fp_poly
			(pts
				(xy -2.2225 -1.4351) (xy -2.2225 1.4351) (xy 2.1463 1.4351) (xy 2.1463 -1.4351)
			)
			(stroke
				(width 0)
				(type default)
			)
			(fill yes)
			(layer "F.SilkS")
		)
		(fp_rect
			(start -2.7559 3.3655)
			(end 2.7559 -3.3655)
			(stroke
				(width 0)
				(type default)
			)
			(fill no)
			(layer "F.CrtYd")
		)
		(fp_rect
			(start -2.7559 3.3655)
			(end 2.7559 -3.3655)
			(stroke
				(width 0)
				(type default)
			)
			(fill no)
			(layer "F.Fab")
		)
		(pad "1" smd rect
			(at -1.905 2.4765 270)
			(size 0.635 1.524)
			(layers "F.Cu" "F.Mask" "F.Paste")
			(net "SPI_CS_GBE#")
		)
		(pad "2" smd rect
			(at -0.635 2.4765 270)
			(size 0.635 1.524)
			(layers "F.Cu" "F.Mask" "F.Paste")
			(net "SO_GBE")
		)
		(pad "3" smd rect
			(at 0.635 2.4765 270)
			(size 0.635 1.524)
			(layers "F.Cu" "F.Mask" "F.Paste")
			(net "SPI_GBE_HOLD#")
		)
		(pad "4" smd rect
			(at 1.905 2.4765 270)
			(size 0.635 1.524)
			(layers "F.Cu" "F.Mask" "F.Paste")
			(net "GND")
		)
		(pad "5" smd rect
			(at 1.905 -2.4765 270)
			(size 0.635 1.524)
			(layers "F.Cu" "F.Mask" "F.Paste")
			(net "SPI_MOSI_GBE_R")
		)
		(pad "6" smd rect
			(at 0.635 -2.4765 270)
			(size 0.635 1.524)
			(layers "F.Cu" "F.Mask" "F.Paste")
			(net "SPI_CLK_GBE_R")
		)
		(pad "7" smd rect
			(at -0.635 -2.4765 270)
			(size 0.635 1.524)
			(layers "F.Cu" "F.Mask" "F.Paste")
			(net "SPI_GBE_HOLD#")
		)
		(pad "8" smd rect
			(at -1.905 -2.4765 270)
			(size 0.635 1.524)
			(layers "F.Cu" "F.Mask" "F.Paste")
			(net "P3V3_CPU")
		)
	)
	(footprint ""
		(layer "F.Cu")
		(at 8.509 -59.182 90)
		(property "Reference" "C40"
			(at 0 0 90)
			(layer "F.SilkS")
			(hide yes)
			(effects
				(font
					(size 1.27 1.27)
				)
			)
		)
		(property "Value" "SCD1U16V2KX-3GP"
			(at 1.1811 -2.7051 90)
			(unlocked yes)
			(layer "F.Fab")
			(hide yes)
			(effects
				(font
					(size 1.016 1.016)
					(thickness 0.1524)
				)
			)
		)
		(property "Device Type" "C402H22"
			(at 1.1811 -4.2291 90)
			(unlocked yes)
			(layer "F.Fab")
			(hide yes)
			(effects
				(font
					(size 1.016 1.016)
					(thickness 0.1524)
				)
			)
		)
		(duplicate_pad_numbers_are_jumpers no)
		(fp_rect
			(start -0.381 0.7366)
			(end 0.381 -0.7366)
			(stroke
				(width 0)
				(type default)
			)
			(fill no)
			(layer "F.CrtYd")
		)
		(fp_rect
			(start -0.381 0.7366)
			(end 0.381 -0.7366)
			(stroke
				(width 0)
				(type default)
			)
			(fill no)
			(layer "F.Fab")
		)
		(pad "1" smd custom
			(at 0 -0.4572 90)
			(size 0.1143 0.1143)
			(layers "F.Cu" "F.Mask" "F.Paste")
			(net "P2E_CPU_NGFF_TX_DP14")
			(options
				(clearance outline)
				(anchor circle)
			)
			(primitives
				(gr_poly
					(pts
						(arc
							(start -0.254 -0.1778)
							(mid -0.239121 -0.213721)
							(end -0.2032 -0.2286)
						)
						(arc
							(start 0.2032 -0.2286)
							(mid 0.239121 -0.213721)
							(end 0.254 -0.1778)
						)
						(arc
							(start 0.254 0.1778)
							(mid 0.239121 0.213721)
							(end 0.2032 0.2286)
						)
						(arc
							(start -0.2032 0.2286)
							(mid -0.239121 0.213721)
							(end -0.254 0.1778)
						)
					)
					(width 0)
					(fill yes)
				)
			)
		)
		(pad "2" smd custom
			(at 0 0.4572 90)
			(size 0.1143 0.1143)
			(layers "F.Cu" "F.Mask" "F.Paste")
			(net "P2E_CPU_NGFF_C_TX_DP14")
			(options
				(clearance outline)
				(anchor circle)
			)
			(primitives
				(gr_poly
					(pts
						(arc
							(start -0.254 -0.1778)
							(mid -0.239121 -0.213721)
							(end -0.2032 -0.2286)
						)
						(arc
							(start 0.2032 -0.2286)
							(mid 0.239121 -0.213721)
							(end 0.254 -0.1778)
						)
						(arc
							(start 0.254 0.1778)
							(mid 0.239121 0.213721)
							(end 0.2032 0.2286)
						)
						(arc
							(start -0.2032 0.2286)
							(mid -0.239121 0.213721)
							(end -0.254 0.1778)
						)
					)
					(width 0)
					(fill yes)
				)
			)
		)
	)
	(footprint ""
		(layer "F.Cu")
		(at 41.783 -49.53 180)
		(property "Reference" "C14"
			(at 0 0 180)
			(layer "F.SilkS")
			(hide yes)
			(effects
				(font
					(size 1.27 1.27)
				)
			)
		)
		(property "Value" "SC1U10V2KX-1GP"
			(at 1.8923 -1.2065 180)
			(unlocked yes)
			(layer "F.Fab")
			(hide yes)
			(effects
				(font
					(size 1.016 1.016)
					(thickness 0.1524)
				)
			)
		)
		(property "Device Type" "C402H22"
			(at 1.8923 -2.7305 180)
			(unlocked yes)
			(layer "F.Fab")
			(hide yes)
			(effects
				(font
					(size 1.016 1.016)
					(thickness 0.1524)
				)
			)
		)
		(duplicate_pad_numbers_are_jumpers no)
		(fp_rect
			(start -0.381 0.7366)
			(end 0.381 -0.7366)
			(stroke
				(width 0)
				(type default)
			)
			(fill no)
			(layer "F.CrtYd")
		)
		(fp_rect
			(start -0.381 0.7366)
			(end 0.381 -0.7366)
			(stroke
				(width 0)
				(type default)
			)
			(fill no)
			(layer "F.Fab")
		)
		(pad "1" smd custom
			(at 0 -0.4572 180)
			(size 0.1143 0.1143)
			(layers "F.Cu" "F.Mask" "F.Paste")
			(net "P3V3_CPU_DELAY_IN")
			(options
				(clearance outline)
				(anchor circle)
			)
			(primitives
				(gr_poly
					(pts
						(arc
							(start -0.254 -0.1778)
							(mid -0.239121 -0.213721)
							(end -0.2032 -0.2286)
						)
						(arc
							(start 0.2032 -0.2286)
							(mid 0.239121 -0.213721)
							(end 0.254 -0.1778)
						)
						(arc
							(start 0.254 0.1778)
							(mid 0.239121 0.213721)
							(end 0.2032 0.2286)
						)
						(arc
							(start -0.2032 0.2286)
							(mid -0.239121 0.213721)
							(end -0.254 0.1778)
						)
					)
					(width 0)
					(fill yes)
				)
			)
		)
		(pad "2" smd custom
			(at 0 0.4572 180)
			(size 0.1143 0.1143)
			(layers "F.Cu" "F.Mask" "F.Paste")
			(net "GND")
			(options
				(clearance outline)
				(anchor circle)
			)
			(primitives
				(gr_poly
					(pts
						(arc
							(start -0.254 -0.1778)
							(mid -0.239121 -0.213721)
							(end -0.2032 -0.2286)
						)
						(arc
							(start 0.2032 -0.2286)
							(mid 0.239121 -0.213721)
							(end 0.254 -0.1778)
						)
						(arc
							(start 0.254 0.1778)
							(mid 0.239121 0.213721)
							(end 0.2032 0.2286)
						)
						(arc
							(start -0.2032 0.2286)
							(mid -0.239121 0.213721)
							(end -0.254 0.1778)
						)
					)
					(width 0)
					(fill yes)
				)
			)
		)
	)
	(footprint ""
		(layer "F.Cu")
		(at 128.143 -36.068 -90)
		(property "Reference" "R29"
			(at 0 0 270)
			(layer "F.SilkS")
			(hide yes)
			(effects
				(font
					(size 1.27 1.27)
				)
			)
		)
		(property "Value" "33R2F-3-GP"
			(at 0.064008 -3.993896 270)
			(unlocked yes)
			(layer "F.Fab")
			(hide yes)
			(effects
				(font
					(size 1.016 1.016)
					(thickness 0.1524)
				)
			)
		)
		(property "Device Type" "R402H16"
			(at 0.064008 -5.517896 270)
			(unlocked yes)
			(layer "F.Fab")
			(hide yes)
			(effects
				(font
					(size 1.016 1.016)
					(thickness 0.1524)
				)
			)
		)
		(duplicate_pad_numbers_are_jumpers no)
		(fp_rect
			(start -0.381 0.8382)
			(end 0.381 -0.8382)
			(stroke
				(width 0)
				(type default)
			)
			(fill no)
			(layer "F.CrtYd")
		)
		(fp_rect
			(start -0.381 0.8382)
			(end 0.381 -0.8382)
			(stroke
				(width 0)
				(type default)
			)
			(fill no)
			(layer "F.Fab")
		)
		(pad "1" smd custom
			(at 0 -0.4318 270)
			(size 0.127 0.127)
			(layers "F.Cu" "F.Mask" "F.Paste")
			(net "LPC_AD_1")
			(options
				(clearance outline)
				(anchor circle)
			)
			(primitives
				(gr_poly
					(pts
						(arc
							(start -0.2032 -0.2794)
							(mid -0.239121 -0.264521)
							(end -0.254 -0.2286)
						)
						(arc
							(start -0.254 0.2286)
							(mid -0.239121 0.264521)
							(end -0.2032 0.2794)
						)
						(arc
							(start 0.2032 0.2794)
							(mid 0.239121 0.264521)
							(end 0.254 0.2286)
						)
						(arc
							(start 0.254 -0.2286)
							(mid 0.239121 -0.264521)
							(end 0.2032 -0.2794)
						)
					)
					(width 0)
					(fill yes)
				)
			)
		)
		(pad "2" smd custom
			(at 0 0.4318 270)
			(size 0.127 0.127)
			(layers "F.Cu" "F.Mask" "F.Paste")
			(net "LPC_CPU_LAD1")
			(options
				(clearance outline)
				(anchor circle)
			)
			(primitives
				(gr_poly
					(pts
						(arc
							(start -0.2032 -0.2794)
							(mid -0.239121 -0.264521)
							(end -0.254 -0.2286)
						)
						(arc
							(start -0.254 0.2286)
							(mid -0.239121 0.264521)
							(end -0.2032 0.2794)
						)
						(arc
							(start 0.2032 0.2794)
							(mid 0.239121 0.264521)
							(end 0.254 0.2286)
						)
						(arc
							(start 0.254 -0.2286)
							(mid 0.239121 -0.264521)
							(end 0.2032 -0.2794)
						)
					)
					(width 0)
					(fill yes)
				)
			)
		)
	)
	(footprint ""
		(layer "F.Cu")
		(at 5.715 -35.4076 -90)
		(property "Reference" "PC188"
			(at 0 0 270)
			(layer "F.SilkS")
			(hide yes)
			(effects
				(font
					(size 1.27 1.27)
				)
			)
		)
		(property "Value" "SC4D7U25V5KX-1-GP"
			(at 0 -4.9022 270)
			(unlocked yes)
			(layer "F.Fab")
			(hide yes)
			(effects
				(font
					(size 1.016 1.016)
					(thickness 0.1524)
				)
			)
		)
		(property "Device Type" "C805H58"
			(at 0 -6.8072 270)
			(unlocked yes)
			(layer "F.Fab")
			(hide yes)
			(effects
				(font
					(size 1.016 1.016)
					(thickness 0.1524)
				)
			)
		)
		(duplicate_pad_numbers_are_jumpers no)
		(fp_line
			(start 0.6096 0)
			(end -0.6096 0)
			(stroke
				(width 0.3048)
				(type default)
			)
			(layer "F.SilkS")
		)
		(fp_poly
			(pts
				(xy -0.9017 1.4351) (xy 0.9017 1.4351) (xy 0.9017 -1.4351) (xy -0.9017 -1.4351)
			)
			(stroke
				(width 0)
				(type default)
			)
			(fill no)
			(layer "F.CrtYd")
		)
		(fp_poly
			(pts
				(xy 0.9017 1.4351) (xy 0.9017 -1.4351) (xy -0.9017 -1.4351) (xy -0.9017 1.4351)
			)
			(stroke
				(width 0)
				(type default)
			)
			(fill no)
			(layer "F.Fab")
		)
		(pad "1" smd rect
			(at 0 -0.8382 270)
			(size 1.5494 0.9398)
			(layers "F.Cu" "F.Mask" "F.Paste")
			(net "P3V3_STBY_VDD")
		)
		(pad "2" smd rect
			(at 0 0.8382 270)
			(size 1.5494 0.9398)
			(layers "F.Cu" "F.Mask" "F.Paste")
			(net "GND")
		)
	)
	(footprint ""
		(layer "F.Cu")
		(at 11.049 -36.449 -90)
		(property "Reference" "PU15"
			(at 0 0 270)
			(layer "F.SilkS")
			(hide yes)
			(effects
				(font
					(size 1.27 1.27)
				)
			)
		)
		(property "Value" "TPS53318DQPR-GP"
			(at -4.298442 -3.894328 270)
			(unlocked yes)
			(layer "F.Fab")
			(hide yes)
			(effects
				(font
					(size 1.016 1.016)
					(thickness 0.1524)
				)
			)
		)
		(property "Device Type" "DFN22G6050-G6133H60"
			(at -4.298442 -5.418328 270)
			(unlocked yes)
			(layer "F.Fab")
			(hide yes)
			(effects
				(font
					(size 1.016 1.016)
					(thickness 0.1524)
				)
			)
		)
		(duplicate_pad_numbers_are_jumpers no)
		(fp_poly
			(pts
				(xy 2.508504 -2.882138) (xy 2.986024 -3.359912) (xy 2.03073 -3.359912)
			)
			(stroke
				(width 0)
				(type default)
			)
			(fill yes)
			(layer "F.SilkS")
		)
		(fp_rect
			(start -3.2512 2.8829)
			(end 3.2512 -2.8829)
			(stroke
				(width 0)
				(type default)
			)
			(fill no)
			(layer "F.CrtYd")
		)
		(fp_rect
			(start -3.2512 2.8829)
			(end 3.2512 -2.8829)
			(stroke
				(width 0)
				(type default)
			)
			(fill no)
			(layer "F.Fab")
		)
		(pad "1" smd rect
			(at 2.500122 -2.322322 270)
			(size 0.3048 0.8636)
			(layers "F.Cu" "F.Mask" "F.Paste")
			(net "P3V3_STBY_VFB")
		)
		(pad "2" smd rect
			(at 1.999996 -2.322322 270)
			(size 0.3048 0.8636)
			(layers "F.Cu" "F.Mask" "F.Paste")
			(net "P3V3_STBY_EN")
		)
		(pad "3" smd rect
			(at 1.500124 -2.322322 270)
			(size 0.3048 0.8636)
			(layers "F.Cu" "F.Mask" "F.Paste")
			(net "P3V3_STBY_PG")
		)
		(pad "4" smd rect
			(at 0.999998 -2.322322 270)
			(size 0.3048 0.8636)
			(layers "F.Cu" "F.Mask" "F.Paste")
			(net "P3V3_STBY_VBST")
		)
		(pad "5" smd rect
			(at 0.500126 -2.322322 270)
			(size 0.3048 0.8636)
			(layers "F.Cu" "F.Mask" "F.Paste")
			(net "P3V3_STBY_ROVP")
		)
		(pad "6" smd rect
			(at 0 -2.322322 270)
			(size 0.3048 0.8636)
			(layers "F.Cu" "F.Mask" "F.Paste")
			(net "P3V3_STBY_LL")
		)
		(pad "7" smd rect
			(at -0.500126 -2.322322 270)
			(size 0.3048 0.8636)
			(layers "F.Cu" "F.Mask" "F.Paste")
			(net "P3V3_STBY_LL")
		)
		(pad "8" smd rect
			(at -0.999998 -2.322322 270)
			(size 0.3048 0.8636)
			(layers "F.Cu" "F.Mask" "F.Paste")
			(net "P3V3_STBY_LL")
		)
		(pad "9" smd rect
			(at -1.500124 -2.322322 270)
			(size 0.3048 0.8636)
			(layers "F.Cu" "F.Mask" "F.Paste")
			(net "P3V3_STBY_LL")
		)
		(pad "10" smd rect
			(at -1.999996 -2.322322 270)
			(size 0.3048 0.8636)
			(layers "F.Cu" "F.Mask" "F.Paste")
			(net "P3V3_STBY_LL")
		)
		(pad "11" smd rect
			(at -2.500122 -2.322322 270)
			(size 0.3048 0.8636)
			(layers "F.Cu" "F.Mask" "F.Paste")
			(net "P3V3_STBY_LL")
		)
		(pad "12" smd rect
			(at -2.500122 2.322322 270)
			(size 0.3048 0.8636)
			(layers "F.Cu" "F.Mask" "F.Paste")
			(net "P3V3_STBY_VIN")
		)
		(pad "13" smd rect
			(at -1.999996 2.322322 270)
			(size 0.3048 0.8636)
			(layers "F.Cu" "F.Mask" "F.Paste")
			(net "P3V3_STBY_VIN")
		)
		(pad "14" smd rect
			(at -1.500124 2.322322 270)
			(size 0.3048 0.8636)
			(layers "F.Cu" "F.Mask" "F.Paste")
			(net "P3V3_STBY_VIN")
		)
		(pad "15" smd rect
			(at -0.999998 2.322322 270)
			(size 0.3048 0.8636)
			(layers "F.Cu" "F.Mask" "F.Paste")
			(net "P3V3_STBY_VIN")
		)
		(pad "16" smd rect
			(at -0.500126 2.322322 270)
			(size 0.3048 0.8636)
			(layers "F.Cu" "F.Mask" "F.Paste")
			(net "P3V3_STBY_VIN")
		)
		(pad "17" smd rect
			(at 0 2.322322 270)
			(size 0.3048 0.8636)
			(layers "F.Cu" "F.Mask" "F.Paste")
			(net "P3V3_STBY_VIN")
		)
		(pad "18" smd rect
			(at 0.500126 2.322322 270)
			(size 0.3048 0.8636)
			(layers "F.Cu" "F.Mask" "F.Paste")
			(net "P3V3_STBY_VREG")
		)
		(pad "19" smd rect
			(at 0.999998 2.322322 270)
			(size 0.3048 0.8636)
			(layers "F.Cu" "F.Mask" "F.Paste")
			(net "P3V3_STBY_VDD")
		)
		(pad "20" smd rect
			(at 1.500124 2.322322 270)
			(size 0.3048 0.8636)
			(layers "F.Cu" "F.Mask" "F.Paste")
			(net "P3V3_STBY_MODE")
		)
		(pad "21" smd rect
			(at 1.999996 2.322322 270)
			(size 0.3048 0.8636)
			(layers "F.Cu" "F.Mask" "F.Paste")
			(net "P3V3_STBY_TRIP")
		)
		(pad "22" smd rect
			(at 2.500122 2.322322 270)
			(size 0.3048 0.8636)
			(layers "F.Cu" "F.Mask" "F.Paste")
			(net "P3V3_STBY_RF")
		)
		(pad "23" smd custom
			(at 0 0 270)
			(size 0.83185 0.83185)
			(layers "F.Cu" "F.Mask" "F.Paste")
			(net "GND")
			(options
				(clearance outline)
				(anchor circle)
			)
			(primitives
				(gr_poly
					(pts
						(xy -2.7813 1.6637) (xy -2.7813 1.2954) (xy -3.048 1.2954) (xy -3.048 0.9525) (xy -2.7813 0.9525)
						(xy -2.7813 -0.9525) (xy -3.048 -0.9525) (xy -3.048 -1.2954) (xy -2.7813 -1.2954) (xy -2.7813 -1.6637)
						(xy 2.7813 -1.6637) (xy 2.7813 -1.2954) (xy 3.048 -1.2954) (xy 3.048 -0.9525) (xy 2.7813 -0.9525)
						(xy 2.7813 0.9525) (xy 3.048 0.9525) (xy 3.048 1.2954) (xy 2.7813 1.2954) (xy 2.7813 1.6637)
					)
					(width 0)
					(fill yes)
				)
			)
		)
	)
	(footprint ""
		(layer "F.Cu")
		(at 14.478 -31.877 180)
		(property "Reference" "R319"
			(at 0 0 180)
			(layer "F.SilkS")
			(hide yes)
			(effects
				(font
					(size 1.27 1.27)
				)
			)
		)
		(property "Value" "2K2R2F-GP"
			(at 1.7907 -1.1176 180)
			(unlocked yes)
			(layer "F.Fab")
			(hide yes)
			(effects
				(font
					(size 1.016 1.016)
					(thickness 0.1524)
				)
			)
		)
		(property "Device Type" "R402H16"
			(at 1.7907 -2.6416 180)
			(unlocked yes)
			(layer "F.Fab")
			(hide yes)
			(effects
				(font
					(size 1.016 1.016)
					(thickness 0.1524)
				)
			)
		)
		(duplicate_pad_numbers_are_jumpers no)
		(fp_rect
			(start -0.381 0.8382)
			(end 0.381 -0.8382)
			(stroke
				(width 0)
				(type default)
			)
			(fill no)
			(layer "F.CrtYd")
		)
		(fp_rect
			(start -0.381 0.8382)
			(end 0.381 -0.8382)
			(stroke
				(width 0)
				(type default)
			)
			(fill no)
			(layer "F.Fab")
		)
		(pad "1" smd custom
			(at 0 -0.4318 180)
			(size 0.127 0.127)
			(layers "F.Cu" "F.Mask" "F.Paste")
			(net "AGND_P3V3_STBY")
			(options
				(clearance outline)
				(anchor circle)
			)
			(primitives
				(gr_poly
					(pts
						(arc
							(start -0.2032 -0.2794)
							(mid -0.239121 -0.264521)
							(end -0.254 -0.2286)
						)
						(arc
							(start -0.254 0.2286)
							(mid -0.239121 0.264521)
							(end -0.2032 0.2794)
						)
						(arc
							(start 0.2032 0.2794)
							(mid 0.239121 0.264521)
							(end 0.254 0.2286)
						)
						(arc
							(start 0.254 -0.2286)
							(mid 0.239121 -0.264521)
							(end 0.2032 -0.2794)
						)
					)
					(width 0)
					(fill yes)
				)
			)
		)
		(pad "2" smd custom
			(at 0 0.4318 180)
			(size 0.127 0.127)
			(layers "F.Cu" "F.Mask" "F.Paste")
			(net "P3V3_STBY_EN")
			(options
				(clearance outline)
				(anchor circle)
			)
			(primitives
				(gr_poly
					(pts
						(arc
							(start -0.2032 -0.2794)
							(mid -0.239121 -0.264521)
							(end -0.254 -0.2286)
						)
						(arc
							(start -0.254 0.2286)
							(mid -0.239121 0.264521)
							(end -0.2032 0.2794)
						)
						(arc
							(start 0.2032 0.2794)
							(mid 0.239121 0.264521)
							(end 0.254 0.2286)
						)
						(arc
							(start 0.254 -0.2286)
							(mid 0.239121 -0.264521)
							(end 0.2032 -0.2794)
						)
					)
					(width 0)
					(fill yes)
				)
			)
		)
	)
	(footprint ""
		(layer "F.Cu")
		(at 15.7988 -34.29)
		(property "Reference" "PR193"
			(at 0 0 0)
			(layer "F.SilkS")
			(hide yes)
			(effects
				(font
					(size 1.27 1.27)
				)
			)
		)
		(property "Value" "3D01R5F-GP"
			(at 0 -4.9022 0)
			(unlocked yes)
			(layer "F.Fab")
			(hide yes)
			(effects
				(font
					(size 1.016 1.016)
					(thickness 0.1524)
				)
			)
		)
		(property "Device Type" "R805H24"
			(at 0 -6.8072 0)
			(unlocked yes)
			(layer "F.Fab")
			(hide yes)
			(effects
				(font
					(size 1.016 1.016)
					(thickness 0.1524)
				)
			)
		)
		(duplicate_pad_numbers_are_jumpers no)
		(fp_line
			(start -0.2794 0)
			(end -0.6096 0)
			(stroke
				(width 0.3048)
				(type default)
			)
			(layer "F.SilkS")
		)
		(fp_line
			(start 0.6096 0)
			(end 0.2794 0)
			(stroke
				(width 0.3048)
				(type default)
			)
			(layer "F.SilkS")
		)
		(fp_poly
			(pts
				(xy -0.9017 1.4351) (xy 0.9017 1.4351) (xy 0.9017 -1.4351) (xy -0.9017 -1.4351)
			)
			(stroke
				(width 0)
				(type default)
			)
			(fill no)
			(layer "F.CrtYd")
		)
		(fp_poly
			(pts
				(xy 0.9017 1.4351) (xy 0.9017 -1.4351) (xy -0.9017 -1.4351) (xy -0.9017 1.4351)
			)
			(stroke
				(width 0)
				(type default)
			)
			(fill no)
			(layer "F.Fab")
		)
		(pad "1" smd rect
			(at 0 -0.8382)
			(size 1.5494 0.9398)
			(layers "F.Cu" "F.Mask" "F.Paste")
			(net "P3V3_STBY_VBST")
		)
		(pad "2" smd rect
			(at 0 0.8382)
			(size 1.5494 0.9398)
			(layers "F.Cu" "F.Mask" "F.Paste")
			(net "P3V3_STBY_VBST_RC")
		)
	)
	(footprint ""
		(layer "F.Cu")
		(at 148.717 -20.701)
		(property "Reference" "C46"
			(at 0 0 0)
			(layer "F.SilkS")
			(hide yes)
			(effects
				(font
					(size 1.27 1.27)
				)
			)
		)
		(property "Value" "SCD1U10V2KX-5GP"
			(at 1.1811 -2.7051 0)
			(unlocked yes)
			(layer "F.Fab")
			(hide yes)
			(effects
				(font
					(size 1.016 1.016)
					(thickness 0.1524)
				)
			)
		)
		(property "Device Type" "C402H22"
			(at 1.1811 -4.2291 0)
			(unlocked yes)
			(layer "F.Fab")
			(hide yes)
			(effects
				(font
					(size 1.016 1.016)
					(thickness 0.1524)
				)
			)
		)
		(duplicate_pad_numbers_are_jumpers no)
		(fp_rect
			(start -0.381 0.7366)
			(end 0.381 -0.7366)
			(stroke
				(width 0)
				(type default)
			)
			(fill no)
			(layer "F.CrtYd")
		)
		(fp_rect
			(start -0.381 0.7366)
			(end 0.381 -0.7366)
			(stroke
				(width 0)
				(type default)
			)
			(fill no)
			(layer "F.Fab")
		)
		(pad "1" smd custom
			(at 0 -0.4572)
			(size 0.1143 0.1143)
			(layers "F.Cu" "F.Mask" "F.Paste")
			(net "P1V2_FPGA_D")
			(options
				(clearance outline)
				(anchor circle)
			)
			(primitives
				(gr_poly
					(pts
						(arc
							(start -0.254 -0.1778)
							(mid -0.239121 -0.213721)
							(end -0.2032 -0.2286)
						)
						(arc
							(start 0.2032 -0.2286)
							(mid 0.239121 -0.213721)
							(end 0.254 -0.1778)
						)
						(arc
							(start 0.254 0.1778)
							(mid 0.239121 0.213721)
							(end 0.2032 0.2286)
						)
						(arc
							(start -0.2032 0.2286)
							(mid -0.239121 0.213721)
							(end -0.254 0.1778)
						)
					)
					(width 0)
					(fill yes)
				)
			)
		)
		(pad "2" smd custom
			(at 0 0.4572)
			(size 0.1143 0.1143)
			(layers "F.Cu" "F.Mask" "F.Paste")
			(net "GND")
			(options
				(clearance outline)
				(anchor circle)
			)
			(primitives
				(gr_poly
					(pts
						(arc
							(start -0.254 -0.1778)
							(mid -0.239121 -0.213721)
							(end -0.2032 -0.2286)
						)
						(arc
							(start 0.2032 -0.2286)
							(mid 0.239121 -0.213721)
							(end 0.254 -0.1778)
						)
						(arc
							(start 0.254 0.1778)
							(mid 0.239121 0.213721)
							(end 0.2032 0.2286)
						)
						(arc
							(start -0.2032 0.2286)
							(mid -0.239121 0.213721)
							(end -0.254 0.1778)
						)
					)
					(width 0)
					(fill yes)
				)
			)
		)
	)
	(footprint ""
		(layer "F.Cu")
		(at 158.242 -28.956 180)
		(property "Reference" "R147"
			(at 0 0 180)
			(layer "F.SilkS")
			(hide yes)
			(effects
				(font
					(size 1.27 1.27)
				)
			)
		)
		(property "Value" "4K7R2F-GP"
			(at 0.064008 -3.993896 180)
			(unlocked yes)
			(layer "F.Fab")
			(hide yes)
			(effects
				(font
					(size 1.016 1.016)
					(thickness 0.1524)
				)
			)
		)
		(property "Device Type" "R402H16"
			(at 0.064008 -5.517896 180)
			(unlocked yes)
			(layer "F.Fab")
			(hide yes)
			(effects
				(font
					(size 1.016 1.016)
					(thickness 0.1524)
				)
			)
		)
		(duplicate_pad_numbers_are_jumpers no)
		(fp_rect
			(start -0.381 0.8382)
			(end 0.381 -0.8382)
			(stroke
				(width 0)
				(type default)
			)
			(fill no)
			(layer "F.CrtYd")
		)
		(fp_rect
			(start -0.381 0.8382)
			(end 0.381 -0.8382)
			(stroke
				(width 0)
				(type default)
			)
			(fill no)
			(layer "F.Fab")
		)
		(pad "1" smd custom
			(at 0 -0.4318 180)
			(size 0.127 0.127)
			(layers "F.Cu" "F.Mask" "F.Paste")
			(net "P3V3_STBY")
			(options
				(clearance outline)
				(anchor circle)
			)
			(primitives
				(gr_poly
					(pts
						(arc
							(start -0.2032 -0.2794)
							(mid -0.239121 -0.264521)
							(end -0.254 -0.2286)
						)
						(arc
							(start -0.254 0.2286)
							(mid -0.239121 0.264521)
							(end -0.2032 0.2794)
						)
						(arc
							(start 0.2032 0.2794)
							(mid 0.239121 0.264521)
							(end 0.254 0.2286)
						)
						(arc
							(start 0.254 -0.2286)
							(mid 0.239121 -0.264521)
							(end 0.2032 -0.2794)
						)
					)
					(width 0)
					(fill yes)
				)
			)
		)
		(pad "2" smd custom
			(at 0 0.4318 180)
			(size 0.127 0.127)
			(layers "F.Cu" "F.Mask" "F.Paste")
			(net "FPGA_READY#")
			(options
				(clearance outline)
				(anchor circle)
			)
			(primitives
				(gr_poly
					(pts
						(arc
							(start -0.2032 -0.2794)
							(mid -0.239121 -0.264521)
							(end -0.254 -0.2286)
						)
						(arc
							(start -0.254 0.2286)
							(mid -0.239121 0.264521)
							(end -0.2032 0.2794)
						)
						(arc
							(start 0.2032 0.2794)
							(mid 0.239121 0.264521)
							(end 0.254 0.2286)
						)
						(arc
							(start 0.254 -0.2286)
							(mid 0.239121 -0.264521)
							(end 0.2032 -0.2794)
						)
					)
					(width 0)
					(fill yes)
				)
			)
		)
	)
	(footprint ""
		(layer "F.Cu")
		(at 6.839966 -46.479968)
		(property "Reference" "U1"
			(at 0 0 0)
			(layer "F.SilkS")
			(hide yes)
			(effects
				(font
					(size 1.27 1.27)
				)
			)
		)
		(property "Value" "TMP75AIDGKR-GP"
			(at -0.1143 -9.1948 0)
			(unlocked yes)
			(layer "F.Fab")
			(hide yes)
			(effects
				(font
					(size 1.016 1.016)
					(thickness 0.1524)
				)
			)
		)
		(property "Device Type" "MSOP8-1H44"
			(at -0.1143 -10.795 0)
			(unlocked yes)
			(layer "F.Fab")
			(hide yes)
			(effects
				(font
					(size 1.016 1.016)
					(thickness 0.1524)
				)
			)
		)
		(duplicate_pad_numbers_are_jumpers no)
		(fp_line
			(start -1.7018 -1.016)
			(end -1.7018 1.016)
			(stroke
				(width 0.1524)
				(type default)
			)
			(layer "F.SilkS")
		)
		(fp_line
			(start -1.7018 -0.4318)
			(end -1.27 0)
			(stroke
				(width 0.1524)
				(type default)
			)
			(layer "F.SilkS")
		)
		(fp_line
			(start -1.7018 1.016)
			(end 1.0668 1.016)
			(stroke
				(width 0.1524)
				(type default)
			)
			(layer "F.SilkS")
		)
		(fp_line
			(start -1.651 1.0668)
			(end -1.651 2.794)
			(stroke
				(width 0.254)
				(type default)
			)
			(layer "F.SilkS")
		)
		(fp_line
			(start -1.27 0)
			(end -1.7018 0.4318)
			(stroke
				(width 0.1524)
				(type default)
			)
			(layer "F.SilkS")
		)
		(fp_line
			(start 1.0668 -1.016)
			(end -1.7018 -1.016)
			(stroke
				(width 0.1524)
				(type default)
			)
			(layer "F.SilkS")
		)
		(fp_line
			(start 1.0668 1.016)
			(end 1.0668 -1.016)
			(stroke
				(width 0.1524)
				(type default)
			)
			(layer "F.SilkS")
		)
		(fp_poly
			(pts
				(xy -1.1684 1.016) (xy 1.0668 1.016) (xy 1.0668 -1.016) (xy -1.1684 -1.016)
			)
			(stroke
				(width 0)
				(type default)
			)
			(fill yes)
			(layer "F.SilkS")
		)
		(fp_rect
			(start -1.7526 2.8194)
			(end 1.7526 -2.8194)
			(stroke
				(width 0)
				(type default)
			)
			(fill no)
			(layer "F.CrtYd")
		)
		(fp_rect
			(start -1.7526 2.8194)
			(end 1.7526 -2.8194)
			(stroke
				(width 0)
				(type default)
			)
			(fill no)
			(layer "F.Fab")
		)
		(pad "1" smd rect
			(at -0.97536 1.99136)
			(size 0.3556 1.397)
			(layers "F.Cu" "F.Mask" "F.Paste")
			(net "TEMP_1_DATA")
		)
		(pad "2" smd rect
			(at -0.32512 1.99136)
			(size 0.3556 1.397)
			(layers "F.Cu" "F.Mask" "F.Paste")
			(net "TEMP_1_CLK")
		)
		(pad "3" smd rect
			(at 0.32512 1.99136)
			(size 0.3556 1.397)
			(layers "F.Cu" "F.Mask" "F.Paste")
			(net "TEMP_1_ALERT#")
		)
		(pad "4" smd rect
			(at 0.97536 1.99136)
			(size 0.3556 1.397)
			(layers "F.Cu" "F.Mask" "F.Paste")
			(net "GND")
		)
		(pad "5" smd rect
			(at 0.97536 -1.99136)
			(size 0.3556 1.397)
			(layers "F.Cu" "F.Mask" "F.Paste")
			(net "TEMP_1_A2")
		)
		(pad "6" smd rect
			(at 0.32512 -1.99136)
			(size 0.3556 1.397)
			(layers "F.Cu" "F.Mask" "F.Paste")
			(net "TEMP_1_A1")
		)
		(pad "7" smd rect
			(at -0.32512 -1.99136)
			(size 0.3556 1.397)
			(layers "F.Cu" "F.Mask" "F.Paste")
			(net "TEMP_1_A0")
		)
		(pad "8" smd rect
			(at -0.97536 -1.99136)
			(size 0.3556 1.397)
			(layers "F.Cu" "F.Mask" "F.Paste")
			(net "P3V3_STBY")
		)
	)
	(footprint ""
		(layer "F.Cu")
		(at 70.231 -36.957 90)
		(property "Reference" "R99"
			(at 0 0 90)
			(layer "F.SilkS")
			(hide yes)
			(effects
				(font
					(size 1.27 1.27)
				)
			)
		)
		(property "Value" "10KR2F-2-GP"
			(at 0.064008 -3.993896 90)
			(unlocked yes)
			(layer "F.Fab")
			(hide yes)
			(effects
				(font
					(size 1.016 1.016)
					(thickness 0.1524)
				)
			)
		)
		(property "Device Type" "R402H16"
			(at 0.064008 -5.517896 90)
			(unlocked yes)
			(layer "F.Fab")
			(hide yes)
			(effects
				(font
					(size 1.016 1.016)
					(thickness 0.1524)
				)
			)
		)
		(duplicate_pad_numbers_are_jumpers no)
		(fp_rect
			(start -0.381 0.8382)
			(end 0.381 -0.8382)
			(stroke
				(width 0)
				(type default)
			)
			(fill no)
			(layer "F.CrtYd")
		)
		(fp_rect
			(start -0.381 0.8382)
			(end 0.381 -0.8382)
			(stroke
				(width 0)
				(type default)
			)
			(fill no)
			(layer "F.Fab")
		)
		(pad "1" smd custom
			(at 0 -0.4318 90)
			(size 0.127 0.127)
			(layers "F.Cu" "F.Mask" "F.Paste")
			(net "P3V3_CPU")
			(options
				(clearance outline)
				(anchor circle)
			)
			(primitives
				(gr_poly
					(pts
						(arc
							(start -0.2032 -0.2794)
							(mid -0.239121 -0.264521)
							(end -0.254 -0.2286)
						)
						(arc
							(start -0.254 0.2286)
							(mid -0.239121 0.264521)
							(end -0.2032 0.2794)
						)
						(arc
							(start 0.2032 0.2794)
							(mid 0.239121 0.264521)
							(end 0.254 0.2286)
						)
						(arc
							(start 0.254 -0.2286)
							(mid 0.239121 -0.264521)
							(end 0.2032 -0.2794)
						)
					)
					(width 0)
					(fill yes)
				)
			)
		)
		(pad "2" smd custom
			(at 0 0.4318 90)
			(size 0.127 0.127)
			(layers "F.Cu" "F.Mask" "F.Paste")
			(net "PMU_SLP_S3#")
			(options
				(clearance outline)
				(anchor circle)
			)
			(primitives
				(gr_poly
					(pts
						(arc
							(start -0.2032 -0.2794)
							(mid -0.239121 -0.264521)
							(end -0.254 -0.2286)
						)
						(arc
							(start -0.254 0.2286)
							(mid -0.239121 0.264521)
							(end -0.2032 0.2794)
						)
						(arc
							(start 0.2032 0.2794)
							(mid 0.239121 0.264521)
							(end 0.254 0.2286)
						)
						(arc
							(start 0.254 -0.2286)
							(mid 0.239121 -0.264521)
							(end 0.2032 -0.2794)
						)
					)
					(width 0)
					(fill yes)
				)
			)
		)
	)
	(footprint ""
		(layer "F.Cu")
		(at 31.4198 -36.2204)
		(property "Reference" "R277"
			(at 0 0 0)
			(layer "F.SilkS")
			(hide yes)
			(effects
				(font
					(size 1.27 1.27)
				)
			)
		)
		(property "Value" "51R2F-2-GP"
			(at 0.064008 -3.993896 0)
			(unlocked yes)
			(layer "F.Fab")
			(hide yes)
			(effects
				(font
					(size 1.016 1.016)
					(thickness 0.1524)
				)
			)
		)
		(property "Device Type" "R402H16"
			(at 0.064008 -5.517896 0)
			(unlocked yes)
			(layer "F.Fab")
			(hide yes)
			(effects
				(font
					(size 1.016 1.016)
					(thickness 0.1524)
				)
			)
		)
		(duplicate_pad_numbers_are_jumpers no)
		(fp_rect
			(start -0.381 0.8382)
			(end 0.381 -0.8382)
			(stroke
				(width 0)
				(type default)
			)
			(fill no)
			(layer "F.CrtYd")
		)
		(fp_rect
			(start -0.381 0.8382)
			(end 0.381 -0.8382)
			(stroke
				(width 0)
				(type default)
			)
			(fill no)
			(layer "F.Fab")
		)
		(pad "1" smd custom
			(at 0 -0.4318)
			(size 0.127 0.127)
			(layers "F.Cu" "F.Mask" "F.Paste")
			(net "P1V0_STBY")
			(options
				(clearance outline)
				(anchor circle)
			)
			(primitives
				(gr_poly
					(pts
						(arc
							(start -0.2032 -0.2794)
							(mid -0.239121 -0.264521)
							(end -0.254 -0.2286)
						)
						(arc
							(start -0.254 0.2286)
							(mid -0.239121 0.264521)
							(end -0.2032 0.2794)
						)
						(arc
							(start 0.2032 0.2794)
							(mid 0.239121 0.264521)
							(end 0.254 0.2286)
						)
						(arc
							(start 0.254 -0.2286)
							(mid 0.239121 -0.264521)
							(end 0.2032 -0.2794)
						)
					)
					(width 0)
					(fill yes)
				)
			)
		)
		(pad "2" smd custom
			(at 0 0.4318)
			(size 0.127 0.127)
			(layers "F.Cu" "F.Mask" "F.Paste")
			(net "XDP_SOC_CPU_TDI")
			(options
				(clearance outline)
				(anchor circle)
			)
			(primitives
				(gr_poly
					(pts
						(arc
							(start -0.2032 -0.2794)
							(mid -0.239121 -0.264521)
							(end -0.254 -0.2286)
						)
						(arc
							(start -0.254 0.2286)
							(mid -0.239121 0.264521)
							(end -0.2032 0.2794)
						)
						(arc
							(start 0.2032 0.2794)
							(mid 0.239121 0.264521)
							(end 0.254 0.2286)
						)
						(arc
							(start 0.254 -0.2286)
							(mid 0.239121 -0.264521)
							(end 0.2032 -0.2794)
						)
					)
					(width 0)
					(fill yes)
				)
			)
		)
	)
	(footprint ""
		(layer "F.Cu")
		(at 172.847 -42.164 90)
		(property "Reference" "PU17"
			(at 0 0 90)
			(layer "F.SilkS")
			(hide yes)
			(effects
				(font
					(size 1.27 1.27)
				)
			)
		)
		(property "Value" "TPS79301DBVR-GP"
			(at -2.914396 -2.576322 90)
			(unlocked yes)
			(layer "F.Fab")
			(hide yes)
			(effects
				(font
					(size 1.016 1.016)
					(thickness 0.1524)
				)
			)
		)
		(property "Device Type" "SOT-6-1H58"
			(at -2.914396 -1.052322 90)
			(unlocked yes)
			(layer "F.Fab")
			(hide yes)
			(effects
				(font
					(size 1.016 1.016)
					(thickness 0.1524)
				)
			)
		)
		(duplicate_pad_numbers_are_jumpers no)
		(fp_line
			(start 1.2573 -0.4064)
			(end -1.7018 -0.4064)
			(stroke
				(width 0.1524)
				(type default)
			)
			(layer "F.SilkS")
		)
		(fp_line
			(start -1.7018 -0.4064)
			(end -1.7018 0.4064)
			(stroke
				(width 0.1524)
				(type default)
			)
			(layer "F.SilkS")
		)
		(fp_line
			(start -1.7018 -0.3175)
			(end -1.397 -0.0127)
			(stroke
				(width 0.1524)
				(type default)
			)
			(layer "F.SilkS")
		)
		(fp_line
			(start -1.397 -0.0127)
			(end -1.7018 0.2921)
			(stroke
				(width 0.1524)
				(type default)
			)
			(layer "F.SilkS")
		)
		(fp_line
			(start 1.2573 0.4064)
			(end 1.2573 -0.4064)
			(stroke
				(width 0.1524)
				(type default)
			)
			(layer "F.SilkS")
		)
		(fp_line
			(start -1.6637 0.4064)
			(end -1.6637 1.5748)
			(stroke
				(width 0.254)
				(type default)
			)
			(layer "F.SilkS")
		)
		(fp_line
			(start -1.7018 0.4064)
			(end 1.2573 0.4064)
			(stroke
				(width 0.1524)
				(type default)
			)
			(layer "F.SilkS")
		)
		(fp_poly
			(pts
				(xy -1.2573 0.4064) (xy 1.2573 0.4064) (xy 1.2573 -0.4064) (xy -1.2573 -0.4064)
			)
			(stroke
				(width 0)
				(type default)
			)
			(fill yes)
			(layer "F.SilkS")
		)
		(fp_poly
			(pts
				(xy -1.7018 1.053846) (xy -1.7018 -1.053846) (xy -1.38176 -1.053846) (xy -1.38176 -1.780794) (xy 1.38176 -1.780794)
				(xy 1.38176 -1.053846) (xy 1.7018 -1.053846) (xy 1.7018 1.053846) (xy 1.38176 1.053846) (xy 1.38176 1.780794)
				(xy -1.38176 1.780794) (xy -1.38176 1.053846)
			)
			(stroke
				(width 0)
				(type default)
			)
			(fill no)
			(layer "F.CrtYd")
		)
		(fp_poly
			(pts
				(xy -1.7018 1.053846) (xy -1.7018 -1.053846) (xy -1.38176 -1.053846) (xy -1.38176 -1.780794) (xy 1.38176 -1.780794)
				(xy 1.38176 -1.053846) (xy 1.7018 -1.053846) (xy 1.7018 1.053846) (xy 1.38176 1.053846) (xy 1.38176 1.780794)
				(xy -1.38176 1.780794) (xy -1.38176 1.053846)
			)
			(stroke
				(width 0)
				(type default)
			)
			(fill no)
			(layer "F.Fab")
		)
		(pad "1" smd rect
			(at -0.94996 1.183894 90)
			(size 0.6096 0.9398)
			(layers "F.Cu" "F.Mask" "F.Paste")
			(net "P3V3_STBY")
		)
		(pad "2" smd rect
			(at 0 1.183894 90)
			(size 0.6096 0.9398)
			(layers "F.Cu" "F.Mask" "F.Paste")
			(net "GND")
		)
		(pad "3" smd rect
			(at 0.94996 1.183894 90)
			(size 0.6096 0.9398)
			(layers "F.Cu" "F.Mask" "F.Paste")
			(net "P3V3_STBY")
		)
		(pad "4" smd rect
			(at 0.94996 -1.183894 90)
			(size 0.6096 0.9398)
			(layers "F.Cu" "F.Mask" "F.Paste")
			(net "P2V5_STBY_BYPASS")
		)
		(pad "5" smd rect
			(at 0 -1.183894 90)
			(size 0.6096 0.9398)
			(layers "F.Cu" "F.Mask" "F.Paste")
			(net "P2V5_STBY_FB")
		)
		(pad "6" smd rect
			(at -0.94996 -1.183894 90)
			(size 0.6096 0.9398)
			(layers "F.Cu" "F.Mask" "F.Paste")
			(net "P2V5_STBY_OUT")
		)
	)
	(footprint ""
		(layer "F.Cu")
		(at 186.817 -45.974 180)
		(property "Reference" "R219"
			(at 0 0 180)
			(layer "F.SilkS")
			(hide yes)
			(effects
				(font
					(size 1.27 1.27)
				)
			)
		)
		(property "Value" "100R2F-L1-GP-U"
			(at 0.064008 -3.993896 180)
			(unlocked yes)
			(layer "F.Fab")
			(hide yes)
			(effects
				(font
					(size 1.016 1.016)
					(thickness 0.1524)
				)
			)
		)
		(property "Device Type" "R402H14"
			(at 0.064008 -5.517896 180)
			(unlocked yes)
			(layer "F.Fab")
			(hide yes)
			(effects
				(font
					(size 1.016 1.016)
					(thickness 0.1524)
				)
			)
		)
		(duplicate_pad_numbers_are_jumpers no)
		(fp_rect
			(start -0.381 0.8382)
			(end 0.381 -0.8382)
			(stroke
				(width 0)
				(type default)
			)
			(fill no)
			(layer "F.CrtYd")
		)
		(fp_rect
			(start -0.381 0.8382)
			(end 0.381 -0.8382)
			(stroke
				(width 0)
				(type default)
			)
			(fill no)
			(layer "F.Fab")
		)
		(pad "1" smd custom
			(at 0 -0.4318 180)
			(size 0.127 0.127)
			(layers "F.Cu" "F.Mask" "F.Paste")
			(net "PV_VDDR")
			(options
				(clearance outline)
				(anchor circle)
			)
			(primitives
				(gr_poly
					(pts
						(arc
							(start -0.2032 -0.2794)
							(mid -0.239121 -0.264521)
							(end -0.254 -0.2286)
						)
						(arc
							(start -0.254 0.2286)
							(mid -0.239121 0.264521)
							(end -0.2032 0.2794)
						)
						(arc
							(start 0.2032 0.2794)
							(mid 0.239121 0.264521)
							(end 0.254 0.2286)
						)
						(arc
							(start 0.254 -0.2286)
							(mid 0.239121 -0.264521)
							(end 0.2032 -0.2794)
						)
					)
					(width 0)
					(fill yes)
				)
			)
		)
		(pad "2" smd custom
			(at 0 0.4318 180)
			(size 0.127 0.127)
			(layers "F.Cu" "F.Mask" "F.Paste")
			(net "PV_VDDR_VREF_B_FB")
			(options
				(clearance outline)
				(anchor circle)
			)
			(primitives
				(gr_poly
					(pts
						(arc
							(start -0.2032 -0.2794)
							(mid -0.239121 -0.264521)
							(end -0.254 -0.2286)
						)
						(arc
							(start -0.254 0.2286)
							(mid -0.239121 0.264521)
							(end -0.2032 0.2794)
						)
						(arc
							(start 0.2032 0.2794)
							(mid 0.239121 0.264521)
							(end 0.254 0.2286)
						)
						(arc
							(start 0.254 -0.2286)
							(mid 0.239121 -0.264521)
							(end 0.2032 -0.2794)
						)
					)
					(width 0)
					(fill yes)
				)
			)
		)
	)
	(footprint ""
		(layer "F.Cu")
		(at 188.087 -50.673 180)
		(property "Reference" "R208"
			(at 0 0 180)
			(layer "F.SilkS")
			(hide yes)
			(effects
				(font
					(size 1.27 1.27)
				)
			)
		)
		(property "Value" "12K1R2F-L1-GP"
			(at 0.064008 -3.993896 180)
			(unlocked yes)
			(layer "F.Fab")
			(hide yes)
			(effects
				(font
					(size 1.016 1.016)
					(thickness 0.1524)
				)
			)
		)
		(property "Device Type" "R402H16"
			(at 0.064008 -5.517896 180)
			(unlocked yes)
			(layer "F.Fab")
			(hide yes)
			(effects
				(font
					(size 1.016 1.016)
					(thickness 0.1524)
				)
			)
		)
		(duplicate_pad_numbers_are_jumpers no)
		(fp_rect
			(start -0.381 0.8382)
			(end 0.381 -0.8382)
			(stroke
				(width 0)
				(type default)
			)
			(fill no)
			(layer "F.CrtYd")
		)
		(fp_rect
			(start -0.381 0.8382)
			(end 0.381 -0.8382)
			(stroke
				(width 0)
				(type default)
			)
			(fill no)
			(layer "F.Fab")
		)
		(pad "1" smd custom
			(at 0 -0.4318 180)
			(size 0.127 0.127)
			(layers "F.Cu" "F.Mask" "F.Paste")
			(net "PV_VDDR_VREF_RW")
			(options
				(clearance outline)
				(anchor circle)
			)
			(primitives
				(gr_poly
					(pts
						(arc
							(start -0.2032 -0.2794)
							(mid -0.239121 -0.264521)
							(end -0.254 -0.2286)
						)
						(arc
							(start -0.254 0.2286)
							(mid -0.239121 0.264521)
							(end -0.2032 0.2794)
						)
						(arc
							(start 0.2032 0.2794)
							(mid 0.239121 0.264521)
							(end 0.254 0.2286)
						)
						(arc
							(start 0.254 -0.2286)
							(mid 0.239121 -0.264521)
							(end 0.2032 -0.2794)
						)
					)
					(width 0)
					(fill yes)
				)
			)
		)
		(pad "2" smd custom
			(at 0 0.4318 180)
			(size 0.127 0.127)
			(layers "F.Cu" "F.Mask" "F.Paste")
			(net "GND")
			(options
				(clearance outline)
				(anchor circle)
			)
			(primitives
				(gr_poly
					(pts
						(arc
							(start -0.2032 -0.2794)
							(mid -0.239121 -0.264521)
							(end -0.254 -0.2286)
						)
						(arc
							(start -0.254 0.2286)
							(mid -0.239121 0.264521)
							(end -0.2032 0.2794)
						)
						(arc
							(start 0.2032 0.2794)
							(mid 0.239121 0.264521)
							(end 0.254 0.2286)
						)
						(arc
							(start 0.254 -0.2286)
							(mid 0.239121 -0.264521)
							(end 0.2032 -0.2794)
						)
					)
					(width 0)
					(fill yes)
				)
			)
		)
	)
	(footprint ""
		(layer "F.Cu")
		(at 151.257 -50.927 180)
		(property "Reference" "R484"
			(at 0 0 180)
			(layer "F.SilkS")
			(hide yes)
			(effects
				(font
					(size 1.27 1.27)
				)
			)
		)
		(property "Value" "10KR2F-2-GP"
			(at 1.7907 -1.1176 180)
			(unlocked yes)
			(layer "F.Fab")
			(hide yes)
			(effects
				(font
					(size 1.016 1.016)
					(thickness 0.1524)
				)
			)
		)
		(property "Device Type" "R402H16"
			(at 1.7907 -2.6416 180)
			(unlocked yes)
			(layer "F.Fab")
			(hide yes)
			(effects
				(font
					(size 1.016 1.016)
					(thickness 0.1524)
				)
			)
		)
		(duplicate_pad_numbers_are_jumpers no)
		(fp_rect
			(start -0.381 0.8382)
			(end 0.381 -0.8382)
			(stroke
				(width 0)
				(type default)
			)
			(fill no)
			(layer "F.CrtYd")
		)
		(fp_rect
			(start -0.381 0.8382)
			(end 0.381 -0.8382)
			(stroke
				(width 0)
				(type default)
			)
			(fill no)
			(layer "F.Fab")
		)
		(pad "1" smd custom
			(at 0 -0.4318 180)
			(size 0.127 0.127)
			(layers "F.Cu" "F.Mask" "F.Paste")
			(net "BUS_SW_OE#")
			(options
				(clearance outline)
				(anchor circle)
			)
			(primitives
				(gr_poly
					(pts
						(arc
							(start -0.2032 -0.2794)
							(mid -0.239121 -0.264521)
							(end -0.254 -0.2286)
						)
						(arc
							(start -0.254 0.2286)
							(mid -0.239121 0.264521)
							(end -0.2032 0.2794)
						)
						(arc
							(start 0.2032 0.2794)
							(mid 0.239121 0.264521)
							(end 0.254 0.2286)
						)
						(arc
							(start 0.254 -0.2286)
							(mid 0.239121 -0.264521)
							(end 0.2032 -0.2794)
						)
					)
					(width 0)
					(fill yes)
				)
			)
		)
		(pad "2" smd custom
			(at 0 0.4318 180)
			(size 0.127 0.127)
			(layers "F.Cu" "F.Mask" "F.Paste")
			(net "GND")
			(options
				(clearance outline)
				(anchor circle)
			)
			(primitives
				(gr_poly
					(pts
						(arc
							(start -0.2032 -0.2794)
							(mid -0.239121 -0.264521)
							(end -0.254 -0.2286)
						)
						(arc
							(start -0.254 0.2286)
							(mid -0.239121 0.264521)
							(end -0.2032 0.2794)
						)
						(arc
							(start 0.2032 0.2794)
							(mid 0.239121 0.264521)
							(end 0.254 0.2286)
						)
						(arc
							(start 0.254 -0.2286)
							(mid 0.239121 -0.264521)
							(end 0.2032 -0.2794)
						)
					)
					(width 0)
					(fill yes)
				)
			)
		)
	)
	(footprint ""
		(layer "F.Cu")
		(at 64.2112 -26.8732 -90)
		(property "Reference" "Q9"
			(at 0 0 270)
			(layer "F.SilkS")
			(hide yes)
			(effects
				(font
					(size 1.27 1.27)
				)
			)
		)
		(property "Value" "2N7002A-7-GP"
			(at 0.127 -8.9662 270)
			(unlocked yes)
			(layer "F.Fab")
			(hide yes)
			(effects
				(font
					(size 1.016 1.016)
					(thickness 0.1524)
				)
			)
		)
		(property "Device Type" "SOT23DGS2D4H48"
			(at 0.127 -10.4902 270)
			(unlocked yes)
			(layer "F.Fab")
			(hide yes)
			(effects
				(font
					(size 1.016 1.016)
					(thickness 0.1524)
				)
			)
		)
		(duplicate_pad_numbers_are_jumpers no)
		(fp_line
			(start -1.7145 0.4445)
			(end 1.7145 0.4445)
			(stroke
				(width 0.1524)
				(type default)
			)
			(layer "F.SilkS")
		)
		(fp_line
			(start 1.7145 0.4445)
			(end 1.7145 -0.4445)
			(stroke
				(width 0.1524)
				(type default)
			)
			(layer "F.SilkS")
		)
		(fp_line
			(start -1.7145 -0.4445)
			(end -1.7145 0.4445)
			(stroke
				(width 0.1524)
				(type default)
			)
			(layer "F.SilkS")
		)
		(fp_line
			(start 1.7145 -0.4445)
			(end -1.7145 -0.4445)
			(stroke
				(width 0.1524)
				(type default)
			)
			(layer "F.SilkS")
		)
		(fp_poly
			(pts
				(xy -1.4224 1.5621) (xy -1.4224 0.9017) (xy -1.7145 0.9017) (xy -1.7145 -0.9017) (xy -0.4699 -0.9017)
				(xy -0.4699 -1.5621) (xy 0.4699 -1.5621) (xy 0.4699 -0.9017) (xy 1.7145 -0.9017) (xy 1.7145 0.9017)
				(xy 1.4224 0.9017) (xy 1.4224 1.5621) (xy 0.4826 1.5621) (xy 0.4826 0.9017) (xy -0.4826 0.9017)
				(xy -0.4826 1.5621)
			)
			(stroke
				(width 0)
				(type default)
			)
			(fill no)
			(layer "F.CrtYd")
		)
		(fp_poly
			(pts
				(xy -1.4224 1.5621) (xy -1.4224 0.9017) (xy -1.7145 0.9017) (xy -1.7145 -0.9017) (xy -0.4699 -0.9017)
				(xy -0.4699 -1.5621) (xy 0.4699 -1.5621) (xy 0.4699 -0.9017) (xy 1.7145 -0.9017) (xy 1.7145 0.9017)
				(xy 1.4224 0.9017) (xy 1.4224 1.5621) (xy 0.4826 1.5621) (xy 0.4826 0.9017) (xy -0.4826 0.9017)
				(xy -0.4826 1.5621)
			)
			(stroke
				(width 0)
				(type default)
			)
			(fill no)
			(layer "F.Fab")
		)
		(pad "D" smd custom
			(at 0 -1.069086 270)
			(size 0.17145 0.17145)
			(layers "F.Cu" "F.Mask" "F.Paste")
			(net "SW_P1V8_EN_LV")
			(options
				(clearance outline)
				(anchor circle)
			)
			(primitives
				(gr_poly
					(pts
						(arc
							(start -0.1397 0.3683)
							(mid -0.283384 0.308784)
							(end -0.3429 0.1651)
						)
						(arc
							(start -0.3429 -0.1651)
							(mid -0.283384 -0.308784)
							(end -0.1397 -0.3683)
						)
						(arc
							(start 0.1397 -0.3683)
							(mid 0.283384 -0.308784)
							(end 0.3429 -0.1651)
						)
						(arc
							(start 0.3429 0.1651)
							(mid 0.283384 0.308784)
							(end 0.1397 0.3683)
						)
					)
					(width 0)
					(fill yes)
				)
			)
		)
		(pad "G" smd custom
			(at -0.94996 1.069086 270)
			(size 0.17145 0.17145)
			(layers "F.Cu" "F.Mask" "F.Paste")
			(net "SW_P1V8_EN_G")
			(options
				(clearance outline)
				(anchor circle)
			)
			(primitives
				(gr_poly
					(pts
						(arc
							(start -0.1397 0.3683)
							(mid -0.283384 0.308784)
							(end -0.3429 0.1651)
						)
						(arc
							(start -0.3429 -0.1651)
							(mid -0.283384 -0.308784)
							(end -0.1397 -0.3683)
						)
						(arc
							(start 0.1397 -0.3683)
							(mid 0.283384 -0.308784)
							(end 0.3429 -0.1651)
						)
						(arc
							(start 0.3429 0.1651)
							(mid 0.283384 0.308784)
							(end 0.1397 0.3683)
						)
					)
					(width 0)
					(fill yes)
				)
			)
		)
		(pad "S" smd custom
			(at 0.94996 1.069086 270)
			(size 0.17145 0.17145)
			(layers "F.Cu" "F.Mask" "F.Paste")
			(net "SW_P1V8_EN_S")
			(options
				(clearance outline)
				(anchor circle)
			)
			(primitives
				(gr_poly
					(pts
						(arc
							(start -0.1397 0.3683)
							(mid -0.283384 0.308784)
							(end -0.3429 0.1651)
						)
						(arc
							(start -0.3429 -0.1651)
							(mid -0.283384 -0.308784)
							(end -0.1397 -0.3683)
						)
						(arc
							(start 0.1397 -0.3683)
							(mid 0.283384 -0.308784)
							(end 0.3429 -0.1651)
						)
						(arc
							(start 0.3429 0.1651)
							(mid 0.283384 0.308784)
							(end 0.1397 0.3683)
						)
					)
					(width 0)
					(fill yes)
				)
			)
		)
	)
	(footprint ""
		(layer "F.Cu")
		(at 23.749 -48.895 90)
		(property "Reference" "PR81"
			(at 0 0 90)
			(layer "F.SilkS")
			(hide yes)
			(effects
				(font
					(size 1.27 1.27)
				)
			)
		)
		(property "Value" "10R2F-L-GP"
			(at 1.7907 -1.1176 90)
			(unlocked yes)
			(layer "F.Fab")
			(hide yes)
			(effects
				(font
					(size 1.016 1.016)
					(thickness 0.1524)
				)
			)
		)
		(property "Device Type" "R402H14"
			(at 1.7907 -2.6416 90)
			(unlocked yes)
			(layer "F.Fab")
			(hide yes)
			(effects
				(font
					(size 1.016 1.016)
					(thickness 0.1524)
				)
			)
		)
		(duplicate_pad_numbers_are_jumpers no)
		(fp_rect
			(start -0.381 0.8382)
			(end 0.381 -0.8382)
			(stroke
				(width 0)
				(type default)
			)
			(fill no)
			(layer "F.CrtYd")
		)
		(fp_rect
			(start -0.381 0.8382)
			(end 0.381 -0.8382)
			(stroke
				(width 0)
				(type default)
			)
			(fill no)
			(layer "F.Fab")
		)
		(pad "1" smd custom
			(at 0 -0.4318 90)
			(size 0.127 0.127)
			(layers "F.Cu" "F.Mask" "F.Paste")
			(net "VR_PVCCP_ISUMN_R2")
			(options
				(clearance outline)
				(anchor circle)
			)
			(primitives
				(gr_poly
					(pts
						(arc
							(start -0.2032 -0.2794)
							(mid -0.239121 -0.264521)
							(end -0.254 -0.2286)
						)
						(arc
							(start -0.254 0.2286)
							(mid -0.239121 0.264521)
							(end -0.2032 0.2794)
						)
						(arc
							(start 0.2032 0.2794)
							(mid 0.239121 0.264521)
							(end 0.254 0.2286)
						)
						(arc
							(start 0.254 -0.2286)
							(mid 0.239121 -0.264521)
							(end 0.2032 -0.2794)
						)
					)
					(width 0)
					(fill yes)
				)
			)
		)
		(pad "2" smd custom
			(at 0 0.4318 90)
			(size 0.127 0.127)
			(layers "F.Cu" "F.Mask" "F.Paste")
			(net "VR_PVCCP_ISUMN")
			(options
				(clearance outline)
				(anchor circle)
			)
			(primitives
				(gr_poly
					(pts
						(arc
							(start -0.2032 -0.2794)
							(mid -0.239121 -0.264521)
							(end -0.254 -0.2286)
						)
						(arc
							(start -0.254 0.2286)
							(mid -0.239121 0.264521)
							(end -0.2032 0.2794)
						)
						(arc
							(start 0.2032 0.2794)
							(mid 0.239121 0.264521)
							(end 0.254 0.2286)
						)
						(arc
							(start 0.254 -0.2286)
							(mid 0.239121 -0.264521)
							(end 0.2032 -0.2794)
						)
					)
					(width 0)
					(fill yes)
				)
			)
		)
	)
	(footprint ""
		(layer "F.Cu")
		(at 105.8926 -20.701 90)
		(property "Reference" "R162"
			(at 0 0 90)
			(layer "F.SilkS")
			(hide yes)
			(effects
				(font
					(size 1.27 1.27)
				)
			)
		)
		(property "Value" "100KR2F-L1-GP"
			(at 0.064008 -3.993896 90)
			(unlocked yes)
			(layer "F.Fab")
			(hide yes)
			(effects
				(font
					(size 1.016 1.016)
					(thickness 0.1524)
				)
			)
		)
		(property "Device Type" "R402H16"
			(at 0.064008 -5.517896 90)
			(unlocked yes)
			(layer "F.Fab")
			(hide yes)
			(effects
				(font
					(size 1.016 1.016)
					(thickness 0.1524)
				)
			)
		)
		(duplicate_pad_numbers_are_jumpers no)
		(fp_rect
			(start -0.381 0.8382)
			(end 0.381 -0.8382)
			(stroke
				(width 0)
				(type default)
			)
			(fill no)
			(layer "F.CrtYd")
		)
		(fp_rect
			(start -0.381 0.8382)
			(end 0.381 -0.8382)
			(stroke
				(width 0)
				(type default)
			)
			(fill no)
			(layer "F.Fab")
		)
		(pad "1" smd custom
			(at 0 -0.4318 90)
			(size 0.127 0.127)
			(layers "F.Cu" "F.Mask" "F.Paste")
			(net "GND")
			(options
				(clearance outline)
				(anchor circle)
			)
			(primitives
				(gr_poly
					(pts
						(arc
							(start -0.2032 -0.2794)
							(mid -0.239121 -0.264521)
							(end -0.254 -0.2286)
						)
						(arc
							(start -0.254 0.2286)
							(mid -0.239121 0.264521)
							(end -0.2032 0.2794)
						)
						(arc
							(start 0.2032 0.2794)
							(mid 0.239121 0.264521)
							(end 0.254 0.2286)
						)
						(arc
							(start 0.254 -0.2286)
							(mid 0.239121 -0.264521)
							(end 0.2032 -0.2794)
						)
					)
					(width 0)
					(fill yes)
				)
			)
		)
		(pad "2" smd custom
			(at 0 0.4318 90)
			(size 0.127 0.127)
			(layers "F.Cu" "F.Mask" "F.Paste")
			(net "M_B_R_RESET#")
			(options
				(clearance outline)
				(anchor circle)
			)
			(primitives
				(gr_poly
					(pts
						(arc
							(start -0.2032 -0.2794)
							(mid -0.239121 -0.264521)
							(end -0.254 -0.2286)
						)
						(arc
							(start -0.254 0.2286)
							(mid -0.239121 0.264521)
							(end -0.2032 0.2794)
						)
						(arc
							(start 0.2032 0.2794)
							(mid 0.239121 0.264521)
							(end 0.254 0.2286)
						)
						(arc
							(start 0.254 -0.2286)
							(mid 0.239121 -0.264521)
							(end 0.2032 -0.2794)
						)
					)
					(width 0)
					(fill yes)
				)
			)
		)
	)
	(footprint ""
		(layer "F.Cu")
		(at 178.689 -48.895 90)
		(property "Reference" "C84"
			(at 0 0 90)
			(layer "F.SilkS")
			(hide yes)
			(effects
				(font
					(size 1.27 1.27)
				)
			)
		)
		(property "Value" "SCD1U16V2KX-3GP"
			(at 1.1811 -2.7051 90)
			(unlocked yes)
			(layer "F.Fab")
			(hide yes)
			(effects
				(font
					(size 1.016 1.016)
					(thickness 0.1524)
				)
			)
		)
		(property "Device Type" "C402H22"
			(at 1.1811 -4.2291 90)
			(unlocked yes)
			(layer "F.Fab")
			(hide yes)
			(effects
				(font
					(size 1.016 1.016)
					(thickness 0.1524)
				)
			)
		)
		(duplicate_pad_numbers_are_jumpers no)
		(fp_rect
			(start -0.381 0.7366)
			(end 0.381 -0.7366)
			(stroke
				(width 0)
				(type default)
			)
			(fill no)
			(layer "F.CrtYd")
		)
		(fp_rect
			(start -0.381 0.7366)
			(end 0.381 -0.7366)
			(stroke
				(width 0)
				(type default)
			)
			(fill no)
			(layer "F.Fab")
		)
		(pad "1" smd custom
			(at 0 -0.4572 90)
			(size 0.1143 0.1143)
			(layers "F.Cu" "F.Mask" "F.Paste")
			(net "P3V3_STBY")
			(options
				(clearance outline)
				(anchor circle)
			)
			(primitives
				(gr_poly
					(pts
						(arc
							(start -0.254 -0.1778)
							(mid -0.239121 -0.213721)
							(end -0.2032 -0.2286)
						)
						(arc
							(start 0.2032 -0.2286)
							(mid 0.239121 -0.213721)
							(end 0.254 -0.1778)
						)
						(arc
							(start 0.254 0.1778)
							(mid 0.239121 0.213721)
							(end 0.2032 0.2286)
						)
						(arc
							(start -0.2032 0.2286)
							(mid -0.239121 0.213721)
							(end -0.254 0.1778)
						)
					)
					(width 0)
					(fill yes)
				)
			)
		)
		(pad "2" smd custom
			(at 0 0.4572 90)
			(size 0.1143 0.1143)
			(layers "F.Cu" "F.Mask" "F.Paste")
			(net "GND")
			(options
				(clearance outline)
				(anchor circle)
			)
			(primitives
				(gr_poly
					(pts
						(arc
							(start -0.254 -0.1778)
							(mid -0.239121 -0.213721)
							(end -0.2032 -0.2286)
						)
						(arc
							(start 0.2032 -0.2286)
							(mid 0.239121 -0.213721)
							(end 0.254 -0.1778)
						)
						(arc
							(start 0.254 0.1778)
							(mid 0.239121 0.213721)
							(end 0.2032 0.2286)
						)
						(arc
							(start -0.2032 0.2286)
							(mid -0.239121 0.213721)
							(end -0.254 0.1778)
						)
					)
					(width 0)
					(fill yes)
				)
			)
		)
	)
	(footprint ""
		(layer "F.Cu")
		(at 54.864 -42.164)
		(property "Reference" "C19"
			(at 0 0 0)
			(layer "F.SilkS")
			(hide yes)
			(effects
				(font
					(size 1.27 1.27)
				)
			)
		)
		(property "Value" "SCD47U25V2KX-GP"
			(at 1.8923 -1.2065 0)
			(unlocked yes)
			(layer "F.Fab")
			(hide yes)
			(effects
				(font
					(size 1.016 1.016)
					(thickness 0.1524)
				)
			)
		)
		(property "Device Type" "C402H24"
			(at 1.8923 -2.7305 0)
			(unlocked yes)
			(layer "F.Fab")
			(hide yes)
			(effects
				(font
					(size 1.016 1.016)
					(thickness 0.1524)
				)
			)
		)
		(duplicate_pad_numbers_are_jumpers no)
		(fp_rect
			(start -0.381 0.7366)
			(end 0.381 -0.7366)
			(stroke
				(width 0)
				(type default)
			)
			(fill no)
			(layer "F.CrtYd")
		)
		(fp_rect
			(start -0.381 0.7366)
			(end 0.381 -0.7366)
			(stroke
				(width 0)
				(type default)
			)
			(fill no)
			(layer "F.Fab")
		)
		(pad "1" smd custom
			(at 0 -0.4572)
			(size 0.1143 0.1143)
			(layers "F.Cu" "F.Mask" "F.Paste")
			(net "SW_P3V3_EN_LV_D")
			(options
				(clearance outline)
				(anchor circle)
			)
			(primitives
				(gr_poly
					(pts
						(arc
							(start -0.254 -0.1778)
							(mid -0.239121 -0.213721)
							(end -0.2032 -0.2286)
						)
						(arc
							(start 0.2032 -0.2286)
							(mid 0.239121 -0.213721)
							(end 0.254 -0.1778)
						)
						(arc
							(start 0.254 0.1778)
							(mid 0.239121 0.213721)
							(end 0.2032 0.2286)
						)
						(arc
							(start -0.2032 0.2286)
							(mid -0.239121 0.213721)
							(end -0.254 0.1778)
						)
					)
					(width 0)
					(fill yes)
				)
			)
		)
		(pad "2" smd custom
			(at 0 0.4572)
			(size 0.1143 0.1143)
			(layers "F.Cu" "F.Mask" "F.Paste")
			(net "P3V3")
			(options
				(clearance outline)
				(anchor circle)
			)
			(primitives
				(gr_poly
					(pts
						(arc
							(start -0.254 -0.1778)
							(mid -0.239121 -0.213721)
							(end -0.2032 -0.2286)
						)
						(arc
							(start 0.2032 -0.2286)
							(mid 0.239121 -0.213721)
							(end 0.254 -0.1778)
						)
						(arc
							(start 0.254 0.1778)
							(mid 0.239121 0.213721)
							(end 0.2032 0.2286)
						)
						(arc
							(start -0.2032 0.2286)
							(mid -0.239121 0.213721)
							(end -0.254 0.1778)
						)
					)
					(width 0)
					(fill yes)
				)
			)
		)
	)
	(footprint ""
		(layer "F.Cu")
		(at 197.4596 -65.0748 -90)
		(property "Reference" "PC171"
			(at 0 0 270)
			(layer "F.SilkS")
			(hide yes)
			(effects
				(font
					(size 1.27 1.27)
				)
			)
		)
		(property "Value" "SC22U6D3V5MX-2GP"
			(at 0 -4.9022 270)
			(unlocked yes)
			(layer "F.Fab")
			(hide yes)
			(effects
				(font
					(size 1.016 1.016)
					(thickness 0.1524)
				)
			)
		)
		(property "Device Type" "C805H58"
			(at 0 -6.8072 270)
			(unlocked yes)
			(layer "F.Fab")
			(hide yes)
			(effects
				(font
					(size 1.016 1.016)
					(thickness 0.1524)
				)
			)
		)
		(duplicate_pad_numbers_are_jumpers no)
		(fp_line
			(start 0.6096 0)
			(end -0.6096 0)
			(stroke
				(width 0.3048)
				(type default)
			)
			(layer "F.SilkS")
		)
		(fp_poly
			(pts
				(xy -0.9017 1.4351) (xy 0.9017 1.4351) (xy 0.9017 -1.4351) (xy -0.9017 -1.4351)
			)
			(stroke
				(width 0)
				(type default)
			)
			(fill no)
			(layer "F.CrtYd")
		)
		(fp_poly
			(pts
				(xy 0.9017 1.4351) (xy 0.9017 -1.4351) (xy -0.9017 -1.4351) (xy -0.9017 1.4351)
			)
			(stroke
				(width 0)
				(type default)
			)
			(fill no)
			(layer "F.Fab")
		)
		(pad "1" smd rect
			(at 0 -0.8382 270)
			(size 1.5494 0.9398)
			(layers "F.Cu" "F.Mask" "F.Paste")
			(net "PV_VDDR")
		)
		(pad "2" smd rect
			(at 0 0.8382 270)
			(size 1.5494 0.9398)
			(layers "F.Cu" "F.Mask" "F.Paste")
			(net "GND")
		)
	)
	(footprint ""
		(layer "F.Cu")
		(at 25.25268 -64.8716 180)
		(property "Reference" "PR13"
			(at 0 0 180)
			(layer "F.SilkS")
			(hide yes)
			(effects
				(font
					(size 1.27 1.27)
				)
			)
		)
		(property "Value" "0R3J-0-U-GP"
			(at -0.0254 -2.0193 180)
			(unlocked yes)
			(layer "F.Fab")
			(hide yes)
			(effects
				(font
					(size 1.016 1.016)
					(thickness 0.1524)
				)
			)
		)
		(property "Device Type" "R603H22"
			(at -0.0254 -3.5433 180)
			(unlocked yes)
			(layer "F.Fab")
			(hide yes)
			(effects
				(font
					(size 1.016 1.016)
					(thickness 0.1524)
				)
			)
		)
		(duplicate_pad_numbers_are_jumpers no)
		(fp_line
			(start 0.4318 0)
			(end 0.2032 0)
			(stroke
				(width 0.2032)
				(type default)
			)
			(layer "F.SilkS")
		)
		(fp_line
			(start -0.2032 0)
			(end -0.4191 0)
			(stroke
				(width 0.2032)
				(type default)
			)
			(layer "F.SilkS")
		)
		(fp_rect
			(start -0.635 1.1811)
			(end 0.635 -1.1811)
			(stroke
				(width 0)
				(type default)
			)
			(fill no)
			(layer "F.CrtYd")
		)
		(fp_rect
			(start -0.635 1.1811)
			(end 0.635 -1.1811)
			(stroke
				(width 0)
				(type default)
			)
			(fill no)
			(layer "F.Fab")
		)
		(pad "1" smd custom
			(at 0 -0.6604 180)
			(size 0.19685 0.19685)
			(layers "F.Cu" "F.Mask" "F.Paste")
			(net "VR_PVNN_GH")
			(options
				(clearance outline)
				(anchor circle)
			)
			(primitives
				(gr_poly
					(pts
						(arc
							(start 0.508 -0.2921)
							(mid 0.478242 -0.363942)
							(end 0.4064 -0.3937)
						)
						(arc
							(start -0.4064 -0.3937)
							(mid -0.478242 -0.363942)
							(end -0.508 -0.2921)
						)
						(arc
							(start -0.508 0.2921)
							(mid -0.478242 0.363942)
							(end -0.4064 0.3937)
						)
						(arc
							(start 0.4064 0.3937)
							(mid 0.478242 0.363942)
							(end 0.508 0.2921)
						)
					)
					(width 0)
					(fill yes)
				)
			)
		)
		(pad "2" smd custom
			(at 0 0.6604 180)
			(size 0.19685 0.19685)
			(layers "F.Cu" "F.Mask" "F.Paste")
			(net "VR_PVNN_GH_R")
			(options
				(clearance outline)
				(anchor circle)
			)
			(primitives
				(gr_poly
					(pts
						(arc
							(start 0.508 -0.2921)
							(mid 0.478242 -0.363942)
							(end 0.4064 -0.3937)
						)
						(arc
							(start -0.4064 -0.3937)
							(mid -0.478242 -0.363942)
							(end -0.508 -0.2921)
						)
						(arc
							(start -0.508 0.2921)
							(mid -0.478242 0.363942)
							(end -0.4064 0.3937)
						)
						(arc
							(start 0.4064 0.3937)
							(mid 0.478242 0.363942)
							(end 0.508 0.2921)
						)
					)
					(width 0)
					(fill yes)
				)
			)
		)
	)
	(footprint ""
		(layer "F.Cu")
		(at 73.66 -26.416 -90)
		(property "Reference" "R358"
			(at 0 0 270)
			(layer "F.SilkS")
			(hide yes)
			(effects
				(font
					(size 1.27 1.27)
				)
			)
		)
		(property "Value" "10KR2F-2-GP"
			(at 0.064008 -3.993896 270)
			(unlocked yes)
			(layer "F.Fab")
			(hide yes)
			(effects
				(font
					(size 1.016 1.016)
					(thickness 0.1524)
				)
			)
		)
		(property "Device Type" "R402H16"
			(at 0.064008 -5.517896 270)
			(unlocked yes)
			(layer "F.Fab")
			(hide yes)
			(effects
				(font
					(size 1.016 1.016)
					(thickness 0.1524)
				)
			)
		)
		(duplicate_pad_numbers_are_jumpers no)
		(fp_rect
			(start -0.381 0.8382)
			(end 0.381 -0.8382)
			(stroke
				(width 0)
				(type default)
			)
			(fill no)
			(layer "F.CrtYd")
		)
		(fp_rect
			(start -0.381 0.8382)
			(end 0.381 -0.8382)
			(stroke
				(width 0)
				(type default)
			)
			(fill no)
			(layer "F.Fab")
		)
		(pad "1" smd custom
			(at 0 -0.4318 270)
			(size 0.127 0.127)
			(layers "F.Cu" "F.Mask" "F.Paste")
			(net "P3V3_CPU")
			(options
				(clearance outline)
				(anchor circle)
			)
			(primitives
				(gr_poly
					(pts
						(arc
							(start -0.2032 -0.2794)
							(mid -0.239121 -0.264521)
							(end -0.254 -0.2286)
						)
						(arc
							(start -0.254 0.2286)
							(mid -0.239121 0.264521)
							(end -0.2032 0.2794)
						)
						(arc
							(start 0.2032 0.2794)
							(mid 0.239121 0.264521)
							(end 0.254 0.2286)
						)
						(arc
							(start 0.254 -0.2286)
							(mid 0.239121 -0.264521)
							(end 0.2032 -0.2794)
						)
					)
					(width 0)
					(fill yes)
				)
			)
		)
		(pad "2" smd custom
			(at 0 0.4318 270)
			(size 0.127 0.127)
			(layers "F.Cu" "F.Mask" "F.Paste")
			(net "CPU_RSMRST#")
			(options
				(clearance outline)
				(anchor circle)
			)
			(primitives
				(gr_poly
					(pts
						(arc
							(start -0.2032 -0.2794)
							(mid -0.239121 -0.264521)
							(end -0.254 -0.2286)
						)
						(arc
							(start -0.254 0.2286)
							(mid -0.239121 0.264521)
							(end -0.2032 0.2794)
						)
						(arc
							(start 0.2032 0.2794)
							(mid 0.239121 0.264521)
							(end 0.254 0.2286)
						)
						(arc
							(start 0.254 -0.2286)
							(mid 0.239121 -0.264521)
							(end 0.2032 -0.2794)
						)
					)
					(width 0)
					(fill yes)
				)
			)
		)
	)
	(footprint ""
		(layer "F.Cu")
		(at 176.403 -57.15 180)
		(property "Reference" "R171"
			(at 0 0 180)
			(layer "F.SilkS")
			(hide yes)
			(effects
				(font
					(size 1.27 1.27)
				)
			)
		)
		(property "Value" "4K7R2F-GP"
			(at 0.064008 -3.993896 180)
			(unlocked yes)
			(layer "F.Fab")
			(hide yes)
			(effects
				(font
					(size 1.016 1.016)
					(thickness 0.1524)
				)
			)
		)
		(property "Device Type" "R402H16"
			(at 0.064008 -5.517896 180)
			(unlocked yes)
			(layer "F.Fab")
			(hide yes)
			(effects
				(font
					(size 1.016 1.016)
					(thickness 0.1524)
				)
			)
		)
		(duplicate_pad_numbers_are_jumpers no)
		(fp_rect
			(start -0.381 0.8382)
			(end 0.381 -0.8382)
			(stroke
				(width 0)
				(type default)
			)
			(fill no)
			(layer "F.CrtYd")
		)
		(fp_rect
			(start -0.381 0.8382)
			(end 0.381 -0.8382)
			(stroke
				(width 0)
				(type default)
			)
			(fill no)
			(layer "F.Fab")
		)
		(pad "1" smd custom
			(at 0 -0.4318 180)
			(size 0.127 0.127)
			(layers "F.Cu" "F.Mask" "F.Paste")
			(net "EEPROM_A0")
			(options
				(clearance outline)
				(anchor circle)
			)
			(primitives
				(gr_poly
					(pts
						(arc
							(start -0.2032 -0.2794)
							(mid -0.239121 -0.264521)
							(end -0.254 -0.2286)
						)
						(arc
							(start -0.254 0.2286)
							(mid -0.239121 0.264521)
							(end -0.2032 0.2794)
						)
						(arc
							(start 0.2032 0.2794)
							(mid 0.239121 0.264521)
							(end 0.254 0.2286)
						)
						(arc
							(start 0.254 -0.2286)
							(mid 0.239121 -0.264521)
							(end 0.2032 -0.2794)
						)
					)
					(width 0)
					(fill yes)
				)
			)
		)
		(pad "2" smd custom
			(at 0 0.4318 180)
			(size 0.127 0.127)
			(layers "F.Cu" "F.Mask" "F.Paste")
			(net "GND")
			(options
				(clearance outline)
				(anchor circle)
			)
			(primitives
				(gr_poly
					(pts
						(arc
							(start -0.2032 -0.2794)
							(mid -0.239121 -0.264521)
							(end -0.254 -0.2286)
						)
						(arc
							(start -0.254 0.2286)
							(mid -0.239121 0.264521)
							(end -0.2032 0.2794)
						)
						(arc
							(start 0.2032 0.2794)
							(mid 0.239121 0.264521)
							(end 0.254 0.2286)
						)
						(arc
							(start 0.254 -0.2286)
							(mid 0.239121 -0.264521)
							(end 0.2032 -0.2794)
						)
					)
					(width 0)
					(fill yes)
				)
			)
		)
	)
	(footprint ""
		(layer "F.Cu")
		(at 15.8496 -59.8932 -90)
		(property "Reference" "PR42"
			(at 0 0 270)
			(layer "F.SilkS")
			(hide yes)
			(effects
				(font
					(size 1.27 1.27)
				)
			)
		)
		(property "Value" "0R2J-2-GP"
			(at 1.7907 -1.1176 270)
			(unlocked yes)
			(layer "F.Fab")
			(hide yes)
			(effects
				(font
					(size 1.016 1.016)
					(thickness 0.1524)
				)
			)
		)
		(property "Device Type" "R402H16"
			(at 1.7907 -2.6416 270)
			(unlocked yes)
			(layer "F.Fab")
			(hide yes)
			(effects
				(font
					(size 1.016 1.016)
					(thickness 0.1524)
				)
			)
		)
		(duplicate_pad_numbers_are_jumpers no)
		(fp_rect
			(start -0.381 0.8382)
			(end 0.381 -0.8382)
			(stroke
				(width 0)
				(type default)
			)
			(fill no)
			(layer "F.CrtYd")
		)
		(fp_rect
			(start -0.381 0.8382)
			(end 0.381 -0.8382)
			(stroke
				(width 0)
				(type default)
			)
			(fill no)
			(layer "F.Fab")
		)
		(pad "1" smd custom
			(at 0 -0.4318 270)
			(size 0.127 0.127)
			(layers "F.Cu" "F.Mask" "F.Paste")
			(net "VR_95831_ALERT_N")
			(options
				(clearance outline)
				(anchor circle)
			)
			(primitives
				(gr_poly
					(pts
						(arc
							(start -0.2032 -0.2794)
							(mid -0.239121 -0.264521)
							(end -0.254 -0.2286)
						)
						(arc
							(start -0.254 0.2286)
							(mid -0.239121 0.264521)
							(end -0.2032 0.2794)
						)
						(arc
							(start 0.2032 0.2794)
							(mid 0.239121 0.264521)
							(end 0.254 0.2286)
						)
						(arc
							(start 0.254 -0.2286)
							(mid 0.239121 -0.264521)
							(end 0.2032 -0.2794)
						)
					)
					(width 0)
					(fill yes)
				)
			)
		)
		(pad "2" smd custom
			(at 0 0.4318 270)
			(size 0.127 0.127)
			(layers "F.Cu" "F.Mask" "F.Paste")
			(net "SVID_CPU_ALERT#")
			(options
				(clearance outline)
				(anchor circle)
			)
			(primitives
				(gr_poly
					(pts
						(arc
							(start -0.2032 -0.2794)
							(mid -0.239121 -0.264521)
							(end -0.254 -0.2286)
						)
						(arc
							(start -0.254 0.2286)
							(mid -0.239121 0.264521)
							(end -0.2032 0.2794)
						)
						(arc
							(start 0.2032 0.2794)
							(mid 0.239121 0.264521)
							(end 0.254 0.2286)
						)
						(arc
							(start 0.254 -0.2286)
							(mid 0.239121 -0.264521)
							(end 0.2032 -0.2794)
						)
					)
					(width 0)
					(fill yes)
				)
			)
		)
	)
	(footprint ""
		(layer "F.Cu")
		(at 163.7792 -48.895 -90)
		(property "Reference" "R494"
			(at 0 0 270)
			(layer "F.SilkS")
			(hide yes)
			(effects
				(font
					(size 1.27 1.27)
				)
			)
		)
		(property "Value" "0R2J-2-GP"
			(at 1.7907 -1.1176 270)
			(unlocked yes)
			(layer "F.Fab")
			(hide yes)
			(effects
				(font
					(size 1.016 1.016)
					(thickness 0.1524)
				)
			)
		)
		(property "Device Type" "R402H16"
			(at 1.7907 -2.6416 270)
			(unlocked yes)
			(layer "F.Fab")
			(hide yes)
			(effects
				(font
					(size 1.016 1.016)
					(thickness 0.1524)
				)
			)
		)
		(duplicate_pad_numbers_are_jumpers no)
		(fp_rect
			(start -0.381 0.8382)
			(end 0.381 -0.8382)
			(stroke
				(width 0)
				(type default)
			)
			(fill no)
			(layer "F.CrtYd")
		)
		(fp_rect
			(start -0.381 0.8382)
			(end 0.381 -0.8382)
			(stroke
				(width 0)
				(type default)
			)
			(fill no)
			(layer "F.Fab")
		)
		(pad "1" smd custom
			(at 0 -0.4318 270)
			(size 0.127 0.127)
			(layers "F.Cu" "F.Mask" "F.Paste")
			(net "JTAG_CPU_PLD_TDO")
			(options
				(clearance outline)
				(anchor circle)
			)
			(primitives
				(gr_poly
					(pts
						(arc
							(start -0.2032 -0.2794)
							(mid -0.239121 -0.264521)
							(end -0.254 -0.2286)
						)
						(arc
							(start -0.254 0.2286)
							(mid -0.239121 0.264521)
							(end -0.2032 0.2794)
						)
						(arc
							(start 0.2032 0.2794)
							(mid 0.239121 0.264521)
							(end 0.254 0.2286)
						)
						(arc
							(start 0.254 -0.2286)
							(mid 0.239121 -0.264521)
							(end 0.2032 -0.2794)
						)
					)
					(width 0)
					(fill yes)
				)
			)
		)
		(pad "2" smd custom
			(at 0 0.4318 270)
			(size 0.127 0.127)
			(layers "F.Cu" "F.Mask" "F.Paste")
			(net "JTAG_PLD_TDO")
			(options
				(clearance outline)
				(anchor circle)
			)
			(primitives
				(gr_poly
					(pts
						(arc
							(start -0.2032 -0.2794)
							(mid -0.239121 -0.264521)
							(end -0.254 -0.2286)
						)
						(arc
							(start -0.254 0.2286)
							(mid -0.239121 0.264521)
							(end -0.2032 0.2794)
						)
						(arc
							(start 0.2032 0.2794)
							(mid 0.239121 0.264521)
							(end 0.254 0.2286)
						)
						(arc
							(start 0.254 -0.2286)
							(mid 0.239121 -0.264521)
							(end 0.2032 -0.2794)
						)
					)
					(width 0)
					(fill yes)
				)
			)
		)
	)
	(footprint ""
		(layer "F.Cu")
		(at 168.275 -48.133 90)
		(property "Reference" "R211"
			(at 0 0 90)
			(layer "F.SilkS")
			(hide yes)
			(effects
				(font
					(size 1.27 1.27)
				)
			)
		)
		(property "Value" "0R2J-2-GP"
			(at 1.7907 -1.1176 90)
			(unlocked yes)
			(layer "F.Fab")
			(hide yes)
			(effects
				(font
					(size 1.016 1.016)
					(thickness 0.1524)
				)
			)
		)
		(property "Device Type" "R402H16"
			(at 1.7907 -2.6416 90)
			(unlocked yes)
			(layer "F.Fab")
			(hide yes)
			(effects
				(font
					(size 1.016 1.016)
					(thickness 0.1524)
				)
			)
		)
		(duplicate_pad_numbers_are_jumpers no)
		(fp_rect
			(start -0.381 0.8382)
			(end 0.381 -0.8382)
			(stroke
				(width 0)
				(type default)
			)
			(fill no)
			(layer "F.CrtYd")
		)
		(fp_rect
			(start -0.381 0.8382)
			(end 0.381 -0.8382)
			(stroke
				(width 0)
				(type default)
			)
			(fill no)
			(layer "F.Fab")
		)
		(pad "1" smd custom
			(at 0 -0.4318 90)
			(size 0.127 0.127)
			(layers "F.Cu" "F.Mask" "F.Paste")
			(net "JTAG_RST#")
			(options
				(clearance outline)
				(anchor circle)
			)
			(primitives
				(gr_poly
					(pts
						(arc
							(start -0.2032 -0.2794)
							(mid -0.239121 -0.264521)
							(end -0.254 -0.2286)
						)
						(arc
							(start -0.254 0.2286)
							(mid -0.239121 0.264521)
							(end -0.2032 0.2794)
						)
						(arc
							(start 0.2032 0.2794)
							(mid 0.239121 0.264521)
							(end 0.254 0.2286)
						)
						(arc
							(start 0.254 -0.2286)
							(mid 0.239121 -0.264521)
							(end 0.2032 -0.2794)
						)
					)
					(width 0)
					(fill yes)
				)
			)
		)
		(pad "2" smd custom
			(at 0 0.4318 90)
			(size 0.127 0.127)
			(layers "F.Cu" "F.Mask" "F.Paste")
			(net "JTAG_RST_D#")
			(options
				(clearance outline)
				(anchor circle)
			)
			(primitives
				(gr_poly
					(pts
						(arc
							(start -0.2032 -0.2794)
							(mid -0.239121 -0.264521)
							(end -0.254 -0.2286)
						)
						(arc
							(start -0.254 0.2286)
							(mid -0.239121 0.264521)
							(end -0.2032 0.2794)
						)
						(arc
							(start 0.2032 0.2794)
							(mid 0.239121 0.264521)
							(end 0.254 0.2286)
						)
						(arc
							(start 0.254 -0.2286)
							(mid 0.239121 -0.264521)
							(end 0.2032 -0.2794)
						)
					)
					(width 0)
					(fill yes)
				)
			)
		)
	)
	(footprint ""
		(layer "F.Cu")
		(at 18.415 -23.749)
		(property "Reference" "PC50"
			(at 0 0 0)
			(layer "F.SilkS")
			(hide yes)
			(effects
				(font
					(size 1.27 1.27)
				)
			)
		)
		(property "Value" "SCD1U50V3KX-GP"
			(at -0.0254 -2.0193 0)
			(unlocked yes)
			(layer "F.Fab")
			(hide yes)
			(effects
				(font
					(size 1.016 1.016)
					(thickness 0.1524)
				)
			)
		)
		(property "Device Type" "C603H36"
			(at -0.0254 -3.5433 0)
			(unlocked yes)
			(layer "F.Fab")
			(hide yes)
			(effects
				(font
					(size 1.016 1.016)
					(thickness 0.1524)
				)
			)
		)
		(duplicate_pad_numbers_are_jumpers no)
		(fp_line
			(start -0.4064 0)
			(end 0.4064 0)
			(stroke
				(width 0.2286)
				(type default)
			)
			(layer "F.SilkS")
		)
		(fp_rect
			(start -0.635 1.1811)
			(end 0.635 -1.1811)
			(stroke
				(width 0)
				(type default)
			)
			(fill no)
			(layer "F.CrtYd")
		)
		(fp_rect
			(start -0.635 1.1811)
			(end 0.635 -1.1811)
			(stroke
				(width 0)
				(type default)
			)
			(fill no)
			(layer "F.Fab")
		)
		(pad "1" smd custom
			(at 0 -0.6604)
			(size 0.19685 0.19685)
			(layers "F.Cu" "F.Mask" "F.Paste")
			(net "P1V0_VBST")
			(options
				(clearance outline)
				(anchor circle)
			)
			(primitives
				(gr_poly
					(pts
						(arc
							(start 0.508 -0.2921)
							(mid 0.478242 -0.363942)
							(end 0.4064 -0.3937)
						)
						(arc
							(start -0.4064 -0.3937)
							(mid -0.478242 -0.363942)
							(end -0.508 -0.2921)
						)
						(arc
							(start -0.508 0.2921)
							(mid -0.478242 0.363942)
							(end -0.4064 0.3937)
						)
						(arc
							(start 0.4064 0.3937)
							(mid 0.478242 0.363942)
							(end 0.508 0.2921)
						)
					)
					(width 0)
					(fill yes)
				)
			)
		)
		(pad "2" smd custom
			(at 0 0.6604)
			(size 0.19685 0.19685)
			(layers "F.Cu" "F.Mask" "F.Paste")
			(net "P1V0_VBST_RC")
			(options
				(clearance outline)
				(anchor circle)
			)
			(primitives
				(gr_poly
					(pts
						(arc
							(start 0.508 -0.2921)
							(mid 0.478242 -0.363942)
							(end 0.4064 -0.3937)
						)
						(arc
							(start -0.4064 -0.3937)
							(mid -0.478242 -0.363942)
							(end -0.508 -0.2921)
						)
						(arc
							(start -0.508 0.2921)
							(mid -0.478242 0.363942)
							(end -0.4064 0.3937)
						)
						(arc
							(start 0.4064 0.3937)
							(mid 0.478242 0.363942)
							(end 0.508 0.2921)
						)
					)
					(width 0)
					(fill yes)
				)
			)
		)
	)
	(footprint ""
		(layer "F.Cu")
		(at 27.178 -68.199 -90)
		(property "Reference" "PR64"
			(at 0 0 270)
			(layer "F.SilkS")
			(hide yes)
			(effects
				(font
					(size 1.27 1.27)
				)
			)
		)
		(property "Value" "3K3R3F-GP"
			(at -0.0254 -2.0193 270)
			(unlocked yes)
			(layer "F.Fab")
			(hide yes)
			(effects
				(font
					(size 1.016 1.016)
					(thickness 0.1524)
				)
			)
		)
		(property "Device Type" "R603H22"
			(at -0.0254 -3.5433 270)
			(unlocked yes)
			(layer "F.Fab")
			(hide yes)
			(effects
				(font
					(size 1.016 1.016)
					(thickness 0.1524)
				)
			)
		)
		(duplicate_pad_numbers_are_jumpers no)
		(fp_line
			(start -0.2032 0)
			(end -0.4191 0)
			(stroke
				(width 0.2032)
				(type default)
			)
			(layer "F.SilkS")
		)
		(fp_line
			(start 0.4318 0)
			(end 0.2032 0)
			(stroke
				(width 0.2032)
				(type default)
			)
			(layer "F.SilkS")
		)
		(fp_rect
			(start -0.635 1.1811)
			(end 0.635 -1.1811)
			(stroke
				(width 0)
				(type default)
			)
			(fill no)
			(layer "F.CrtYd")
		)
		(fp_rect
			(start -0.635 1.1811)
			(end 0.635 -1.1811)
			(stroke
				(width 0)
				(type default)
			)
			(fill no)
			(layer "F.Fab")
		)
		(pad "1" smd custom
			(at 0 -0.6604 270)
			(size 0.19685 0.19685)
			(layers "F.Cu" "F.Mask" "F.Paste")
			(net "P12V")
			(options
				(clearance outline)
				(anchor circle)
			)
			(primitives
				(gr_poly
					(pts
						(arc
							(start 0.508 -0.2921)
							(mid 0.478242 -0.363942)
							(end 0.4064 -0.3937)
						)
						(arc
							(start -0.4064 -0.3937)
							(mid -0.478242 -0.363942)
							(end -0.508 -0.2921)
						)
						(arc
							(start -0.508 0.2921)
							(mid -0.478242 0.363942)
							(end -0.4064 0.3937)
						)
						(arc
							(start 0.4064 0.3937)
							(mid 0.478242 0.363942)
							(end 0.508 0.2921)
						)
					)
					(width 0)
					(fill yes)
				)
			)
		)
		(pad "2" smd custom
			(at 0 0.6604 270)
			(size 0.19685 0.19685)
			(layers "F.Cu" "F.Mask" "F.Paste")
			(net "VCCP_Z")
			(options
				(clearance outline)
				(anchor circle)
			)
			(primitives
				(gr_poly
					(pts
						(arc
							(start 0.508 -0.2921)
							(mid 0.478242 -0.363942)
							(end 0.4064 -0.3937)
						)
						(arc
							(start -0.4064 -0.3937)
							(mid -0.478242 -0.363942)
							(end -0.508 -0.2921)
						)
						(arc
							(start -0.508 0.2921)
							(mid -0.478242 0.363942)
							(end -0.4064 0.3937)
						)
						(arc
							(start 0.4064 0.3937)
							(mid 0.478242 0.363942)
							(end 0.508 0.2921)
						)
					)
					(width 0)
					(fill yes)
				)
			)
		)
	)
	(footprint ""
		(layer "F.Cu")
		(at 148.082 -59.182)
		(property "Reference" "C369"
			(at 0 0 0)
			(layer "F.SilkS")
			(hide yes)
			(effects
				(font
					(size 1.27 1.27)
				)
			)
		)
		(property "Value" "SC47U6D3V5MX-1-GP"
			(at 0 -4.9022 0)
			(unlocked yes)
			(layer "F.Fab")
			(hide yes)
			(effects
				(font
					(size 1.016 1.016)
					(thickness 0.1524)
				)
			)
		)
		(property "Device Type" "C805H54"
			(at 0 -6.8072 0)
			(unlocked yes)
			(layer "F.Fab")
			(hide yes)
			(effects
				(font
					(size 1.016 1.016)
					(thickness 0.1524)
				)
			)
		)
		(duplicate_pad_numbers_are_jumpers no)
		(fp_line
			(start 0.6096 0)
			(end -0.6096 0)
			(stroke
				(width 0.3048)
				(type default)
			)
			(layer "F.SilkS")
		)
		(fp_poly
			(pts
				(xy -0.9017 1.4351) (xy 0.9017 1.4351) (xy 0.9017 -1.4351) (xy -0.9017 -1.4351)
			)
			(stroke
				(width 0)
				(type default)
			)
			(fill no)
			(layer "F.CrtYd")
		)
		(fp_poly
			(pts
				(xy 0.9017 1.4351) (xy 0.9017 -1.4351) (xy -0.9017 -1.4351) (xy -0.9017 1.4351)
			)
			(stroke
				(width 0)
				(type default)
			)
			(fill no)
			(layer "F.Fab")
		)
		(pad "1" smd rect
			(at 0 -0.8382)
			(size 1.5494 0.9398)
			(layers "F.Cu" "F.Mask" "F.Paste")
			(net "PV_VDDR")
		)
		(pad "2" smd rect
			(at 0 0.8382)
			(size 1.5494 0.9398)
			(layers "F.Cu" "F.Mask" "F.Paste")
			(net "GND")
		)
	)
	(footprint ""
		(layer "F.Cu")
		(at 169.672 -38.989 -90)
		(property "Reference" "PR226"
			(at 0 0 270)
			(layer "F.SilkS")
			(hide yes)
			(effects
				(font
					(size 1.27 1.27)
				)
			)
		)
		(property "Value" "0R3J-6-GP"
			(at -0.0254 -2.0193 270)
			(unlocked yes)
			(layer "F.Fab")
			(hide yes)
			(effects
				(font
					(size 1.016 1.016)
					(thickness 0.1524)
				)
			)
		)
		(property "Device Type" "R603H22"
			(at -0.0254 -3.5433 270)
			(unlocked yes)
			(layer "F.Fab")
			(hide yes)
			(effects
				(font
					(size 1.016 1.016)
					(thickness 0.1524)
				)
			)
		)
		(duplicate_pad_numbers_are_jumpers no)
		(fp_line
			(start -0.2032 0)
			(end -0.4191 0)
			(stroke
				(width 0.2032)
				(type default)
			)
			(layer "F.SilkS")
		)
		(fp_line
			(start 0.4318 0)
			(end 0.2032 0)
			(stroke
				(width 0.2032)
				(type default)
			)
			(layer "F.SilkS")
		)
		(fp_rect
			(start -0.635 1.1811)
			(end 0.635 -1.1811)
			(stroke
				(width 0)
				(type default)
			)
			(fill no)
			(layer "F.CrtYd")
		)
		(fp_rect
			(start -0.635 1.1811)
			(end 0.635 -1.1811)
			(stroke
				(width 0)
				(type default)
			)
			(fill no)
			(layer "F.Fab")
		)
		(pad "1" smd custom
			(at 0 -0.6604 270)
			(size 0.19685 0.19685)
			(layers "F.Cu" "F.Mask" "F.Paste")
			(net "P2V5_STBY_OUT")
			(options
				(clearance outline)
				(anchor circle)
			)
			(primitives
				(gr_poly
					(pts
						(arc
							(start 0.508 -0.2921)
							(mid 0.478242 -0.363942)
							(end 0.4064 -0.3937)
						)
						(arc
							(start -0.4064 -0.3937)
							(mid -0.478242 -0.363942)
							(end -0.508 -0.2921)
						)
						(arc
							(start -0.508 0.2921)
							(mid -0.478242 0.363942)
							(end -0.4064 0.3937)
						)
						(arc
							(start 0.4064 0.3937)
							(mid 0.478242 0.363942)
							(end 0.508 0.2921)
						)
					)
					(width 0)
					(fill yes)
				)
			)
		)
		(pad "2" smd custom
			(at 0 0.6604 270)
			(size 0.19685 0.19685)
			(layers "F.Cu" "F.Mask" "F.Paste")
			(net "P2V5_STBY")
			(options
				(clearance outline)
				(anchor circle)
			)
			(primitives
				(gr_poly
					(pts
						(arc
							(start 0.508 -0.2921)
							(mid 0.478242 -0.363942)
							(end 0.4064 -0.3937)
						)
						(arc
							(start -0.4064 -0.3937)
							(mid -0.478242 -0.363942)
							(end -0.508 -0.2921)
						)
						(arc
							(start -0.508 0.2921)
							(mid -0.478242 0.363942)
							(end -0.4064 0.3937)
						)
						(arc
							(start 0.4064 0.3937)
							(mid 0.478242 0.363942)
							(end 0.508 0.2921)
						)
					)
					(width 0)
					(fill yes)
				)
			)
		)
	)
	(footprint ""
		(layer "F.Cu")
		(at 182.9308 -29.5656 90)
		(property "Reference" "PC108"
			(at 0 0 90)
			(layer "F.SilkS")
			(hide yes)
			(effects
				(font
					(size 1.27 1.27)
				)
			)
		)
		(property "Value" "SC1KP50V2KX-1GP"
			(at 1.8923 -1.2065 90)
			(unlocked yes)
			(layer "F.Fab")
			(hide yes)
			(effects
				(font
					(size 1.016 1.016)
					(thickness 0.1524)
				)
			)
		)
		(property "Device Type" "C402H22"
			(at 1.8923 -2.7305 90)
			(unlocked yes)
			(layer "F.Fab")
			(hide yes)
			(effects
				(font
					(size 1.016 1.016)
					(thickness 0.1524)
				)
			)
		)
		(duplicate_pad_numbers_are_jumpers no)
		(fp_rect
			(start -0.381 0.7366)
			(end 0.381 -0.7366)
			(stroke
				(width 0)
				(type default)
			)
			(fill no)
			(layer "F.CrtYd")
		)
		(fp_rect
			(start -0.381 0.7366)
			(end 0.381 -0.7366)
			(stroke
				(width 0)
				(type default)
			)
			(fill no)
			(layer "F.Fab")
		)
		(pad "1" smd custom
			(at 0 -0.4572 90)
			(size 0.1143 0.1143)
			(layers "F.Cu" "F.Mask" "F.Paste")
			(net "VR_PVDDR_A_COMP")
			(options
				(clearance outline)
				(anchor circle)
			)
			(primitives
				(gr_poly
					(pts
						(arc
							(start -0.254 -0.1778)
							(mid -0.239121 -0.213721)
							(end -0.2032 -0.2286)
						)
						(arc
							(start 0.2032 -0.2286)
							(mid 0.239121 -0.213721)
							(end 0.254 -0.1778)
						)
						(arc
							(start 0.254 0.1778)
							(mid 0.239121 0.213721)
							(end 0.2032 0.2286)
						)
						(arc
							(start -0.2032 0.2286)
							(mid -0.239121 0.213721)
							(end -0.254 0.1778)
						)
					)
					(width 0)
					(fill yes)
				)
			)
		)
		(pad "2" smd custom
			(at 0 0.4572 90)
			(size 0.1143 0.1143)
			(layers "F.Cu" "F.Mask" "F.Paste")
			(net "VR_PVDDR_A_FB_COMP")
			(options
				(clearance outline)
				(anchor circle)
			)
			(primitives
				(gr_poly
					(pts
						(arc
							(start -0.254 -0.1778)
							(mid -0.239121 -0.213721)
							(end -0.2032 -0.2286)
						)
						(arc
							(start 0.2032 -0.2286)
							(mid 0.239121 -0.213721)
							(end 0.254 -0.1778)
						)
						(arc
							(start 0.254 0.1778)
							(mid 0.239121 0.213721)
							(end 0.2032 0.2286)
						)
						(arc
							(start -0.2032 0.2286)
							(mid -0.239121 0.213721)
							(end -0.254 0.1778)
						)
					)
					(width 0)
					(fill yes)
				)
			)
		)
	)
	(footprint ""
		(layer "F.Cu")
		(at 8.509 -63.627 90)
		(property "Reference" "C189"
			(at 0 0 90)
			(layer "F.SilkS")
			(hide yes)
			(effects
				(font
					(size 1.27 1.27)
				)
			)
		)
		(property "Value" "SCD1U16V2KX-3GP"
			(at 1.1811 -2.7051 90)
			(unlocked yes)
			(layer "F.Fab")
			(hide yes)
			(effects
				(font
					(size 1.016 1.016)
					(thickness 0.1524)
				)
			)
		)
		(property "Device Type" "C402H22"
			(at 1.1811 -4.2291 90)
			(unlocked yes)
			(layer "F.Fab")
			(hide yes)
			(effects
				(font
					(size 1.016 1.016)
					(thickness 0.1524)
				)
			)
		)
		(duplicate_pad_numbers_are_jumpers no)
		(fp_rect
			(start -0.381 0.7366)
			(end 0.381 -0.7366)
			(stroke
				(width 0)
				(type default)
			)
			(fill no)
			(layer "F.CrtYd")
		)
		(fp_rect
			(start -0.381 0.7366)
			(end 0.381 -0.7366)
			(stroke
				(width 0)
				(type default)
			)
			(fill no)
			(layer "F.Fab")
		)
		(pad "1" smd custom
			(at 0 -0.4572 90)
			(size 0.1143 0.1143)
			(layers "F.Cu" "F.Mask" "F.Paste")
			(net "P2E_CPU_NGFF_TX_DN15")
			(options
				(clearance outline)
				(anchor circle)
			)
			(primitives
				(gr_poly
					(pts
						(arc
							(start -0.254 -0.1778)
							(mid -0.239121 -0.213721)
							(end -0.2032 -0.2286)
						)
						(arc
							(start 0.2032 -0.2286)
							(mid 0.239121 -0.213721)
							(end 0.254 -0.1778)
						)
						(arc
							(start 0.254 0.1778)
							(mid 0.239121 0.213721)
							(end 0.2032 0.2286)
						)
						(arc
							(start -0.2032 0.2286)
							(mid -0.239121 0.213721)
							(end -0.254 0.1778)
						)
					)
					(width 0)
					(fill yes)
				)
			)
		)
		(pad "2" smd custom
			(at 0 0.4572 90)
			(size 0.1143 0.1143)
			(layers "F.Cu" "F.Mask" "F.Paste")
			(net "P2E_CPU_NGFF_C_TX_DN15")
			(options
				(clearance outline)
				(anchor circle)
			)
			(primitives
				(gr_poly
					(pts
						(arc
							(start -0.254 -0.1778)
							(mid -0.239121 -0.213721)
							(end -0.2032 -0.2286)
						)
						(arc
							(start 0.2032 -0.2286)
							(mid 0.239121 -0.213721)
							(end 0.254 -0.1778)
						)
						(arc
							(start 0.254 0.1778)
							(mid 0.239121 0.213721)
							(end 0.2032 0.2286)
						)
						(arc
							(start -0.2032 0.2286)
							(mid -0.239121 0.213721)
							(end -0.254 0.1778)
						)
					)
					(width 0)
					(fill yes)
				)
			)
		)
	)
	(footprint ""
		(layer "F.Cu")
		(at 59.817 -17.018 90)
		(property "Reference" "R180"
			(at 0 0 90)
			(layer "F.SilkS")
			(hide yes)
			(effects
				(font
					(size 1.27 1.27)
				)
			)
		)
		(property "Value" "0R2J-2-GP"
			(at 0.064008 -3.993896 90)
			(unlocked yes)
			(layer "F.Fab")
			(hide yes)
			(effects
				(font
					(size 1.016 1.016)
					(thickness 0.1524)
				)
			)
		)
		(property "Device Type" "R402H16"
			(at 0.064008 -5.517896 90)
			(unlocked yes)
			(layer "F.Fab")
			(hide yes)
			(effects
				(font
					(size 1.016 1.016)
					(thickness 0.1524)
				)
			)
		)
		(duplicate_pad_numbers_are_jumpers no)
		(fp_rect
			(start -0.381 0.8382)
			(end 0.381 -0.8382)
			(stroke
				(width 0)
				(type default)
			)
			(fill no)
			(layer "F.CrtYd")
		)
		(fp_rect
			(start -0.381 0.8382)
			(end 0.381 -0.8382)
			(stroke
				(width 0)
				(type default)
			)
			(fill no)
			(layer "F.Fab")
		)
		(pad "1" smd custom
			(at 0 -0.4318 90)
			(size 0.127 0.127)
			(layers "F.Cu" "F.Mask" "F.Paste")
			(net "SPI_MOSI_GBE_R")
			(options
				(clearance outline)
				(anchor circle)
			)
			(primitives
				(gr_poly
					(pts
						(arc
							(start -0.2032 -0.2794)
							(mid -0.239121 -0.264521)
							(end -0.254 -0.2286)
						)
						(arc
							(start -0.254 0.2286)
							(mid -0.239121 0.264521)
							(end -0.2032 0.2794)
						)
						(arc
							(start 0.2032 0.2794)
							(mid 0.239121 0.264521)
							(end 0.254 0.2286)
						)
						(arc
							(start 0.254 -0.2286)
							(mid 0.239121 -0.264521)
							(end 0.2032 -0.2794)
						)
					)
					(width 0)
					(fill yes)
				)
			)
		)
		(pad "2" smd custom
			(at 0 0.4318 90)
			(size 0.127 0.127)
			(layers "F.Cu" "F.Mask" "F.Paste")
			(net "SPI_MOSI_GBE")
			(options
				(clearance outline)
				(anchor circle)
			)
			(primitives
				(gr_poly
					(pts
						(arc
							(start -0.2032 -0.2794)
							(mid -0.239121 -0.264521)
							(end -0.254 -0.2286)
						)
						(arc
							(start -0.254 0.2286)
							(mid -0.239121 0.264521)
							(end -0.2032 0.2794)
						)
						(arc
							(start 0.2032 0.2794)
							(mid 0.239121 0.264521)
							(end 0.254 0.2286)
						)
						(arc
							(start 0.254 -0.2286)
							(mid 0.239121 -0.264521)
							(end 0.2032 -0.2794)
						)
					)
					(width 0)
					(fill yes)
				)
			)
		)
	)
	(footprint ""
		(layer "F.Cu")
		(at 19.939 -21.59 90)
		(property "Reference" "PC75"
			(at 0 0 90)
			(layer "F.SilkS")
			(hide yes)
			(effects
				(font
					(size 1.27 1.27)
				)
			)
		)
		(property "Value" "SC1KP50V2KX-1GP"
			(at 1.8923 -1.2065 90)
			(unlocked yes)
			(layer "F.Fab")
			(hide yes)
			(effects
				(font
					(size 1.016 1.016)
					(thickness 0.1524)
				)
			)
		)
		(property "Device Type" "C402H22"
			(at 1.8923 -2.7305 90)
			(unlocked yes)
			(layer "F.Fab")
			(hide yes)
			(effects
				(font
					(size 1.016 1.016)
					(thickness 0.1524)
				)
			)
		)
		(duplicate_pad_numbers_are_jumpers no)
		(fp_rect
			(start -0.381 0.7366)
			(end 0.381 -0.7366)
			(stroke
				(width 0)
				(type default)
			)
			(fill no)
			(layer "F.CrtYd")
		)
		(fp_rect
			(start -0.381 0.7366)
			(end 0.381 -0.7366)
			(stroke
				(width 0)
				(type default)
			)
			(fill no)
			(layer "F.Fab")
		)
		(pad "1" smd custom
			(at 0 -0.4572 90)
			(size 0.1143 0.1143)
			(layers "F.Cu" "F.Mask" "F.Paste")
			(net "P1V0_VFB")
			(options
				(clearance outline)
				(anchor circle)
			)
			(primitives
				(gr_poly
					(pts
						(arc
							(start -0.254 -0.1778)
							(mid -0.239121 -0.213721)
							(end -0.2032 -0.2286)
						)
						(arc
							(start 0.2032 -0.2286)
							(mid 0.239121 -0.213721)
							(end 0.254 -0.1778)
						)
						(arc
							(start 0.254 0.1778)
							(mid 0.239121 0.213721)
							(end 0.2032 0.2286)
						)
						(arc
							(start -0.2032 0.2286)
							(mid -0.239121 0.213721)
							(end -0.254 0.1778)
						)
					)
					(width 0)
					(fill yes)
				)
			)
		)
		(pad "2" smd custom
			(at 0 0.4572 90)
			(size 0.1143 0.1143)
			(layers "F.Cu" "F.Mask" "F.Paste")
			(net "P1V0_SW_R")
			(options
				(clearance outline)
				(anchor circle)
			)
			(primitives
				(gr_poly
					(pts
						(arc
							(start -0.254 -0.1778)
							(mid -0.239121 -0.213721)
							(end -0.2032 -0.2286)
						)
						(arc
							(start 0.2032 -0.2286)
							(mid 0.239121 -0.213721)
							(end 0.254 -0.1778)
						)
						(arc
							(start 0.254 0.1778)
							(mid 0.239121 0.213721)
							(end 0.2032 0.2286)
						)
						(arc
							(start -0.2032 0.2286)
							(mid -0.239121 0.213721)
							(end -0.254 0.1778)
						)
					)
					(width 0)
					(fill yes)
				)
			)
		)
	)
	(footprint ""
		(layer "F.Cu")
		(at 197.739 -1.778 90)
		(property "Reference" "C91"
			(at 0 0 90)
			(layer "F.SilkS")
			(hide yes)
			(effects
				(font
					(size 1.27 1.27)
				)
			)
		)
		(property "Value" "SC10U6D3V3MX-GP"
			(at 0 -2.8194 90)
			(unlocked yes)
			(layer "F.Fab")
			(hide yes)
			(effects
				(font
					(size 1.016 1.016)
					(thickness 0.1524)
				)
			)
		)
		(property "Device Type" "C603H38"
			(at 0 -4.3434 90)
			(unlocked yes)
			(layer "F.Fab")
			(hide yes)
			(effects
				(font
					(size 1.016 1.016)
					(thickness 0.1524)
				)
			)
		)
		(duplicate_pad_numbers_are_jumpers no)
		(fp_line
			(start -0.4064 0)
			(end 0.4064 0)
			(stroke
				(width 0.2286)
				(type default)
			)
			(layer "F.SilkS")
		)
		(fp_rect
			(start -0.635 1.1811)
			(end 0.635 -1.1811)
			(stroke
				(width 0)
				(type default)
			)
			(fill no)
			(layer "F.CrtYd")
		)
		(fp_rect
			(start -0.635 1.1811)
			(end 0.635 -1.1811)
			(stroke
				(width 0)
				(type default)
			)
			(fill no)
			(layer "F.Fab")
		)
		(pad "1" smd custom
			(at 0 -0.6604 90)
			(size 0.19685 0.19685)
			(layers "F.Cu" "F.Mask" "F.Paste")
			(net "PV_VTT_DDR_B")
			(options
				(clearance outline)
				(anchor circle)
			)
			(primitives
				(gr_poly
					(pts
						(arc
							(start 0.508 -0.2921)
							(mid 0.478242 -0.363942)
							(end 0.4064 -0.3937)
						)
						(arc
							(start -0.4064 -0.3937)
							(mid -0.478242 -0.363942)
							(end -0.508 -0.2921)
						)
						(arc
							(start -0.508 0.2921)
							(mid -0.478242 0.363942)
							(end -0.4064 0.3937)
						)
						(arc
							(start 0.4064 0.3937)
							(mid 0.478242 0.363942)
							(end 0.508 0.2921)
						)
					)
					(width 0)
					(fill yes)
				)
			)
		)
		(pad "2" smd custom
			(at 0 0.6604 90)
			(size 0.19685 0.19685)
			(layers "F.Cu" "F.Mask" "F.Paste")
			(net "GND")
			(options
				(clearance outline)
				(anchor circle)
			)
			(primitives
				(gr_poly
					(pts
						(arc
							(start 0.508 -0.2921)
							(mid 0.478242 -0.363942)
							(end 0.4064 -0.3937)
						)
						(arc
							(start -0.4064 -0.3937)
							(mid -0.478242 -0.363942)
							(end -0.508 -0.2921)
						)
						(arc
							(start -0.508 0.2921)
							(mid -0.478242 0.363942)
							(end -0.4064 0.3937)
						)
						(arc
							(start 0.4064 0.3937)
							(mid 0.478242 0.363942)
							(end 0.508 0.2921)
						)
					)
					(width 0)
					(fill yes)
				)
			)
		)
	)
	(footprint ""
		(layer "F.Cu")
		(at 32.2072 -36.2204 180)
		(property "Reference" "R268"
			(at 0 0 180)
			(layer "F.SilkS")
			(hide yes)
			(effects
				(font
					(size 1.27 1.27)
				)
			)
		)
		(property "Value" "0R2J-2-GP"
			(at 0.064008 -3.993896 180)
			(unlocked yes)
			(layer "F.Fab")
			(hide yes)
			(effects
				(font
					(size 1.016 1.016)
					(thickness 0.1524)
				)
			)
		)
		(property "Device Type" "R402H16"
			(at 0.064008 -5.517896 180)
			(unlocked yes)
			(layer "F.Fab")
			(hide yes)
			(effects
				(font
					(size 1.016 1.016)
					(thickness 0.1524)
				)
			)
		)
		(duplicate_pad_numbers_are_jumpers no)
		(fp_rect
			(start -0.381 0.8382)
			(end 0.381 -0.8382)
			(stroke
				(width 0)
				(type default)
			)
			(fill no)
			(layer "F.CrtYd")
		)
		(fp_rect
			(start -0.381 0.8382)
			(end 0.381 -0.8382)
			(stroke
				(width 0)
				(type default)
			)
			(fill no)
			(layer "F.Fab")
		)
		(pad "1" smd custom
			(at 0 -0.4318 180)
			(size 0.127 0.127)
			(layers "F.Cu" "F.Mask" "F.Paste")
			(net "TDI_56")
			(options
				(clearance outline)
				(anchor circle)
			)
			(primitives
				(gr_poly
					(pts
						(arc
							(start -0.2032 -0.2794)
							(mid -0.239121 -0.264521)
							(end -0.254 -0.2286)
						)
						(arc
							(start -0.254 0.2286)
							(mid -0.239121 0.264521)
							(end -0.2032 0.2794)
						)
						(arc
							(start 0.2032 0.2794)
							(mid 0.239121 0.264521)
							(end 0.254 0.2286)
						)
						(arc
							(start 0.254 -0.2286)
							(mid 0.239121 -0.264521)
							(end 0.2032 -0.2794)
						)
					)
					(width 0)
					(fill yes)
				)
			)
		)
		(pad "2" smd custom
			(at 0 0.4318 180)
			(size 0.127 0.127)
			(layers "F.Cu" "F.Mask" "F.Paste")
			(net "XDP_SOC_CPU_TDI")
			(options
				(clearance outline)
				(anchor circle)
			)
			(primitives
				(gr_poly
					(pts
						(arc
							(start -0.2032 -0.2794)
							(mid -0.239121 -0.264521)
							(end -0.254 -0.2286)
						)
						(arc
							(start -0.254 0.2286)
							(mid -0.239121 0.264521)
							(end -0.2032 0.2794)
						)
						(arc
							(start 0.2032 0.2794)
							(mid 0.239121 0.264521)
							(end 0.254 0.2286)
						)
						(arc
							(start 0.254 -0.2286)
							(mid 0.239121 -0.264521)
							(end 0.2032 -0.2794)
						)
					)
					(width 0)
					(fill yes)
				)
			)
		)
	)
	(footprint ""
		(layer "F.Cu")
		(at 154.94 -11.684 -90)
		(property "Reference" "R385"
			(at 0 0 270)
			(layer "F.SilkS")
			(hide yes)
			(effects
				(font
					(size 1.27 1.27)
				)
			)
		)
		(property "Value" "100R2F-L1-GP-U"
			(at 0.064008 -3.993896 270)
			(unlocked yes)
			(layer "F.Fab")
			(hide yes)
			(effects
				(font
					(size 1.016 1.016)
					(thickness 0.1524)
				)
			)
		)
		(property "Device Type" "R402H14"
			(at 0.064008 -5.517896 270)
			(unlocked yes)
			(layer "F.Fab")
			(hide yes)
			(effects
				(font
					(size 1.016 1.016)
					(thickness 0.1524)
				)
			)
		)
		(duplicate_pad_numbers_are_jumpers no)
		(fp_rect
			(start -0.381 0.8382)
			(end 0.381 -0.8382)
			(stroke
				(width 0)
				(type default)
			)
			(fill no)
			(layer "F.CrtYd")
		)
		(fp_rect
			(start -0.381 0.8382)
			(end 0.381 -0.8382)
			(stroke
				(width 0)
				(type default)
			)
			(fill no)
			(layer "F.Fab")
		)
		(pad "1" smd custom
			(at 0 -0.4318 270)
			(size 0.127 0.127)
			(layers "F.Cu" "F.Mask" "F.Paste")
			(net "PV_VDDR")
			(options
				(clearance outline)
				(anchor circle)
			)
			(primitives
				(gr_poly
					(pts
						(arc
							(start -0.2032 -0.2794)
							(mid -0.239121 -0.264521)
							(end -0.254 -0.2286)
						)
						(arc
							(start -0.254 0.2286)
							(mid -0.239121 0.264521)
							(end -0.2032 0.2794)
						)
						(arc
							(start 0.2032 0.2794)
							(mid 0.239121 0.264521)
							(end 0.254 0.2286)
						)
						(arc
							(start 0.254 -0.2286)
							(mid 0.239121 -0.264521)
							(end 0.2032 -0.2794)
						)
					)
					(width 0)
					(fill yes)
				)
			)
		)
		(pad "2" smd custom
			(at 0 0.4318 270)
			(size 0.127 0.127)
			(layers "F.Cu" "F.Mask" "F.Paste")
			(net "DDR3_M_B_VREF_CA")
			(options
				(clearance outline)
				(anchor circle)
			)
			(primitives
				(gr_poly
					(pts
						(arc
							(start -0.2032 -0.2794)
							(mid -0.239121 -0.264521)
							(end -0.254 -0.2286)
						)
						(arc
							(start -0.254 0.2286)
							(mid -0.239121 0.264521)
							(end -0.2032 0.2794)
						)
						(arc
							(start 0.2032 0.2794)
							(mid 0.239121 0.264521)
							(end 0.254 0.2286)
						)
						(arc
							(start 0.254 -0.2286)
							(mid 0.239121 -0.264521)
							(end 0.2032 -0.2794)
						)
					)
					(width 0)
					(fill yes)
				)
			)
		)
	)
	(footprint ""
		(layer "F.Cu")
		(at 50.419 -65.024)
		(property "Reference" "PR33"
			(at 0 0 0)
			(layer "F.SilkS")
			(hide yes)
			(effects
				(font
					(size 1.27 1.27)
				)
			)
		)
		(property "Value" "120R3F-L-GP"
			(at -0.0254 -2.0193 0)
			(unlocked yes)
			(layer "F.Fab")
			(hide yes)
			(effects
				(font
					(size 1.016 1.016)
					(thickness 0.1524)
				)
			)
		)
		(property "Device Type" "R603H22"
			(at -0.0254 -3.5433 0)
			(unlocked yes)
			(layer "F.Fab")
			(hide yes)
			(effects
				(font
					(size 1.016 1.016)
					(thickness 0.1524)
				)
			)
		)
		(duplicate_pad_numbers_are_jumpers no)
		(fp_line
			(start -0.2032 0)
			(end -0.4191 0)
			(stroke
				(width 0.2032)
				(type default)
			)
			(layer "F.SilkS")
		)
		(fp_line
			(start 0.4318 0)
			(end 0.2032 0)
			(stroke
				(width 0.2032)
				(type default)
			)
			(layer "F.SilkS")
		)
		(fp_rect
			(start -0.635 1.1811)
			(end 0.635 -1.1811)
			(stroke
				(width 0)
				(type default)
			)
			(fill no)
			(layer "F.CrtYd")
		)
		(fp_rect
			(start -0.635 1.1811)
			(end 0.635 -1.1811)
			(stroke
				(width 0)
				(type default)
			)
			(fill no)
			(layer "F.Fab")
		)
		(pad "1" smd custom
			(at 0 -0.6604)
			(size 0.19685 0.19685)
			(layers "F.Cu" "F.Mask" "F.Paste")
			(net "PVNN")
			(options
				(clearance outline)
				(anchor circle)
			)
			(primitives
				(gr_poly
					(pts
						(arc
							(start 0.508 -0.2921)
							(mid 0.478242 -0.363942)
							(end 0.4064 -0.3937)
						)
						(arc
							(start -0.4064 -0.3937)
							(mid -0.478242 -0.363942)
							(end -0.508 -0.2921)
						)
						(arc
							(start -0.508 0.2921)
							(mid -0.478242 0.363942)
							(end -0.4064 0.3937)
						)
						(arc
							(start 0.4064 0.3937)
							(mid 0.478242 0.363942)
							(end 0.508 0.2921)
						)
					)
					(width 0)
					(fill yes)
				)
			)
		)
		(pad "2" smd custom
			(at 0 0.6604)
			(size 0.19685 0.19685)
			(layers "F.Cu" "F.Mask" "F.Paste")
			(net "GND")
			(options
				(clearance outline)
				(anchor circle)
			)
			(primitives
				(gr_poly
					(pts
						(arc
							(start 0.508 -0.2921)
							(mid 0.478242 -0.363942)
							(end 0.4064 -0.3937)
						)
						(arc
							(start -0.4064 -0.3937)
							(mid -0.478242 -0.363942)
							(end -0.508 -0.2921)
						)
						(arc
							(start -0.508 0.2921)
							(mid -0.478242 0.363942)
							(end -0.4064 0.3937)
						)
						(arc
							(start 0.4064 0.3937)
							(mid 0.478242 0.363942)
							(end 0.508 0.2921)
						)
					)
					(width 0)
					(fill yes)
				)
			)
		)
	)
	(footprint ""
		(layer "F.Cu")
		(at 6.6294 -28.7274 180)
		(property "Reference" "PC94"
			(at 0 0 180)
			(layer "F.SilkS")
			(hide yes)
			(effects
				(font
					(size 1.27 1.27)
				)
			)
		)
		(property "Value" "SC22U25V5MX-GP"
			(at 0 -4.9022 180)
			(unlocked yes)
			(layer "F.Fab")
			(hide yes)
			(effects
				(font
					(size 1.016 1.016)
					(thickness 0.1524)
				)
			)
		)
		(property "Device Type" "C805H58"
			(at 0 -6.8072 180)
			(unlocked yes)
			(layer "F.Fab")
			(hide yes)
			(effects
				(font
					(size 1.016 1.016)
					(thickness 0.1524)
				)
			)
		)
		(duplicate_pad_numbers_are_jumpers no)
		(fp_line
			(start 0.6096 0)
			(end -0.6096 0)
			(stroke
				(width 0.3048)
				(type default)
			)
			(layer "F.SilkS")
		)
		(fp_poly
			(pts
				(xy -0.9017 1.4351) (xy 0.9017 1.4351) (xy 0.9017 -1.4351) (xy -0.9017 -1.4351)
			)
			(stroke
				(width 0)
				(type default)
			)
			(fill no)
			(layer "F.CrtYd")
		)
		(fp_poly
			(pts
				(xy 0.9017 1.4351) (xy 0.9017 -1.4351) (xy -0.9017 -1.4351) (xy -0.9017 1.4351)
			)
			(stroke
				(width 0)
				(type default)
			)
			(fill no)
			(layer "F.Fab")
		)
		(pad "1" smd rect
			(at 0 -0.8382 180)
			(size 1.5494 0.9398)
			(layers "F.Cu" "F.Mask" "F.Paste")
			(net "P1V0_VIN")
		)
		(pad "2" smd rect
			(at 0 0.8382 180)
			(size 1.5494 0.9398)
			(layers "F.Cu" "F.Mask" "F.Paste")
			(net "GND")
		)
	)
	(footprint ""
		(layer "F.Cu")
		(at 37.338 -49.784 90)
		(property "Reference" "L3"
			(at 0 0 90)
			(layer "F.SilkS")
			(hide yes)
			(effects
				(font
					(size 1.27 1.27)
				)
			)
		)
		(property "Value" "BLM18PG330SN1D-GP"
			(at -0.0254 -2.0193 90)
			(unlocked yes)
			(layer "F.Fab")
			(hide yes)
			(effects
				(font
					(size 1.016 1.016)
					(thickness 0.1524)
				)
			)
		)
		(property "Device Type" "L1608-UH38"
			(at -0.0254 -3.5433 90)
			(unlocked yes)
			(layer "F.Fab")
			(hide yes)
			(effects
				(font
					(size 1.016 1.016)
					(thickness 0.1524)
				)
			)
		)
		(duplicate_pad_numbers_are_jumpers no)
		(fp_line
			(start -0.4064 0)
			(end 0.4064 0)
			(stroke
				(width 0.2032)
				(type default)
			)
			(layer "F.SilkS")
		)
		(fp_rect
			(start -0.635 1.1811)
			(end 0.635 -1.1811)
			(stroke
				(width 0)
				(type default)
			)
			(fill no)
			(layer "F.CrtYd")
		)
		(fp_rect
			(start -0.635 1.1811)
			(end 0.635 -1.1811)
			(stroke
				(width 0)
				(type default)
			)
			(fill no)
			(layer "F.Fab")
		)
		(pad "1" smd custom
			(at 0 -0.6604 90)
			(size 0.19685 0.19685)
			(layers "F.Cu" "F.Mask" "F.Paste")
			(net "P3V3_STBY")
			(options
				(clearance outline)
				(anchor circle)
			)
			(primitives
				(gr_poly
					(pts
						(arc
							(start 0.508 -0.2921)
							(mid 0.478242 -0.363942)
							(end 0.4064 -0.3937)
						)
						(arc
							(start -0.4064 -0.3937)
							(mid -0.478242 -0.363942)
							(end -0.508 -0.2921)
						)
						(arc
							(start -0.508 0.2921)
							(mid -0.478242 0.363942)
							(end -0.4064 0.3937)
						)
						(arc
							(start 0.4064 0.3937)
							(mid 0.478242 0.363942)
							(end 0.508 0.2921)
						)
					)
					(width 0)
					(fill yes)
				)
			)
		)
		(pad "2" smd custom
			(at 0 0.6604 90)
			(size 0.19685 0.19685)
			(layers "F.Cu" "F.Mask" "F.Paste")
			(net "P3V3_CLK_R_PCI")
			(options
				(clearance outline)
				(anchor circle)
			)
			(primitives
				(gr_poly
					(pts
						(arc
							(start 0.508 -0.2921)
							(mid 0.478242 -0.363942)
							(end 0.4064 -0.3937)
						)
						(arc
							(start -0.4064 -0.3937)
							(mid -0.478242 -0.363942)
							(end -0.508 -0.2921)
						)
						(arc
							(start -0.508 0.2921)
							(mid -0.478242 0.363942)
							(end -0.4064 0.3937)
						)
						(arc
							(start 0.4064 0.3937)
							(mid 0.478242 0.363942)
							(end 0.508 0.2921)
						)
					)
					(width 0)
					(fill yes)
				)
			)
		)
	)
	(footprint ""
		(layer "F.Cu")
		(at 36.83 -39.116)
		(property "Reference" "R243"
			(at 0 0 0)
			(layer "F.SilkS")
			(hide yes)
			(effects
				(font
					(size 1.27 1.27)
				)
			)
		)
		(property "Value" "2K2R2F-GP"
			(at 0.064008 -3.993896 0)
			(unlocked yes)
			(layer "F.Fab")
			(hide yes)
			(effects
				(font
					(size 1.016 1.016)
					(thickness 0.1524)
				)
			)
		)
		(property "Device Type" "R402H16"
			(at 0.064008 -5.517896 0)
			(unlocked yes)
			(layer "F.Fab")
			(hide yes)
			(effects
				(font
					(size 1.016 1.016)
					(thickness 0.1524)
				)
			)
		)
		(duplicate_pad_numbers_are_jumpers no)
		(fp_rect
			(start -0.381 0.8382)
			(end 0.381 -0.8382)
			(stroke
				(width 0)
				(type default)
			)
			(fill no)
			(layer "F.CrtYd")
		)
		(fp_rect
			(start -0.381 0.8382)
			(end 0.381 -0.8382)
			(stroke
				(width 0)
				(type default)
			)
			(fill no)
			(layer "F.Fab")
		)
		(pad "1" smd custom
			(at 0 -0.4318)
			(size 0.127 0.127)
			(layers "F.Cu" "F.Mask" "F.Paste")
			(net "P3V3_RTC")
			(options
				(clearance outline)
				(anchor circle)
			)
			(primitives
				(gr_poly
					(pts
						(arc
							(start -0.2032 -0.2794)
							(mid -0.239121 -0.264521)
							(end -0.254 -0.2286)
						)
						(arc
							(start -0.254 0.2286)
							(mid -0.239121 0.264521)
							(end -0.2032 0.2794)
						)
						(arc
							(start 0.2032 0.2794)
							(mid 0.239121 0.264521)
							(end 0.254 0.2286)
						)
						(arc
							(start 0.254 -0.2286)
							(mid 0.239121 -0.264521)
							(end 0.2032 -0.2794)
						)
					)
					(width 0)
					(fill yes)
				)
			)
		)
		(pad "2" smd custom
			(at 0 0.4318)
			(size 0.127 0.127)
			(layers "F.Cu" "F.Mask" "F.Paste")
			(net "XDP_RTEST#")
			(options
				(clearance outline)
				(anchor circle)
			)
			(primitives
				(gr_poly
					(pts
						(arc
							(start -0.2032 -0.2794)
							(mid -0.239121 -0.264521)
							(end -0.254 -0.2286)
						)
						(arc
							(start -0.254 0.2286)
							(mid -0.239121 0.264521)
							(end -0.2032 0.2794)
						)
						(arc
							(start 0.2032 0.2794)
							(mid 0.239121 0.264521)
							(end 0.254 0.2286)
						)
						(arc
							(start 0.254 -0.2286)
							(mid 0.239121 -0.264521)
							(end 0.2032 -0.2794)
						)
					)
					(width 0)
					(fill yes)
				)
			)
		)
	)
	(footprint ""
		(layer "F.Cu")
		(at 52.2224 -12.827 180)
		(property "Reference" "C315"
			(at 0 0 180)
			(layer "F.SilkS")
			(hide yes)
			(effects
				(font
					(size 1.27 1.27)
				)
			)
		)
		(property "Value" "SCD047U25V2KX-GP"
			(at 1.8923 -1.2065 180)
			(unlocked yes)
			(layer "F.Fab")
			(hide yes)
			(effects
				(font
					(size 1.016 1.016)
					(thickness 0.1524)
				)
			)
		)
		(property "Device Type" "C402H22"
			(at 1.8923 -2.7305 180)
			(unlocked yes)
			(layer "F.Fab")
			(hide yes)
			(effects
				(font
					(size 1.016 1.016)
					(thickness 0.1524)
				)
			)
		)
		(duplicate_pad_numbers_are_jumpers no)
		(fp_rect
			(start -0.381 0.7366)
			(end 0.381 -0.7366)
			(stroke
				(width 0)
				(type default)
			)
			(fill no)
			(layer "F.CrtYd")
		)
		(fp_rect
			(start -0.381 0.7366)
			(end 0.381 -0.7366)
			(stroke
				(width 0)
				(type default)
			)
			(fill no)
			(layer "F.Fab")
		)
		(pad "1" smd custom
			(at 0 -0.4572 180)
			(size 0.1143 0.1143)
			(layers "F.Cu" "F.Mask" "F.Paste")
			(net "CPU_GBE_RX_C_DN0")
			(options
				(clearance outline)
				(anchor circle)
			)
			(primitives
				(gr_poly
					(pts
						(arc
							(start -0.254 -0.1778)
							(mid -0.239121 -0.213721)
							(end -0.2032 -0.2286)
						)
						(arc
							(start 0.2032 -0.2286)
							(mid 0.239121 -0.213721)
							(end 0.254 -0.1778)
						)
						(arc
							(start 0.254 0.1778)
							(mid 0.239121 0.213721)
							(end 0.2032 0.2286)
						)
						(arc
							(start -0.2032 0.2286)
							(mid -0.239121 0.213721)
							(end -0.254 0.1778)
						)
					)
					(width 0)
					(fill yes)
				)
			)
		)
		(pad "2" smd custom
			(at 0 0.4572 180)
			(size 0.1143 0.1143)
			(layers "F.Cu" "F.Mask" "F.Paste")
			(net "CPU_GBE_RX_DN0")
			(options
				(clearance outline)
				(anchor circle)
			)
			(primitives
				(gr_poly
					(pts
						(arc
							(start -0.254 -0.1778)
							(mid -0.239121 -0.213721)
							(end -0.2032 -0.2286)
						)
						(arc
							(start 0.2032 -0.2286)
							(mid 0.239121 -0.213721)
							(end 0.254 -0.1778)
						)
						(arc
							(start 0.254 0.1778)
							(mid 0.239121 0.213721)
							(end 0.2032 0.2286)
						)
						(arc
							(start -0.2032 0.2286)
							(mid -0.239121 0.213721)
							(end -0.254 0.1778)
						)
					)
					(width 0)
					(fill yes)
				)
			)
		)
	)
	(footprint ""
		(layer "F.Cu")
		(at 16.2052 -52.578)
		(property "Reference" "PR76"
			(at 0 0 0)
			(layer "F.SilkS")
			(hide yes)
			(effects
				(font
					(size 1.27 1.27)
				)
			)
		)
		(property "Value" "5K6R2F-2-GP"
			(at 1.7907 -1.1176 0)
			(unlocked yes)
			(layer "F.Fab")
			(hide yes)
			(effects
				(font
					(size 1.016 1.016)
					(thickness 0.1524)
				)
			)
		)
		(property "Device Type" "R402H16"
			(at 1.7907 -2.6416 0)
			(unlocked yes)
			(layer "F.Fab")
			(hide yes)
			(effects
				(font
					(size 1.016 1.016)
					(thickness 0.1524)
				)
			)
		)
		(duplicate_pad_numbers_are_jumpers no)
		(fp_rect
			(start -0.381 0.8382)
			(end 0.381 -0.8382)
			(stroke
				(width 0)
				(type default)
			)
			(fill no)
			(layer "F.CrtYd")
		)
		(fp_rect
			(start -0.381 0.8382)
			(end 0.381 -0.8382)
			(stroke
				(width 0)
				(type default)
			)
			(fill no)
			(layer "F.Fab")
		)
		(pad "1" smd custom
			(at 0 -0.4318)
			(size 0.127 0.127)
			(layers "F.Cu" "F.Mask" "F.Paste")
			(net "VR_PVCCP_VW")
			(options
				(clearance outline)
				(anchor circle)
			)
			(primitives
				(gr_poly
					(pts
						(arc
							(start -0.2032 -0.2794)
							(mid -0.239121 -0.264521)
							(end -0.254 -0.2286)
						)
						(arc
							(start -0.254 0.2286)
							(mid -0.239121 0.264521)
							(end -0.2032 0.2794)
						)
						(arc
							(start 0.2032 0.2794)
							(mid 0.239121 0.264521)
							(end 0.254 0.2286)
						)
						(arc
							(start 0.254 -0.2286)
							(mid 0.239121 -0.264521)
							(end 0.2032 -0.2794)
						)
					)
					(width 0)
					(fill yes)
				)
			)
		)
		(pad "2" smd custom
			(at 0 0.4318)
			(size 0.127 0.127)
			(layers "F.Cu" "F.Mask" "F.Paste")
			(net "VR_PVCCP_COMP")
			(options
				(clearance outline)
				(anchor circle)
			)
			(primitives
				(gr_poly
					(pts
						(arc
							(start -0.2032 -0.2794)
							(mid -0.239121 -0.264521)
							(end -0.254 -0.2286)
						)
						(arc
							(start -0.254 0.2286)
							(mid -0.239121 0.264521)
							(end -0.2032 0.2794)
						)
						(arc
							(start 0.2032 0.2794)
							(mid 0.239121 0.264521)
							(end 0.254 0.2286)
						)
						(arc
							(start 0.254 -0.2286)
							(mid 0.239121 -0.264521)
							(end 0.2032 -0.2794)
						)
					)
					(width 0)
					(fill yes)
				)
			)
		)
	)
	(footprint ""
		(layer "F.Cu")
		(at 77.978 -12.065 -90)
		(property "Reference" "R398"
			(at 0 0 270)
			(layer "F.SilkS")
			(hide yes)
			(effects
				(font
					(size 1.27 1.27)
				)
			)
		)
		(property "Value" "0R2J-2-GP"
			(at 1.7907 -1.1176 270)
			(unlocked yes)
			(layer "F.Fab")
			(hide yes)
			(effects
				(font
					(size 1.016 1.016)
					(thickness 0.1524)
				)
			)
		)
		(property "Device Type" "R402H16"
			(at 1.7907 -2.6416 270)
			(unlocked yes)
			(layer "F.Fab")
			(hide yes)
			(effects
				(font
					(size 1.016 1.016)
					(thickness 0.1524)
				)
			)
		)
		(duplicate_pad_numbers_are_jumpers no)
		(fp_rect
			(start -0.381 0.8382)
			(end 0.381 -0.8382)
			(stroke
				(width 0)
				(type default)
			)
			(fill no)
			(layer "F.CrtYd")
		)
		(fp_rect
			(start -0.381 0.8382)
			(end 0.381 -0.8382)
			(stroke
				(width 0)
				(type default)
			)
			(fill no)
			(layer "F.Fab")
		)
		(pad "1" smd custom
			(at 0 -0.4318 270)
			(size 0.127 0.127)
			(layers "F.Cu" "F.Mask" "F.Paste")
			(net "PCIE_GF_I2C_R_ALERT#")
			(options
				(clearance outline)
				(anchor circle)
			)
			(primitives
				(gr_poly
					(pts
						(arc
							(start -0.2032 -0.2794)
							(mid -0.239121 -0.264521)
							(end -0.254 -0.2286)
						)
						(arc
							(start -0.254 0.2286)
							(mid -0.239121 0.264521)
							(end -0.2032 0.2794)
						)
						(arc
							(start 0.2032 0.2794)
							(mid 0.239121 0.264521)
							(end 0.254 0.2286)
						)
						(arc
							(start 0.254 -0.2286)
							(mid 0.239121 -0.264521)
							(end 0.2032 -0.2794)
						)
					)
					(width 0)
					(fill yes)
				)
			)
		)
		(pad "2" smd custom
			(at 0 0.4318 270)
			(size 0.127 0.127)
			(layers "F.Cu" "F.Mask" "F.Paste")
			(net "PCIE_GF_I2C_ALERT#")
			(options
				(clearance outline)
				(anchor circle)
			)
			(primitives
				(gr_poly
					(pts
						(arc
							(start -0.2032 -0.2794)
							(mid -0.239121 -0.264521)
							(end -0.254 -0.2286)
						)
						(arc
							(start -0.254 0.2286)
							(mid -0.239121 0.264521)
							(end -0.2032 0.2794)
						)
						(arc
							(start 0.2032 0.2794)
							(mid 0.239121 0.264521)
							(end 0.254 0.2286)
						)
						(arc
							(start 0.254 -0.2286)
							(mid 0.239121 -0.264521)
							(end 0.2032 -0.2794)
						)
					)
					(width 0)
					(fill yes)
				)
			)
		)
	)
	(footprint ""
		(layer "F.Cu")
		(at 47.879 -18.415 -90)
		(property "Reference" "R343"
			(at 0 0 270)
			(layer "F.SilkS")
			(hide yes)
			(effects
				(font
					(size 1.27 1.27)
				)
			)
		)
		(property "Value" "4K7R2F-GP"
			(at 0.064008 -3.993896 270)
			(unlocked yes)
			(layer "F.Fab")
			(hide yes)
			(effects
				(font
					(size 1.016 1.016)
					(thickness 0.1524)
				)
			)
		)
		(property "Device Type" "R402H16"
			(at 0.064008 -5.517896 270)
			(unlocked yes)
			(layer "F.Fab")
			(hide yes)
			(effects
				(font
					(size 1.016 1.016)
					(thickness 0.1524)
				)
			)
		)
		(duplicate_pad_numbers_are_jumpers no)
		(fp_rect
			(start -0.381 0.8382)
			(end 0.381 -0.8382)
			(stroke
				(width 0)
				(type default)
			)
			(fill no)
			(layer "F.CrtYd")
		)
		(fp_rect
			(start -0.381 0.8382)
			(end 0.381 -0.8382)
			(stroke
				(width 0)
				(type default)
			)
			(fill no)
			(layer "F.Fab")
		)
		(pad "1" smd custom
			(at 0 -0.4318 270)
			(size 0.127 0.127)
			(layers "F.Cu" "F.Mask" "F.Paste")
			(net "CLKBUFF_OE3#")
			(options
				(clearance outline)
				(anchor circle)
			)
			(primitives
				(gr_poly
					(pts
						(arc
							(start -0.2032 -0.2794)
							(mid -0.239121 -0.264521)
							(end -0.254 -0.2286)
						)
						(arc
							(start -0.254 0.2286)
							(mid -0.239121 0.264521)
							(end -0.2032 0.2794)
						)
						(arc
							(start 0.2032 0.2794)
							(mid 0.239121 0.264521)
							(end 0.254 0.2286)
						)
						(arc
							(start 0.254 -0.2286)
							(mid 0.239121 -0.264521)
							(end 0.2032 -0.2794)
						)
					)
					(width 0)
					(fill yes)
				)
			)
		)
		(pad "2" smd custom
			(at 0 0.4318 270)
			(size 0.127 0.127)
			(layers "F.Cu" "F.Mask" "F.Paste")
			(net "GND")
			(options
				(clearance outline)
				(anchor circle)
			)
			(primitives
				(gr_poly
					(pts
						(arc
							(start -0.2032 -0.2794)
							(mid -0.239121 -0.264521)
							(end -0.254 -0.2286)
						)
						(arc
							(start -0.254 0.2286)
							(mid -0.239121 0.264521)
							(end -0.2032 0.2794)
						)
						(arc
							(start 0.2032 0.2794)
							(mid 0.239121 0.264521)
							(end 0.254 0.2286)
						)
						(arc
							(start 0.254 -0.2286)
							(mid 0.239121 -0.264521)
							(end 0.2032 -0.2794)
						)
					)
					(width 0)
					(fill yes)
				)
			)
		)
	)
	(footprint ""
		(layer "F.Cu")
		(at 40.767 -42.926)
		(property "Reference" "U6"
			(at 0 0 0)
			(layer "F.SilkS")
			(hide yes)
			(effects
				(font
					(size 1.27 1.27)
				)
			)
		)
		(property "Value" "SN74LVC1G14DCKR-GP"
			(at 0 -8.0772 0)
			(unlocked yes)
			(layer "F.Fab")
			(hide yes)
			(effects
				(font
					(size 1.016 1.016)
					(thickness 0.1524)
				)
			)
		)
		(property "Device Type" "SC70-5H44"
			(at 0 -9.6012 0)
			(unlocked yes)
			(layer "F.Fab")
			(hide yes)
			(effects
				(font
					(size 1.016 1.016)
					(thickness 0.1524)
				)
			)
		)
		(duplicate_pad_numbers_are_jumpers no)
		(fp_line
			(start -1.0033 -0.3302)
			(end 1.0033 -0.3302)
			(stroke
				(width 0.1524)
				(type default)
			)
			(layer "F.SilkS")
		)
		(fp_line
			(start -1.0033 0.3302)
			(end -1.0033 -0.3302)
			(stroke
				(width 0.1524)
				(type default)
			)
			(layer "F.SilkS")
		)
		(fp_line
			(start 1.0033 -0.3302)
			(end 1.0033 0.3302)
			(stroke
				(width 0.1524)
				(type default)
			)
			(layer "F.SilkS")
		)
		(fp_line
			(start 1.0033 0.3302)
			(end -1.0033 0.3302)
			(stroke
				(width 0.1524)
				(type default)
			)
			(layer "F.SilkS")
		)
		(fp_poly
			(pts
				(xy -1.0033 1.4859) (xy -1.0033 0.8001) (xy -1.1811 0.8001) (xy -1.1811 -0.8001) (xy -1.0033 -0.8001)
				(xy -1.0033 -1.4859) (xy 1.0033 -1.4859) (xy 1.0033 -0.8001) (xy 1.1811 -0.8001) (xy 1.1811 0.8001)
				(xy 1.0033 0.8001) (xy 1.0033 1.4859) (xy 0.2921 1.4859) (xy 0.2921 0.8001) (xy -0.2921 0.8001)
				(xy -0.2921 1.4859)
			)
			(stroke
				(width 0)
				(type default)
			)
			(fill no)
			(layer "F.CrtYd")
		)
		(fp_poly
			(pts
				(xy -1.0033 1.4859) (xy -1.0033 0.8001) (xy -1.1811 0.8001) (xy -1.1811 -0.8001) (xy -1.0033 -0.8001)
				(xy -1.0033 -1.4859) (xy 1.0033 -1.4859) (xy 1.0033 -0.8001) (xy 1.1811 -0.8001) (xy 1.1811 0.8001)
				(xy 1.0033 0.8001) (xy 1.0033 1.4859) (xy 0.2921 1.4859) (xy 0.2921 0.8001) (xy -0.2921 0.8001)
				(xy -0.2921 1.4859)
			)
			(stroke
				(width 0)
				(type default)
			)
			(fill no)
			(layer "F.Fab")
		)
		(pad "1" smd rect
			(at 0.65024 -0.93472)
			(size 0.3556 0.762)
			(layers "F.Cu" "F.Mask" "F.Paste")
			(net "Net_446")
		)
		(pad "2" smd rect
			(at 0 -0.93472)
			(size 0.3556 0.762)
			(layers "F.Cu" "F.Mask" "F.Paste")
			(net "P3V3_CPU_PG_S1")
		)
		(pad "3" smd rect
			(at -0.65024 -0.93472)
			(size 0.3556 0.762)
			(layers "F.Cu" "F.Mask" "F.Paste")
			(net "GND")
		)
		(pad "4" smd rect
			(at -0.65024 0.93472)
			(size 0.3556 0.762)
			(layers "F.Cu" "F.Mask" "F.Paste")
			(net "P3V3_CPU_PG_S2")
		)
		(pad "5" smd rect
			(at 0.65024 0.93472)
			(size 0.3556 0.762)
			(layers "F.Cu" "F.Mask" "F.Paste")
			(net "P3V3_STBY")
		)
	)
	(footprint ""
		(layer "F.Cu")
		(at 27.305 -17.9451)
		(property "Reference" "SW3"
			(at 0 0 0)
			(layer "F.SilkS")
			(hide yes)
			(effects
				(font
					(size 1.27 1.27)
				)
			)
		)
		(property "Value" "SW-PUSH-2P-6-GP"
			(at -4.2291 1.2573 0)
			(unlocked yes)
			(layer "F.Fab")
			(hide yes)
			(effects
				(font
					(size 1.016 1.016)
					(thickness 0.1524)
				)
			)
		)
		(property "Device Type" "TL1015AF160QG-2"
			(at -4.2291 -0.2667 0)
			(unlocked yes)
			(layer "F.Fab")
			(hide yes)
			(effects
				(font
					(size 1.016 1.016)
					(thickness 0.1524)
				)
			)
		)
		(duplicate_pad_numbers_are_jumpers no)
		(fp_poly
			(pts
				(xy -2.726944 0.01905) (xy -3.29057 0.582676) (xy -3.29057 -0.544576)
			)
			(stroke
				(width 0)
				(type default)
			)
			(fill yes)
			(layer "F.SilkS")
		)
		(fp_poly
			(pts
				(xy -2.2098 1.905) (xy -2.2098 0.8255) (xy -2.6797 0.8255) (xy -2.6797 -0.8255) (xy -2.2098 -0.8255)
				(xy -2.2098 -1.905) (xy 2.2098 -1.905) (xy 2.2098 -0.8255) (xy 2.6797 -0.8255) (xy 2.6797 0.8255)
				(xy 2.2098 0.8255) (xy 2.2098 1.905)
			)
			(stroke
				(width 0)
				(type default)
			)
			(fill no)
			(layer "F.CrtYd")
		)
		(fp_poly
			(pts
				(xy -2.2098 1.905) (xy -2.2098 0.8255) (xy -2.6797 0.8255) (xy -2.6797 -0.8255) (xy -2.2098 -0.8255)
				(xy -2.2098 -1.905) (xy 2.2098 -1.905) (xy 2.2098 -0.8255) (xy 2.6797 -0.8255) (xy 2.6797 0.8255)
				(xy 2.2098 0.8255) (xy 2.2098 1.905)
			)
			(stroke
				(width 0)
				(type default)
			)
			(fill no)
			(layer "F.Fab")
		)
		(pad "1" smd rect
			(at -2.074926 0)
			(size 0.9398 1.397)
			(layers "F.Cu" "F.Mask" "F.Paste")
			(net "GND")
		)
		(pad "2" smd rect
			(at 2.074926 0)
			(size 0.9398 1.397)
			(layers "F.Cu" "F.Mask" "F.Paste")
			(net "XDP_BUF_RTEST#")
		)
		(zone
			(layer "F.Cu")
			(hatch none 0.5)
			(connect_pads
				(clearance 0)
			)
			(min_thickness 0.25)
			(keepout
				(tracks not_allowed)
				(vias allowed)
				(pads allowed)
				(copperpour not_allowed)
				(footprints allowed)
			)
			(placement
				(enabled no)
				(sheetname "")
			)
			(fill
				(thermal_gap 0.5)
				(thermal_bridge_width 0.5)
				(island_removal_mode 0)
			)
			(polygon
				(pts
					(xy 25.15489 -19.84502) (xy 25.15489 -19.095212) (xy 26.305002 -19.095212) (xy 26.305002 -19.84502)
				)
			)
		)
		(zone
			(layer "F.Cu")
			(hatch none 0.5)
			(connect_pads
				(clearance 0)
			)
			(min_thickness 0.25)
			(keepout
				(tracks allowed)
				(vias not_allowed)
				(pads allowed)
				(copperpour not_allowed)
				(footprints allowed)
			)
			(placement
				(enabled no)
				(sheetname "")
			)
			(fill
				(thermal_gap 0.5)
				(thermal_bridge_width 0.5)
				(island_removal_mode 0)
			)
			(polygon
				(pts
					(xy 25.15489 -19.095212) (xy 26.305002 -19.095212) (xy 26.305002 -19.84502) (xy 25.15489 -19.84502)
				)
			)
		)
		(zone
			(layer "F.Cu")
			(hatch none 0.5)
			(connect_pads
				(clearance 0)
			)
			(min_thickness 0.25)
			(keepout
				(tracks not_allowed)
				(vias allowed)
				(pads allowed)
				(copperpour not_allowed)
				(footprints allowed)
			)
			(placement
				(enabled no)
				(sheetname "")
			)
			(fill
				(thermal_gap 0.5)
				(thermal_bridge_width 0.5)
				(island_removal_mode 0)
			)
			(polygon
				(pts
					(xy 25.15489 -16.794988) (xy 25.15489 -16.04518) (xy 26.305002 -16.04518) (xy 26.305002 -16.794988)
				)
			)
		)
		(zone
			(layer "F.Cu")
			(hatch none 0.5)
			(connect_pads
				(clearance 0)
			)
			(min_thickness 0.25)
			(keepout
				(tracks allowed)
				(vias not_allowed)
				(pads allowed)
				(copperpour not_allowed)
				(footprints allowed)
			)
			(placement
				(enabled no)
				(sheetname "")
			)
			(fill
				(thermal_gap 0.5)
				(thermal_bridge_width 0.5)
				(island_removal_mode 0)
			)
			(polygon
				(pts
					(xy 25.15489 -16.04518) (xy 26.305002 -16.04518) (xy 26.305002 -16.794988) (xy 25.15489 -16.794988)
				)
			)
		)
		(zone
			(layer "F.Cu")
			(hatch none 0.5)
			(connect_pads
				(clearance 0)
			)
			(min_thickness 0.25)
			(keepout
				(tracks not_allowed)
				(vias allowed)
				(pads allowed)
				(copperpour not_allowed)
				(footprints allowed)
			)
			(placement
				(enabled no)
				(sheetname "")
			)
			(fill
				(thermal_gap 0.5)
				(thermal_bridge_width 0.5)
				(island_removal_mode 0)
			)
			(polygon
				(pts
					(xy 28.304998 -19.84502) (xy 28.304998 -19.095212) (xy 29.45511 -19.095212) (xy 29.45511 -19.84502)
				)
			)
		)
		(zone
			(layer "F.Cu")
			(hatch none 0.5)
			(connect_pads
				(clearance 0)
			)
			(min_thickness 0.25)
			(keepout
				(tracks allowed)
				(vias not_allowed)
				(pads allowed)
				(copperpour not_allowed)
				(footprints allowed)
			)
			(placement
				(enabled no)
				(sheetname "")
			)
			(fill
				(thermal_gap 0.5)
				(thermal_bridge_width 0.5)
				(island_removal_mode 0)
			)
			(polygon
				(pts
					(xy 28.304998 -19.095212) (xy 29.45511 -19.095212) (xy 29.45511 -19.84502) (xy 28.304998 -19.84502)
				)
			)
		)
		(zone
			(layer "F.Cu")
			(hatch none 0.5)
			(connect_pads
				(clearance 0)
			)
			(min_thickness 0.25)
			(keepout
				(tracks not_allowed)
				(vias allowed)
				(pads allowed)
				(copperpour not_allowed)
				(footprints allowed)
			)
			(placement
				(enabled no)
				(sheetname "")
			)
			(fill
				(thermal_gap 0.5)
				(thermal_bridge_width 0.5)
				(island_removal_mode 0)
			)
			(polygon
				(pts
					(xy 28.304998 -16.794988) (xy 28.304998 -16.04518) (xy 29.45511 -16.04518) (xy 29.45511 -16.794988)
				)
			)
		)
		(zone
			(layer "F.Cu")
			(hatch none 0.5)
			(connect_pads
				(clearance 0)
			)
			(min_thickness 0.25)
			(keepout
				(tracks allowed)
				(vias not_allowed)
				(pads allowed)
				(copperpour not_allowed)
				(footprints allowed)
			)
			(placement
				(enabled no)
				(sheetname "")
			)
			(fill
				(thermal_gap 0.5)
				(thermal_bridge_width 0.5)
				(island_removal_mode 0)
			)
			(polygon
				(pts
					(xy 28.304998 -16.04518) (xy 29.45511 -16.04518) (xy 29.45511 -16.794988) (xy 28.304998 -16.794988)
				)
			)
		)
	)
	(footprint ""
		(layer "F.Cu")
		(at 141.859 -47.4472 -90)
		(property "Reference" "R433"
			(at 0 0 270)
			(layer "F.SilkS")
			(hide yes)
			(effects
				(font
					(size 1.27 1.27)
				)
			)
		)
		(property "Value" "1KR2F-3-GP"
			(at 1.7907 -1.1176 270)
			(unlocked yes)
			(layer "F.Fab")
			(hide yes)
			(effects
				(font
					(size 1.016 1.016)
					(thickness 0.1524)
				)
			)
		)
		(property "Device Type" "R402H16"
			(at 1.7907 -2.6416 270)
			(unlocked yes)
			(layer "F.Fab")
			(hide yes)
			(effects
				(font
					(size 1.016 1.016)
					(thickness 0.1524)
				)
			)
		)
		(duplicate_pad_numbers_are_jumpers no)
		(fp_rect
			(start -0.381 0.8382)
			(end 0.381 -0.8382)
			(stroke
				(width 0)
				(type default)
			)
			(fill no)
			(layer "F.CrtYd")
		)
		(fp_rect
			(start -0.381 0.8382)
			(end 0.381 -0.8382)
			(stroke
				(width 0)
				(type default)
			)
			(fill no)
			(layer "F.Fab")
		)
		(pad "1" smd custom
			(at 0 -0.4318 270)
			(size 0.127 0.127)
			(layers "F.Cu" "F.Mask" "F.Paste")
			(net "JTAG_PLD_TMS")
			(options
				(clearance outline)
				(anchor circle)
			)
			(primitives
				(gr_poly
					(pts
						(arc
							(start -0.2032 -0.2794)
							(mid -0.239121 -0.264521)
							(end -0.254 -0.2286)
						)
						(arc
							(start -0.254 0.2286)
							(mid -0.239121 0.264521)
							(end -0.2032 0.2794)
						)
						(arc
							(start 0.2032 0.2794)
							(mid 0.239121 0.264521)
							(end 0.254 0.2286)
						)
						(arc
							(start 0.254 -0.2286)
							(mid 0.239121 -0.264521)
							(end 0.2032 -0.2794)
						)
					)
					(width 0)
					(fill yes)
				)
			)
		)
		(pad "2" smd custom
			(at 0 0.4318 270)
			(size 0.127 0.127)
			(layers "F.Cu" "F.Mask" "F.Paste")
			(net "GND")
			(options
				(clearance outline)
				(anchor circle)
			)
			(primitives
				(gr_poly
					(pts
						(arc
							(start -0.2032 -0.2794)
							(mid -0.239121 -0.264521)
							(end -0.254 -0.2286)
						)
						(arc
							(start -0.254 0.2286)
							(mid -0.239121 0.264521)
							(end -0.2032 0.2794)
						)
						(arc
							(start 0.2032 0.2794)
							(mid 0.239121 0.264521)
							(end 0.254 0.2286)
						)
						(arc
							(start 0.254 -0.2286)
							(mid 0.239121 -0.264521)
							(end 0.2032 -0.2794)
						)
					)
					(width 0)
					(fill yes)
				)
			)
		)
	)
	(footprint ""
		(layer "F.Cu")
		(at 141.2748 -56.8198 -90)
		(property "Reference" "PR67"
			(at 0 0 270)
			(layer "F.SilkS")
			(hide yes)
			(effects
				(font
					(size 1.27 1.27)
				)
			)
		)
		(property "Value" "0R2J-2-GP"
			(at 0.064008 -3.993896 270)
			(unlocked yes)
			(layer "F.Fab")
			(hide yes)
			(effects
				(font
					(size 1.016 1.016)
					(thickness 0.1524)
				)
			)
		)
		(property "Device Type" "R402H16"
			(at 0.064008 -5.517896 270)
			(unlocked yes)
			(layer "F.Fab")
			(hide yes)
			(effects
				(font
					(size 1.016 1.016)
					(thickness 0.1524)
				)
			)
		)
		(duplicate_pad_numbers_are_jumpers no)
		(fp_rect
			(start -0.381 0.8382)
			(end 0.381 -0.8382)
			(stroke
				(width 0)
				(type default)
			)
			(fill no)
			(layer "F.CrtYd")
		)
		(fp_rect
			(start -0.381 0.8382)
			(end 0.381 -0.8382)
			(stroke
				(width 0)
				(type default)
			)
			(fill no)
			(layer "F.Fab")
		)
		(pad "1" smd custom
			(at 0 -0.4318 270)
			(size 0.127 0.127)
			(layers "F.Cu" "F.Mask" "F.Paste")
			(net "PWRGD_PVTT_PG")
			(options
				(clearance outline)
				(anchor circle)
			)
			(primitives
				(gr_poly
					(pts
						(arc
							(start -0.2032 -0.2794)
							(mid -0.239121 -0.264521)
							(end -0.254 -0.2286)
						)
						(arc
							(start -0.254 0.2286)
							(mid -0.239121 0.264521)
							(end -0.2032 0.2794)
						)
						(arc
							(start 0.2032 0.2794)
							(mid 0.239121 0.264521)
							(end 0.254 0.2286)
						)
						(arc
							(start 0.254 -0.2286)
							(mid 0.239121 -0.264521)
							(end 0.2032 -0.2794)
						)
					)
					(width 0)
					(fill yes)
				)
			)
		)
		(pad "2" smd custom
			(at 0 0.4318 270)
			(size 0.127 0.127)
			(layers "F.Cu" "F.Mask" "F.Paste")
			(net "PV_VTT_DDR_R_PG")
			(options
				(clearance outline)
				(anchor circle)
			)
			(primitives
				(gr_poly
					(pts
						(arc
							(start -0.2032 -0.2794)
							(mid -0.239121 -0.264521)
							(end -0.254 -0.2286)
						)
						(arc
							(start -0.254 0.2286)
							(mid -0.239121 0.264521)
							(end -0.2032 0.2794)
						)
						(arc
							(start 0.2032 0.2794)
							(mid 0.239121 0.264521)
							(end 0.254 0.2286)
						)
						(arc
							(start 0.254 -0.2286)
							(mid 0.239121 -0.264521)
							(end 0.2032 -0.2794)
						)
					)
					(width 0)
					(fill yes)
				)
			)
		)
	)
	(footprint ""
		(layer "F.Cu")
		(at 69.342 -12.827 90)
		(property "Reference" "U42"
			(at 0 0 90)
			(layer "F.SilkS")
			(hide yes)
			(effects
				(font
					(size 1.27 1.27)
				)
			)
		)
		(property "Value" "SN74LVC1G11DCKR-GP"
			(at -4.897374 3.525266 90)
			(unlocked yes)
			(layer "F.Fab")
			(hide yes)
			(effects
				(font
					(size 1.016 1.016)
					(thickness 0.1524)
				)
			)
		)
		(property "Device Type" "UMT6H44"
			(at -4.897374 2.001266 90)
			(unlocked yes)
			(layer "F.Fab")
			(hide yes)
			(effects
				(font
					(size 1.016 1.016)
					(thickness 0.1524)
				)
			)
		)
		(duplicate_pad_numbers_are_jumpers no)
		(fp_line
			(start 1.0033 -0.3556)
			(end -1.0033 -0.3556)
			(stroke
				(width 0.1524)
				(type default)
			)
			(layer "F.SilkS")
		)
		(fp_line
			(start -1.0033 -0.3556)
			(end -1.0033 0.3556)
			(stroke
				(width 0.1524)
				(type default)
			)
			(layer "F.SilkS")
		)
		(fp_line
			(start -1.1557 0.2921)
			(end -1.1557 1.2954)
			(stroke
				(width 0.254)
				(type default)
			)
			(layer "F.SilkS")
		)
		(fp_line
			(start 1.0033 0.3556)
			(end 1.0033 -0.3556)
			(stroke
				(width 0.1524)
				(type default)
			)
			(layer "F.SilkS")
		)
		(fp_line
			(start -1.0033 0.3556)
			(end 1.0033 0.3556)
			(stroke
				(width 0.1524)
				(type default)
			)
			(layer "F.SilkS")
		)
		(fp_poly
			(pts
				(xy -1.016 0.3556) (xy 1.016 0.3556) (xy 1.016 -0.3556) (xy -1.016 -0.3556)
			)
			(stroke
				(width 0)
				(type default)
			)
			(fill yes)
			(layer "F.SilkS")
		)
		(fp_poly
			(pts
				(xy -1.0033 -0.8763) (xy -1.2573 -0.8763) (xy -1.2573 0.8763) (xy -0.9906 0.8763) (xy -0.9906 1.4097)
				(xy 0.9906 1.4097) (xy 0.9906 0.8763) (xy 1.2573 0.8763) (xy 1.2573 -0.8763) (xy 0.9906 -0.8763)
				(xy 0.9906 -1.4097) (xy -0.9906 -1.4097) (xy -0.9906 -0.8763)
			)
			(stroke
				(width 0)
				(type default)
			)
			(fill no)
			(layer "F.CrtYd")
		)
		(fp_poly
			(pts
				(xy -1.0033 -0.8763) (xy -1.2573 -0.8763) (xy -1.2573 0.8763) (xy -1.0033 0.8763) (xy -0.9906 0.8763)
				(xy -0.9906 1.4097) (xy 0.9906 1.4097) (xy 0.9906 0.8763) (xy 1.0033 0.8763) (xy 1.2573 0.8763)
				(xy 1.2573 -0.8763) (xy 1.0033 -0.8763) (xy 0.9906 -0.8763) (xy 0.9906 -1.4097) (xy -0.9906 -1.4097)
				(xy -0.9906 -0.8763)
			)
			(stroke
				(width 0)
				(type default)
			)
			(fill no)
			(layer "F.Fab")
		)
		(pad "1" smd rect
			(at -0.65024 0.94996 90)
			(size 0.4064 0.6604)
			(layers "F.Cu" "F.Mask" "F.Paste")
			(net "BMC_SYS_RESET#")
		)
		(pad "2" smd rect
			(at 0 0.94996 90)
			(size 0.4064 0.6604)
			(layers "F.Cu" "F.Mask" "F.Paste")
			(net "GND")
		)
		(pad "3" smd rect
			(at 0.65024 0.94996 90)
			(size 0.4064 0.6604)
			(layers "F.Cu" "F.Mask" "F.Paste")
			(net "HOST_LV_RSTBTN#")
		)
		(pad "4" smd rect
			(at 0.65024 -0.94996 90)
			(size 0.4064 0.6604)
			(layers "F.Cu" "F.Mask" "F.Paste")
			(net "PMU_RESETBUTTON#")
		)
		(pad "5" smd rect
			(at 0 -0.94996 90)
			(size 0.4064 0.6604)
			(layers "F.Cu" "F.Mask" "F.Paste")
			(net "P3V3")
		)
		(pad "6" smd rect
			(at -0.65024 -0.94996 90)
			(size 0.4064 0.6604)
			(layers "F.Cu" "F.Mask" "F.Paste")
			(net "XDP_RST_BTN_R#")
		)
	)
	(footprint ""
		(layer "F.Cu")
		(at 36.576 -27.305 90)
		(property "Reference" "CN4"
			(at 0 0 90)
			(layer "F.SilkS")
			(hide yes)
			(effects
				(font
					(size 1.27 1.27)
				)
			)
		)
		(property "Value" "SMC-CONN60A-GP"
			(at -0.7874 -13.1826 90)
			(unlocked yes)
			(layer "F.Fab")
			(hide yes)
			(effects
				(font
					(size 1.016 1.016)
					(thickness 0.1524)
				)
			)
		)
		(property "Device Type" "BSH-03001-FDA"
			(at -0.7874 -14.7066 90)
			(unlocked yes)
			(layer "F.Fab")
			(hide yes)
			(effects
				(font
					(size 1.016 1.016)
					(thickness 0.1524)
				)
			)
		)
		(duplicate_pad_numbers_are_jumpers no)
		(fp_line
			(start 10.1473 -1.4478)
			(end 10.9093 -0.6858)
			(stroke
				(width 0.3048)
				(type default)
			)
			(layer "F.SilkS")
		)
		(fp_line
			(start -10.9093 -0.6858)
			(end -10.1473 -1.4478)
			(stroke
				(width 0.3048)
				(type default)
			)
			(layer "F.SilkS")
		)
		(fp_poly
			(pts
				(xy -7.268464 6.785102) (xy -7.903464 7.420102) (xy -6.633464 7.420102)
			)
			(stroke
				(width 0)
				(type default)
			)
			(fill yes)
			(layer "F.SilkS")
		)
		(fp_rect
			(start -10.9093 6.7818)
			(end 10.9093 -1.4478)
			(stroke
				(width 0)
				(type default)
			)
			(fill no)
			(layer "F.CrtYd")
		)
		(fp_rect
			(start -10.9093 6.7818)
			(end 10.9093 -1.4478)
			(stroke
				(width 0)
				(type default)
			)
			(fill no)
			(layer "F.Fab")
		)
		(pad "" np_thru_hole circle
			(at -10.06475 0 90)
			(size 0.254 0.254)
			(drill 1.016)
			(layers "*.Cu" "*.Mask")
			(clearance 0.7366)
			(thermal_gap 0.7366)
		)
		(pad "" np_thru_hole circle
			(at 10.06475 0 90)
			(size 0.254 0.254)
			(drill 1.016)
			(layers "*.Cu" "*.Mask")
			(clearance 0.7366)
			(thermal_gap 0.7366)
		)
		(pad "1" smd rect
			(at -7.25043 5.52577 90)
			(size 0.2794 2.2606)
			(layers "F.Cu" "F.Mask" "F.Paste")
			(net "GND")
		)
		(pad "2" smd rect
			(at -7.25043 -0.19812 90)
			(size 0.2794 2.2606)
			(layers "F.Cu" "F.Mask" "F.Paste")
			(net "GND")
		)
		(pad "3" smd rect
			(at -6.75005 5.52577 90)
			(size 0.2794 2.2606)
			(layers "F.Cu" "F.Mask" "F.Paste")
			(net "XDP_CPU_PREQ#")
		)
		(pad "4" smd rect
			(at -6.75005 -0.19812 90)
			(size 0.2794 2.2606)
			(layers "F.Cu" "F.Mask" "F.Paste")
			(net "XDP_DFX_PORT_R_CLK0")
		)
		(pad "5" smd rect
			(at -6.24967 5.52577 90)
			(size 0.2794 2.2606)
			(layers "F.Cu" "F.Mask" "F.Paste")
			(net "XDP_CPU_PRDY#")
		)
		(pad "6" smd rect
			(at -6.24967 -0.19812 90)
			(size 0.2794 2.2606)
			(layers "F.Cu" "F.Mask" "F.Paste")
			(net "XDP_DFX_PORT_R_CLK1")
		)
		(pad "7" smd rect
			(at -5.75056 5.52577 90)
			(size 0.2794 2.2606)
			(layers "F.Cu" "F.Mask" "F.Paste")
			(net "GND")
		)
		(pad "8" smd rect
			(at -5.75056 -0.19812 90)
			(size 0.2794 2.2606)
			(layers "F.Cu" "F.Mask" "F.Paste")
			(net "GND")
		)
		(pad "9" smd rect
			(at -5.25018 5.52577 90)
			(size 0.2794 2.2606)
			(layers "F.Cu" "F.Mask" "F.Paste")
			(net "XDP_DFX_PORT0")
		)
		(pad "10" smd rect
			(at -5.25018 -0.19812 90)
			(size 0.2794 2.2606)
			(layers "F.Cu" "F.Mask" "F.Paste")
			(net "XDP_DFX_PORT8")
		)
		(pad "11" smd rect
			(at -4.7498 5.52577 90)
			(size 0.2794 2.2606)
			(layers "F.Cu" "F.Mask" "F.Paste")
			(net "XDP_DFX_PORT1")
		)
		(pad "12" smd rect
			(at -4.7498 -0.19812 90)
			(size 0.2794 2.2606)
			(layers "F.Cu" "F.Mask" "F.Paste")
			(net "XDP_DFX_PORT9")
		)
		(pad "13" smd rect
			(at -4.24942 5.52577 90)
			(size 0.2794 2.2606)
			(layers "F.Cu" "F.Mask" "F.Paste")
			(net "GND")
		)
		(pad "14" smd rect
			(at -4.24942 -0.19812 90)
			(size 0.2794 2.2606)
			(layers "F.Cu" "F.Mask" "F.Paste")
			(net "GND")
		)
		(pad "15" smd rect
			(at -3.75031 5.52577 90)
			(size 0.2794 2.2606)
			(layers "F.Cu" "F.Mask" "F.Paste")
			(net "XDP_DFX_PORT2")
		)
		(pad "16" smd rect
			(at -3.75031 -0.19812 90)
			(size 0.2794 2.2606)
			(layers "F.Cu" "F.Mask" "F.Paste")
			(net "XDP_DFX_PORT10")
		)
		(pad "17" smd rect
			(at -3.24993 5.52577 90)
			(size 0.2794 2.2606)
			(layers "F.Cu" "F.Mask" "F.Paste")
			(net "XDP_DFX_PORT3")
		)
		(pad "18" smd rect
			(at -3.24993 -0.19812 90)
			(size 0.2794 2.2606)
			(layers "F.Cu" "F.Mask" "F.Paste")
			(net "XDP_DFX_PORT11")
		)
		(pad "19" smd rect
			(at -2.74955 5.52577 90)
			(size 0.2794 2.2606)
			(layers "F.Cu" "F.Mask" "F.Paste")
			(net "GND")
		)
		(pad "20" smd rect
			(at -2.74955 -0.19812 90)
			(size 0.2794 2.2606)
			(layers "F.Cu" "F.Mask" "F.Paste")
			(net "GND")
		)
		(pad "21" smd rect
			(at -2.25044 5.52577 90)
			(size 0.2794 2.2606)
			(layers "F.Cu" "F.Mask" "F.Paste")
			(net "TP_XDP_DFX_PORT_CLK1")
		)
		(pad "22" smd rect
			(at -2.25044 -0.19812 90)
			(size 0.2794 2.2606)
			(layers "F.Cu" "F.Mask" "F.Paste")
			(net "Net_651")
		)
		(pad "23" smd rect
			(at -1.75006 5.52577 90)
			(size 0.2794 2.2606)
			(layers "F.Cu" "F.Mask" "F.Paste")
			(net "Net_649")
		)
		(pad "24" smd rect
			(at -1.75006 -0.19812 90)
			(size 0.2794 2.2606)
			(layers "F.Cu" "F.Mask" "F.Paste")
			(net "Net_650")
		)
		(pad "25" smd rect
			(at -1.24968 5.52577 90)
			(size 0.2794 2.2606)
			(layers "F.Cu" "F.Mask" "F.Paste")
			(net "GND")
		)
		(pad "26" smd rect
			(at -1.24968 -0.19812 90)
			(size 0.2794 2.2606)
			(layers "F.Cu" "F.Mask" "F.Paste")
			(net "GND")
		)
		(pad "27" smd rect
			(at -0.75057 5.52577 90)
			(size 0.2794 2.2606)
			(layers "F.Cu" "F.Mask" "F.Paste")
			(net "XDP_DFX_PORT4")
		)
		(pad "28" smd rect
			(at -0.75057 -0.19812 90)
			(size 0.2794 2.2606)
			(layers "F.Cu" "F.Mask" "F.Paste")
			(net "XDP_DFX_PORT12")
		)
		(pad "29" smd rect
			(at -0.25019 5.52577 90)
			(size 0.2794 2.2606)
			(layers "F.Cu" "F.Mask" "F.Paste")
			(net "XDP_DFX_PORT5")
		)
		(pad "30" smd rect
			(at -0.25019 -0.19812 90)
			(size 0.2794 2.2606)
			(layers "F.Cu" "F.Mask" "F.Paste")
			(net "XDP_DFX_PORT13")
		)
		(pad "31" smd rect
			(at 0.25019 5.52577 90)
			(size 0.2794 2.2606)
			(layers "F.Cu" "F.Mask" "F.Paste")
			(net "GND")
		)
		(pad "32" smd rect
			(at 0.25019 -0.19812 90)
			(size 0.2794 2.2606)
			(layers "F.Cu" "F.Mask" "F.Paste")
			(net "GND")
		)
		(pad "33" smd rect
			(at 0.75057 5.52577 90)
			(size 0.2794 2.2606)
			(layers "F.Cu" "F.Mask" "F.Paste")
			(net "XDP_DFX_PORT6")
		)
		(pad "34" smd rect
			(at 0.75057 -0.19812 90)
			(size 0.2794 2.2606)
			(layers "F.Cu" "F.Mask" "F.Paste")
			(net "XDP_DFX_PORT14")
		)
		(pad "35" smd rect
			(at 1.24968 5.52577 90)
			(size 0.2794 2.2606)
			(layers "F.Cu" "F.Mask" "F.Paste")
			(net "XDP_DFX_PORT7")
		)
		(pad "36" smd rect
			(at 1.24968 -0.19812 90)
			(size 0.2794 2.2606)
			(layers "F.Cu" "F.Mask" "F.Paste")
			(net "XDP_DFX_PORT15")
		)
		(pad "37" smd rect
			(at 1.75006 5.52577 90)
			(size 0.2794 2.2606)
			(layers "F.Cu" "F.Mask" "F.Paste")
			(net "GND")
		)
		(pad "38" smd rect
			(at 1.75006 -0.19812 90)
			(size 0.2794 2.2606)
			(layers "F.Cu" "F.Mask" "F.Paste")
			(net "GND")
		)
		(pad "39" smd rect
			(at 2.25044 5.52577 90)
			(size 0.2794 2.2606)
			(layers "F.Cu" "F.Mask" "F.Paste")
			(net "XDP_RSMRST_R#")
		)
		(pad "40" smd rect
			(at 2.25044 -0.19812 90)
			(size 0.2794 2.2606)
			(layers "F.Cu" "F.Mask" "F.Paste")
			(net "CLK_100M_XDP_R_DP")
		)
		(pad "41" smd rect
			(at 2.74955 5.52577 90)
			(size 0.2794 2.2606)
			(layers "F.Cu" "F.Mask" "F.Paste")
			(net "XDP_PWRBTN_R#")
		)
		(pad "42" smd rect
			(at 2.74955 -0.19812 90)
			(size 0.2794 2.2606)
			(layers "F.Cu" "F.Mask" "F.Paste")
			(net "CLK_100M_XDP_R_DN")
		)
		(pad "43" smd rect
			(at 3.24993 5.52577 90)
			(size 0.2794 2.2606)
			(layers "F.Cu" "F.Mask" "F.Paste")
			(net "P1V0")
		)
		(pad "44" smd rect
			(at 3.24993 -0.19812 90)
			(size 0.2794 2.2606)
			(layers "F.Cu" "F.Mask" "F.Paste")
			(net "VCC_OBS_CD")
		)
		(pad "45" smd rect
			(at 3.75031 5.52577 90)
			(size 0.2794 2.2606)
			(layers "F.Cu" "F.Mask" "F.Paste")
			(net "XDP_PWRGD_IN")
		)
		(pad "46" smd rect
			(at 3.75031 -0.19812 90)
			(size 0.2794 2.2606)
			(layers "F.Cu" "F.Mask" "F.Paste")
			(net "XDP_CPU_R_RESET#")
		)
		(pad "47" smd rect
			(at 4.24942 5.52577 90)
			(size 0.2794 2.2606)
			(layers "F.Cu" "F.Mask" "F.Paste")
			(net "XDP_RTEST#")
		)
		(pad "48" smd rect
			(at 4.24942 -0.19812 90)
			(size 0.2794 2.2606)
			(layers "F.Cu" "F.Mask" "F.Paste")
			(net "XDP_RST_BTN_R#")
		)
		(pad "49" smd rect
			(at 4.7498 5.52577 90)
			(size 0.2794 2.2606)
			(layers "F.Cu" "F.Mask" "F.Paste")
			(net "GND")
		)
		(pad "50" smd rect
			(at 4.7498 -0.19812 90)
			(size 0.2794 2.2606)
			(layers "F.Cu" "F.Mask" "F.Paste")
			(net "GND")
		)
		(pad "51" smd rect
			(at 5.25018 5.52577 90)
			(size 0.2794 2.2606)
			(layers "F.Cu" "F.Mask" "F.Paste")
			(net "SMB_XDP_DATA_R")
		)
		(pad "52" smd rect
			(at 5.25018 -0.19812 90)
			(size 0.2794 2.2606)
			(layers "F.Cu" "F.Mask" "F.Paste")
			(net "XDP_CPU_R_TDO")
		)
		(pad "53" smd rect
			(at 5.75056 5.52577 90)
			(size 0.2794 2.2606)
			(layers "F.Cu" "F.Mask" "F.Paste")
			(net "SMB_XDP_CLK_R")
		)
		(pad "54" smd rect
			(at 5.75056 -0.19812 90)
			(size 0.2794 2.2606)
			(layers "F.Cu" "F.Mask" "F.Paste")
			(net "XDP_SOC_CPU_TRST#")
		)
		(pad "55" smd rect
			(at 6.24967 5.52577 90)
			(size 0.2794 2.2606)
			(layers "F.Cu" "F.Mask" "F.Paste")
			(net "TP_XDP0_TCK1")
		)
		(pad "56" smd rect
			(at 6.24967 -0.19812 90)
			(size 0.2794 2.2606)
			(layers "F.Cu" "F.Mask" "F.Paste")
			(net "TDI_56")
		)
		(pad "57" smd rect
			(at 6.75005 5.52577 90)
			(size 0.2794 2.2606)
			(layers "F.Cu" "F.Mask" "F.Paste")
			(net "XDP_SOC_CPU_TCK")
		)
		(pad "58" smd rect
			(at 6.75005 -0.19812 90)
			(size 0.2794 2.2606)
			(layers "F.Cu" "F.Mask" "F.Paste")
			(net "XDP_SOC_CPU_TMS")
		)
		(pad "59" smd rect
			(at 7.25043 5.52577 90)
			(size 0.2794 2.2606)
			(layers "F.Cu" "F.Mask" "F.Paste")
			(net "GND")
		)
		(pad "60" smd rect
			(at 7.25043 -0.19812 90)
			(size 0.2794 2.2606)
			(layers "F.Cu" "F.Mask" "F.Paste")
			(net "XDP_P60")
		)
		(zone
			(layer "F.Cu")
			(hatch none 0.5)
			(connect_pads
				(clearance 0)
			)
			(min_thickness 0.25)
			(keepout
				(tracks allowed)
				(vias not_allowed)
				(pads allowed)
				(copperpour not_allowed)
				(footprints allowed)
			)
			(placement
				(enabled no)
				(sheetname "")
			)
			(fill
				(thermal_gap 0.5)
				(thermal_bridge_width 0.5)
				(island_removal_mode 0)
			)
			(polygon
				(pts
					(xy 37.50818 -19.91487) (xy 38.01618 -19.91487) (xy 38.01618 -34.69513) (xy 37.50818 -34.69513)
				)
			)
		)
		(zone
			(layer "F.Cu")
			(hatch none 0.5)
			(connect_pads
				(clearance 0)
			)
			(min_thickness 0.25)
			(keepout
				(tracks allowed)
				(vias not_allowed)
				(pads allowed)
				(copperpour not_allowed)
				(footprints allowed)
			)
			(placement
				(enabled no)
				(sheetname "")
			)
			(fill
				(thermal_gap 0.5)
				(thermal_bridge_width 0.5)
				(island_removal_mode 0)
			)
			(polygon
				(pts
					(xy 40.46347 -19.91487) (xy 40.97147 -19.91487) (xy 40.97147 -34.69513) (xy 40.46347 -34.69513)
				)
			)
		)
		(zone
			(layers "F.Cu" "B.Cu" "In1.Cu" "In2.Cu" "In3.Cu" "In4.Cu" "In5.Cu" "In6.Cu"
				"In7.Cu" "In8.Cu" "In9.Cu" "In10.Cu"
			)
			(hatch none 0.5)
			(connect_pads
				(clearance 0)
			)
			(min_thickness 0.25)
			(keepout
				(tracks not_allowed)
				(vias allowed)
				(pads allowed)
				(copperpour not_allowed)
				(footprints allowed)
			)
			(placement
				(enabled no)
				(sheetname "")
			)
			(fill
				(thermal_gap 0.5)
				(thermal_bridge_width 0.5)
				(island_removal_mode 0)
			)
			(polygon
				(pts
					(arc
						(start 37.3888 -37.36975)
						(mid 35.7632 -37.36975)
						(end 37.3888 -37.36975)
					)
				)
			)
		)
		(zone
			(layers "F.Cu" "B.Cu" "In1.Cu" "In2.Cu" "In3.Cu" "In4.Cu" "In5.Cu" "In6.Cu"
				"In7.Cu" "In8.Cu" "In9.Cu" "In10.Cu"
			)
			(hatch none 0.5)
			(connect_pads
				(clearance 0)
			)
			(min_thickness 0.25)
			(keepout
				(tracks not_allowed)
				(vias allowed)
				(pads allowed)
				(copperpour not_allowed)
				(footprints allowed)
			)
			(placement
				(enabled no)
				(sheetname "")
			)
			(fill
				(thermal_gap 0.5)
				(thermal_bridge_width 0.5)
				(island_removal_mode 0)
			)
			(polygon
				(pts
					(arc
						(start 37.3888 -17.24025)
						(mid 35.7632 -17.24025)
						(end 37.3888 -17.24025)
					)
				)
			)
		)
	)
	(footprint ""
		(layer "F.Cu")
		(at 31.877 -37.465 90)
		(property "Reference" "R267"
			(at 0 0 90)
			(layer "F.SilkS")
			(hide yes)
			(effects
				(font
					(size 1.27 1.27)
				)
			)
		)
		(property "Value" "51R2F-2-GP"
			(at 0.064008 -3.993896 90)
			(unlocked yes)
			(layer "F.Fab")
			(hide yes)
			(effects
				(font
					(size 1.016 1.016)
					(thickness 0.1524)
				)
			)
		)
		(property "Device Type" "R402H16"
			(at 0.064008 -5.517896 90)
			(unlocked yes)
			(layer "F.Fab")
			(hide yes)
			(effects
				(font
					(size 1.016 1.016)
					(thickness 0.1524)
				)
			)
		)
		(duplicate_pad_numbers_are_jumpers no)
		(fp_rect
			(start -0.381 0.8382)
			(end 0.381 -0.8382)
			(stroke
				(width 0)
				(type default)
			)
			(fill no)
			(layer "F.CrtYd")
		)
		(fp_rect
			(start -0.381 0.8382)
			(end 0.381 -0.8382)
			(stroke
				(width 0)
				(type default)
			)
			(fill no)
			(layer "F.Fab")
		)
		(pad "1" smd custom
			(at 0 -0.4318 90)
			(size 0.127 0.127)
			(layers "F.Cu" "F.Mask" "F.Paste")
			(net "P1V0_STBY")
			(options
				(clearance outline)
				(anchor circle)
			)
			(primitives
				(gr_poly
					(pts
						(arc
							(start -0.2032 -0.2794)
							(mid -0.239121 -0.264521)
							(end -0.254 -0.2286)
						)
						(arc
							(start -0.254 0.2286)
							(mid -0.239121 0.264521)
							(end -0.2032 0.2794)
						)
						(arc
							(start 0.2032 0.2794)
							(mid 0.239121 0.264521)
							(end 0.254 0.2286)
						)
						(arc
							(start 0.254 -0.2286)
							(mid 0.239121 -0.264521)
							(end 0.2032 -0.2794)
						)
					)
					(width 0)
					(fill yes)
				)
			)
		)
		(pad "2" smd custom
			(at 0 0.4318 90)
			(size 0.127 0.127)
			(layers "F.Cu" "F.Mask" "F.Paste")
			(net "XDP_SOC_CPU_TMS")
			(options
				(clearance outline)
				(anchor circle)
			)
			(primitives
				(gr_poly
					(pts
						(arc
							(start -0.2032 -0.2794)
							(mid -0.239121 -0.264521)
							(end -0.254 -0.2286)
						)
						(arc
							(start -0.254 0.2286)
							(mid -0.239121 0.264521)
							(end -0.2032 0.2794)
						)
						(arc
							(start 0.2032 0.2794)
							(mid 0.239121 0.264521)
							(end 0.254 0.2286)
						)
						(arc
							(start 0.254 -0.2286)
							(mid 0.239121 -0.264521)
							(end 0.2032 -0.2794)
						)
					)
					(width 0)
					(fill yes)
				)
			)
		)
	)
	(footprint ""
		(layer "F.Cu")
		(at 66.294 -42.545)
		(property "Reference" "R49"
			(at 0 0 0)
			(layer "F.SilkS")
			(hide yes)
			(effects
				(font
					(size 1.27 1.27)
				)
			)
		)
		(property "Value" "0R2J-2-GP"
			(at 0.064008 -3.993896 0)
			(unlocked yes)
			(layer "F.Fab")
			(hide yes)
			(effects
				(font
					(size 1.016 1.016)
					(thickness 0.1524)
				)
			)
		)
		(property "Device Type" "R402H16"
			(at 0.064008 -5.517896 0)
			(unlocked yes)
			(layer "F.Fab")
			(hide yes)
			(effects
				(font
					(size 1.016 1.016)
					(thickness 0.1524)
				)
			)
		)
		(duplicate_pad_numbers_are_jumpers no)
		(fp_rect
			(start -0.381 0.8382)
			(end 0.381 -0.8382)
			(stroke
				(width 0)
				(type default)
			)
			(fill no)
			(layer "F.CrtYd")
		)
		(fp_rect
			(start -0.381 0.8382)
			(end 0.381 -0.8382)
			(stroke
				(width 0)
				(type default)
			)
			(fill no)
			(layer "F.Fab")
		)
		(pad "1" smd custom
			(at 0 -0.4318)
			(size 0.127 0.127)
			(layers "F.Cu" "F.Mask" "F.Paste")
			(net "SMB_PECI_LV_R_CLK")
			(options
				(clearance outline)
				(anchor circle)
			)
			(primitives
				(gr_poly
					(pts
						(arc
							(start -0.2032 -0.2794)
							(mid -0.239121 -0.264521)
							(end -0.254 -0.2286)
						)
						(arc
							(start -0.254 0.2286)
							(mid -0.239121 0.264521)
							(end -0.2032 0.2794)
						)
						(arc
							(start 0.2032 0.2794)
							(mid 0.239121 0.264521)
							(end 0.254 0.2286)
						)
						(arc
							(start 0.254 -0.2286)
							(mid 0.239121 -0.264521)
							(end 0.2032 -0.2794)
						)
					)
					(width 0)
					(fill yes)
				)
			)
		)
		(pad "2" smd custom
			(at 0 0.4318)
			(size 0.127 0.127)
			(layers "F.Cu" "F.Mask" "F.Paste")
			(net "SMB_PECI_LV_CLK")
			(options
				(clearance outline)
				(anchor circle)
			)
			(primitives
				(gr_poly
					(pts
						(arc
							(start -0.2032 -0.2794)
							(mid -0.239121 -0.264521)
							(end -0.254 -0.2286)
						)
						(arc
							(start -0.254 0.2286)
							(mid -0.239121 0.264521)
							(end -0.2032 0.2794)
						)
						(arc
							(start 0.2032 0.2794)
							(mid 0.239121 0.264521)
							(end 0.254 0.2286)
						)
						(arc
							(start 0.254 -0.2286)
							(mid 0.239121 -0.264521)
							(end 0.2032 -0.2794)
						)
					)
					(width 0)
					(fill yes)
				)
			)
		)
	)
	(footprint ""
		(layer "F.Cu")
		(at 144.907 -48.387 180)
		(property "Reference" "TP43"
			(at 0 0 180)
			(layer "F.SilkS")
			(hide yes)
			(effects
				(font
					(size 1.27 1.27)
				)
			)
		)
		(property "Value" "TPAD32-GP"
			(at 0 -3.166364 180)
			(unlocked yes)
			(layer "F.Fab")
			(hide yes)
			(effects
				(font
					(size 1.016 1.016)
					(thickness 0.1524)
				)
			)
		)
		(property "Device Type" "TPAD32"
			(at 0 -4.690618 180)
			(unlocked yes)
			(layer "F.Fab")
			(hide yes)
			(effects
				(font
					(size 1.016 1.016)
					(thickness 0.1524)
				)
			)
		)
		(duplicate_pad_numbers_are_jumpers no)
		(fp_poly
			(pts
				(arc
					(start -0.7112 0)
					(mid 0.7112 0)
					(end -0.7112 0)
				)
			)
			(stroke
				(width 0)
				(type default)
			)
			(fill no)
			(layer "F.CrtYd")
		)
		(fp_poly
			(pts
				(arc
					(start -0.7112 0)
					(mid 0.7112 0)
					(end -0.7112 0)
				)
			)
			(stroke
				(width 0)
				(type default)
			)
			(fill no)
			(layer "F.Fab")
		)
		(pad "1" smd circle
			(at 0 0 180)
			(size 0.8128 0.8128)
			(layers "F.Cu" "F.Mask" "F.Paste")
			(net "C_DCLK")
		)
	)
	(footprint ""
		(layer "F.Cu")
		(at 157.607 -33.782 -90)
		(property "Reference" "LED4"
			(at 0 0 270)
			(layer "F.SilkS")
			(hide yes)
			(effects
				(font
					(size 1.27 1.27)
				)
			)
		)
		(property "Value" "LED-YG-51-GP"
			(at -2.6924 -1.4224 270)
			(unlocked yes)
			(layer "F.Fab")
			(hide yes)
			(effects
				(font
					(size 1.016 1.016)
					(thickness 0.1524)
				)
			)
		)
		(property "Device Type" "LED1608AKH40"
			(at -2.6924 -2.9464 270)
			(unlocked yes)
			(layer "F.Fab")
			(hide yes)
			(effects
				(font
					(size 1.016 1.016)
					(thickness 0.1524)
				)
			)
		)
		(duplicate_pad_numbers_are_jumpers no)
		(fp_line
			(start -0.5334 1.3081)
			(end 0.5334 1.3081)
			(stroke
				(width 0.254)
				(type default)
			)
			(layer "F.SilkS")
		)
		(fp_rect
			(start -0.6604 1.1811)
			(end 0.6604 -1.1811)
			(stroke
				(width 0)
				(type default)
			)
			(fill no)
			(layer "F.CrtYd")
		)
		(fp_rect
			(start -0.6604 1.1811)
			(end 0.6604 -1.1811)
			(stroke
				(width 0)
				(type default)
			)
			(fill no)
			(layer "F.Fab")
		)
		(pad "A" smd rect
			(at 0 -0.652526 270)
			(size 1.0668 0.8128)
			(layers "F.Cu" "F.Mask" "F.Paste")
			(net "HEARTBEAT_R_LED")
		)
		(pad "K" smd rect
			(at 0 0.652526 270)
			(size 1.0668 0.8128)
			(layers "F.Cu" "F.Mask" "F.Paste")
			(net "HEARTBEAT_LED")
		)
	)
	(footprint ""
		(layer "F.Cu")
		(at 197.231 -39.243 90)
		(property "Reference" "PR97"
			(at 0 0 90)
			(layer "F.SilkS")
			(hide yes)
			(effects
				(font
					(size 1.27 1.27)
				)
			)
		)
		(property "Value" "0R3J-0-U-GP"
			(at -0.0254 -2.0193 90)
			(unlocked yes)
			(layer "F.Fab")
			(hide yes)
			(effects
				(font
					(size 1.016 1.016)
					(thickness 0.1524)
				)
			)
		)
		(property "Device Type" "R603H22"
			(at -0.0254 -3.5433 90)
			(unlocked yes)
			(layer "F.Fab")
			(hide yes)
			(effects
				(font
					(size 1.016 1.016)
					(thickness 0.1524)
				)
			)
		)
		(duplicate_pad_numbers_are_jumpers no)
		(fp_line
			(start 0.4318 0)
			(end 0.2032 0)
			(stroke
				(width 0.2032)
				(type default)
			)
			(layer "F.SilkS")
		)
		(fp_line
			(start -0.2032 0)
			(end -0.4191 0)
			(stroke
				(width 0.2032)
				(type default)
			)
			(layer "F.SilkS")
		)
		(fp_rect
			(start -0.635 1.1811)
			(end 0.635 -1.1811)
			(stroke
				(width 0)
				(type default)
			)
			(fill no)
			(layer "F.CrtYd")
		)
		(fp_rect
			(start -0.635 1.1811)
			(end 0.635 -1.1811)
			(stroke
				(width 0)
				(type default)
			)
			(fill no)
			(layer "F.Fab")
		)
		(pad "1" smd custom
			(at 0 -0.6604 90)
			(size 0.19685 0.19685)
			(layers "F.Cu" "F.Mask" "F.Paste")
			(net "VR_PVDDR_A_GL1")
			(options
				(clearance outline)
				(anchor circle)
			)
			(primitives
				(gr_poly
					(pts
						(arc
							(start 0.508 -0.2921)
							(mid 0.478242 -0.363942)
							(end 0.4064 -0.3937)
						)
						(arc
							(start -0.4064 -0.3937)
							(mid -0.478242 -0.363942)
							(end -0.508 -0.2921)
						)
						(arc
							(start -0.508 0.2921)
							(mid -0.478242 0.363942)
							(end -0.4064 0.3937)
						)
						(arc
							(start 0.4064 0.3937)
							(mid 0.478242 0.363942)
							(end 0.508 0.2921)
						)
					)
					(width 0)
					(fill yes)
				)
			)
		)
		(pad "2" smd custom
			(at 0 0.6604 90)
			(size 0.19685 0.19685)
			(layers "F.Cu" "F.Mask" "F.Paste")
			(net "VR_PVDDR_A_GL1_BG")
			(options
				(clearance outline)
				(anchor circle)
			)
			(primitives
				(gr_poly
					(pts
						(arc
							(start 0.508 -0.2921)
							(mid 0.478242 -0.363942)
							(end 0.4064 -0.3937)
						)
						(arc
							(start -0.4064 -0.3937)
							(mid -0.478242 -0.363942)
							(end -0.508 -0.2921)
						)
						(arc
							(start -0.508 0.2921)
							(mid -0.478242 0.363942)
							(end -0.4064 0.3937)
						)
						(arc
							(start 0.4064 0.3937)
							(mid 0.478242 0.363942)
							(end 0.508 0.2921)
						)
					)
					(width 0)
					(fill yes)
				)
			)
		)
	)
	(footprint ""
		(layer "F.Cu")
		(at 20.5486 -35.3568 -90)
		(property "Reference" "PC152"
			(at 0 0 270)
			(layer "F.SilkS")
			(hide yes)
			(effects
				(font
					(size 1.27 1.27)
				)
			)
		)
		(property "Value" "SCD1U25V2KX-2-GP"
			(at 1.8923 -1.2065 270)
			(unlocked yes)
			(layer "F.Fab")
			(hide yes)
			(effects
				(font
					(size 1.016 1.016)
					(thickness 0.1524)
				)
			)
		)
		(property "Device Type" "C402H22"
			(at 1.8923 -2.7305 270)
			(unlocked yes)
			(layer "F.Fab")
			(hide yes)
			(effects
				(font
					(size 1.016 1.016)
					(thickness 0.1524)
				)
			)
		)
		(duplicate_pad_numbers_are_jumpers no)
		(fp_rect
			(start -0.381 0.7366)
			(end 0.381 -0.7366)
			(stroke
				(width 0)
				(type default)
			)
			(fill no)
			(layer "F.CrtYd")
		)
		(fp_rect
			(start -0.381 0.7366)
			(end 0.381 -0.7366)
			(stroke
				(width 0)
				(type default)
			)
			(fill no)
			(layer "F.Fab")
		)
		(pad "1" smd custom
			(at 0 -0.4572 270)
			(size 0.1143 0.1143)
			(layers "F.Cu" "F.Mask" "F.Paste")
			(net "P3V3_STBY_OUT")
			(options
				(clearance outline)
				(anchor circle)
			)
			(primitives
				(gr_poly
					(pts
						(arc
							(start -0.254 -0.1778)
							(mid -0.239121 -0.213721)
							(end -0.2032 -0.2286)
						)
						(arc
							(start 0.2032 -0.2286)
							(mid 0.239121 -0.213721)
							(end 0.254 -0.1778)
						)
						(arc
							(start 0.254 0.1778)
							(mid 0.239121 0.213721)
							(end 0.2032 0.2286)
						)
						(arc
							(start -0.2032 0.2286)
							(mid -0.239121 0.213721)
							(end -0.254 0.1778)
						)
					)
					(width 0)
					(fill yes)
				)
			)
		)
		(pad "2" smd custom
			(at 0 0.4572 270)
			(size 0.1143 0.1143)
			(layers "F.Cu" "F.Mask" "F.Paste")
			(net "P3V3_STBY_LL_R")
			(options
				(clearance outline)
				(anchor circle)
			)
			(primitives
				(gr_poly
					(pts
						(arc
							(start -0.254 -0.1778)
							(mid -0.239121 -0.213721)
							(end -0.2032 -0.2286)
						)
						(arc
							(start 0.2032 -0.2286)
							(mid 0.239121 -0.213721)
							(end 0.254 -0.1778)
						)
						(arc
							(start 0.254 0.1778)
							(mid 0.239121 0.213721)
							(end 0.2032 0.2286)
						)
						(arc
							(start -0.2032 0.2286)
							(mid -0.239121 0.213721)
							(end -0.254 0.1778)
						)
					)
					(width 0)
					(fill yes)
				)
			)
		)
	)
	(footprint ""
		(layer "F.Cu")
		(at 38.1 -42.037 180)
		(property "Reference" "R63"
			(at 0 0 180)
			(layer "F.SilkS")
			(hide yes)
			(effects
				(font
					(size 1.27 1.27)
				)
			)
		)
		(property "Value" "10KR2F-2-GP"
			(at 1.7907 -1.1176 180)
			(unlocked yes)
			(layer "F.Fab")
			(hide yes)
			(effects
				(font
					(size 1.016 1.016)
					(thickness 0.1524)
				)
			)
		)
		(property "Device Type" "R402H16"
			(at 1.7907 -2.6416 180)
			(unlocked yes)
			(layer "F.Fab")
			(hide yes)
			(effects
				(font
					(size 1.016 1.016)
					(thickness 0.1524)
				)
			)
		)
		(duplicate_pad_numbers_are_jumpers no)
		(fp_rect
			(start -0.381 0.8382)
			(end 0.381 -0.8382)
			(stroke
				(width 0)
				(type default)
			)
			(fill no)
			(layer "F.CrtYd")
		)
		(fp_rect
			(start -0.381 0.8382)
			(end 0.381 -0.8382)
			(stroke
				(width 0)
				(type default)
			)
			(fill no)
			(layer "F.Fab")
		)
		(pad "1" smd custom
			(at 0 -0.4318 180)
			(size 0.127 0.127)
			(layers "F.Cu" "F.Mask" "F.Paste")
			(net "CPU_RSMRST#")
			(options
				(clearance outline)
				(anchor circle)
			)
			(primitives
				(gr_poly
					(pts
						(arc
							(start -0.2032 -0.2794)
							(mid -0.239121 -0.264521)
							(end -0.254 -0.2286)
						)
						(arc
							(start -0.254 0.2286)
							(mid -0.239121 0.264521)
							(end -0.2032 0.2794)
						)
						(arc
							(start 0.2032 0.2794)
							(mid 0.239121 0.264521)
							(end 0.254 0.2286)
						)
						(arc
							(start 0.254 -0.2286)
							(mid 0.239121 -0.264521)
							(end 0.2032 -0.2794)
						)
					)
					(width 0)
					(fill yes)
				)
			)
		)
		(pad "2" smd custom
			(at 0 0.4318 180)
			(size 0.127 0.127)
			(layers "F.Cu" "F.Mask" "F.Paste")
			(net "GND")
			(options
				(clearance outline)
				(anchor circle)
			)
			(primitives
				(gr_poly
					(pts
						(arc
							(start -0.2032 -0.2794)
							(mid -0.239121 -0.264521)
							(end -0.254 -0.2286)
						)
						(arc
							(start -0.254 0.2286)
							(mid -0.239121 0.264521)
							(end -0.2032 0.2794)
						)
						(arc
							(start 0.2032 0.2794)
							(mid 0.239121 0.264521)
							(end 0.254 0.2286)
						)
						(arc
							(start 0.254 -0.2286)
							(mid 0.239121 -0.264521)
							(end 0.2032 -0.2794)
						)
					)
					(width 0)
					(fill yes)
				)
			)
		)
	)
	(footprint ""
		(layer "F.Cu")
		(at 172.212 -39.751 90)
		(property "Reference" "PC212"
			(at 0 0 90)
			(layer "F.SilkS")
			(hide yes)
			(effects
				(font
					(size 1.27 1.27)
				)
			)
		)
		(property "Value" "SC4D7U10V3KX-GP"
			(at -0.0254 -2.0193 90)
			(unlocked yes)
			(layer "F.Fab")
			(hide yes)
			(effects
				(font
					(size 1.016 1.016)
					(thickness 0.1524)
				)
			)
		)
		(property "Device Type" "C603H36"
			(at -0.0254 -3.5433 90)
			(unlocked yes)
			(layer "F.Fab")
			(hide yes)
			(effects
				(font
					(size 1.016 1.016)
					(thickness 0.1524)
				)
			)
		)
		(duplicate_pad_numbers_are_jumpers no)
		(fp_line
			(start -0.4064 0)
			(end 0.4064 0)
			(stroke
				(width 0.2286)
				(type default)
			)
			(layer "F.SilkS")
		)
		(fp_rect
			(start -0.635 1.1811)
			(end 0.635 -1.1811)
			(stroke
				(width 0)
				(type default)
			)
			(fill no)
			(layer "F.CrtYd")
		)
		(fp_rect
			(start -0.635 1.1811)
			(end 0.635 -1.1811)
			(stroke
				(width 0)
				(type default)
			)
			(fill no)
			(layer "F.Fab")
		)
		(pad "1" smd custom
			(at 0 -0.6604 90)
			(size 0.19685 0.19685)
			(layers "F.Cu" "F.Mask" "F.Paste")
			(net "P2V5_STBY_OUT")
			(options
				(clearance outline)
				(anchor circle)
			)
			(primitives
				(gr_poly
					(pts
						(arc
							(start 0.508 -0.2921)
							(mid 0.478242 -0.363942)
							(end 0.4064 -0.3937)
						)
						(arc
							(start -0.4064 -0.3937)
							(mid -0.478242 -0.363942)
							(end -0.508 -0.2921)
						)
						(arc
							(start -0.508 0.2921)
							(mid -0.478242 0.363942)
							(end -0.4064 0.3937)
						)
						(arc
							(start 0.4064 0.3937)
							(mid 0.478242 0.363942)
							(end 0.508 0.2921)
						)
					)
					(width 0)
					(fill yes)
				)
			)
		)
		(pad "2" smd custom
			(at 0 0.6604 90)
			(size 0.19685 0.19685)
			(layers "F.Cu" "F.Mask" "F.Paste")
			(net "GND")
			(options
				(clearance outline)
				(anchor circle)
			)
			(primitives
				(gr_poly
					(pts
						(arc
							(start 0.508 -0.2921)
							(mid 0.478242 -0.363942)
							(end 0.4064 -0.3937)
						)
						(arc
							(start -0.4064 -0.3937)
							(mid -0.478242 -0.363942)
							(end -0.508 -0.2921)
						)
						(arc
							(start -0.508 0.2921)
							(mid -0.478242 0.363942)
							(end -0.4064 0.3937)
						)
						(arc
							(start 0.4064 0.3937)
							(mid 0.478242 0.363942)
							(end 0.508 0.2921)
						)
					)
					(width 0)
					(fill yes)
				)
			)
		)
	)
	(footprint ""
		(layer "F.Cu")
		(at 37.592 -39.116)
		(property "Reference" "R242"
			(at 0 0 0)
			(layer "F.SilkS")
			(hide yes)
			(effects
				(font
					(size 1.27 1.27)
				)
			)
		)
		(property "Value" "0R2J-2-GP"
			(at 0.064008 -3.993896 0)
			(unlocked yes)
			(layer "F.Fab")
			(hide yes)
			(effects
				(font
					(size 1.016 1.016)
					(thickness 0.1524)
				)
			)
		)
		(property "Device Type" "R402H16"
			(at 0.064008 -5.517896 0)
			(unlocked yes)
			(layer "F.Fab")
			(hide yes)
			(effects
				(font
					(size 1.016 1.016)
					(thickness 0.1524)
				)
			)
		)
		(duplicate_pad_numbers_are_jumpers no)
		(fp_rect
			(start -0.381 0.8382)
			(end 0.381 -0.8382)
			(stroke
				(width 0)
				(type default)
			)
			(fill no)
			(layer "F.CrtYd")
		)
		(fp_rect
			(start -0.381 0.8382)
			(end 0.381 -0.8382)
			(stroke
				(width 0)
				(type default)
			)
			(fill no)
			(layer "F.Fab")
		)
		(pad "1" smd custom
			(at 0 -0.4318)
			(size 0.127 0.127)
			(layers "F.Cu" "F.Mask" "F.Paste")
			(net "SMBUS_HOST_DATA")
			(options
				(clearance outline)
				(anchor circle)
			)
			(primitives
				(gr_poly
					(pts
						(arc
							(start -0.2032 -0.2794)
							(mid -0.239121 -0.264521)
							(end -0.254 -0.2286)
						)
						(arc
							(start -0.254 0.2286)
							(mid -0.239121 0.264521)
							(end -0.2032 0.2794)
						)
						(arc
							(start 0.2032 0.2794)
							(mid 0.239121 0.264521)
							(end 0.254 0.2286)
						)
						(arc
							(start 0.254 -0.2286)
							(mid 0.239121 -0.264521)
							(end 0.2032 -0.2794)
						)
					)
					(width 0)
					(fill yes)
				)
			)
		)
		(pad "2" smd custom
			(at 0 0.4318)
			(size 0.127 0.127)
			(layers "F.Cu" "F.Mask" "F.Paste")
			(net "SMB_XDP_DATA_R")
			(options
				(clearance outline)
				(anchor circle)
			)
			(primitives
				(gr_poly
					(pts
						(arc
							(start -0.2032 -0.2794)
							(mid -0.239121 -0.264521)
							(end -0.254 -0.2286)
						)
						(arc
							(start -0.254 0.2286)
							(mid -0.239121 0.264521)
							(end -0.2032 0.2794)
						)
						(arc
							(start 0.2032 0.2794)
							(mid 0.239121 0.264521)
							(end 0.254 0.2286)
						)
						(arc
							(start 0.254 -0.2286)
							(mid 0.239121 -0.264521)
							(end 0.2032 -0.2794)
						)
					)
					(width 0)
					(fill yes)
				)
			)
		)
	)
	(footprint ""
		(layer "F.Cu")
		(at 116.967 -41.1988 90)
		(property "Reference" "C161"
			(at 0 0 90)
			(layer "F.SilkS")
			(hide yes)
			(effects
				(font
					(size 1.27 1.27)
				)
			)
		)
		(property "Value" "SC22U6D3V5MX-2GP"
			(at -0.0762 -6.1214 90)
			(unlocked yes)
			(layer "F.Fab")
			(hide yes)
			(effects
				(font
					(size 1.016 1.016)
					(thickness 0.1524)
				)
			)
		)
		(property "Device Type" "C805H58"
			(at -0.0762 -8.1534 90)
			(unlocked yes)
			(layer "F.Fab")
			(hide yes)
			(effects
				(font
					(size 1.016 1.016)
					(thickness 0.1524)
				)
			)
		)
		(duplicate_pad_numbers_are_jumpers no)
		(fp_line
			(start 0.6096 0)
			(end -0.6096 0)
			(stroke
				(width 0.3048)
				(type default)
			)
			(layer "F.SilkS")
		)
		(fp_poly
			(pts
				(xy -0.9017 1.4351) (xy 0.9017 1.4351) (xy 0.9017 -1.4351) (xy -0.9017 -1.4351)
			)
			(stroke
				(width 0)
				(type default)
			)
			(fill no)
			(layer "F.CrtYd")
		)
		(fp_poly
			(pts
				(xy 0.9271 1.4351) (xy 0.9271 -1.4351) (xy -0.8763 -1.4351) (xy -0.8763 1.4351)
			)
			(stroke
				(width 0)
				(type default)
			)
			(fill no)
			(layer "F.Fab")
		)
		(pad "1" smd rect
			(at 0 -0.8382 90)
			(size 1.5494 0.9398)
			(layers "F.Cu" "F.Mask" "F.Paste")
			(net "PVCCP")
		)
		(pad "2" smd rect
			(at 0 0.8382 90)
			(size 1.5494 0.9398)
			(layers "F.Cu" "F.Mask" "F.Paste")
			(net "GND")
		)
	)
	(footprint ""
		(layer "F.Cu")
		(at 20.3708 -67.183 180)
		(property "Reference" "PR17"
			(at 0 0 180)
			(layer "F.SilkS")
			(hide yes)
			(effects
				(font
					(size 1.27 1.27)
				)
			)
		)
		(property "Value" "11KR2F-L-GP"
			(at 1.7907 -1.1176 180)
			(unlocked yes)
			(layer "F.Fab")
			(hide yes)
			(effects
				(font
					(size 1.016 1.016)
					(thickness 0.1524)
				)
			)
		)
		(property "Device Type" "R402H16"
			(at 1.7907 -2.6416 180)
			(unlocked yes)
			(layer "F.Fab")
			(hide yes)
			(effects
				(font
					(size 1.016 1.016)
					(thickness 0.1524)
				)
			)
		)
		(duplicate_pad_numbers_are_jumpers no)
		(fp_rect
			(start -0.381 0.8382)
			(end 0.381 -0.8382)
			(stroke
				(width 0)
				(type default)
			)
			(fill no)
			(layer "F.CrtYd")
		)
		(fp_rect
			(start -0.381 0.8382)
			(end 0.381 -0.8382)
			(stroke
				(width 0)
				(type default)
			)
			(fill no)
			(layer "F.Fab")
		)
		(pad "1" smd custom
			(at 0 -0.4318 180)
			(size 0.127 0.127)
			(layers "F.Cu" "F.Mask" "F.Paste")
			(net "VR_PVNN_ISUMN")
			(options
				(clearance outline)
				(anchor circle)
			)
			(primitives
				(gr_poly
					(pts
						(arc
							(start -0.2032 -0.2794)
							(mid -0.239121 -0.264521)
							(end -0.254 -0.2286)
						)
						(arc
							(start -0.254 0.2286)
							(mid -0.239121 0.264521)
							(end -0.2032 0.2794)
						)
						(arc
							(start 0.2032 0.2794)
							(mid 0.239121 0.264521)
							(end 0.254 0.2286)
						)
						(arc
							(start 0.254 -0.2286)
							(mid 0.239121 -0.264521)
							(end 0.2032 -0.2794)
						)
					)
					(width 0)
					(fill yes)
				)
			)
		)
		(pad "2" smd custom
			(at 0 0.4318 180)
			(size 0.127 0.127)
			(layers "F.Cu" "F.Mask" "F.Paste")
			(net "VR_PVNN_ISUMP")
			(options
				(clearance outline)
				(anchor circle)
			)
			(primitives
				(gr_poly
					(pts
						(arc
							(start -0.2032 -0.2794)
							(mid -0.239121 -0.264521)
							(end -0.254 -0.2286)
						)
						(arc
							(start -0.254 0.2286)
							(mid -0.239121 0.264521)
							(end -0.2032 0.2794)
						)
						(arc
							(start 0.2032 0.2794)
							(mid 0.239121 0.264521)
							(end 0.254 0.2286)
						)
						(arc
							(start 0.254 -0.2286)
							(mid 0.239121 -0.264521)
							(end 0.2032 -0.2794)
						)
					)
					(width 0)
					(fill yes)
				)
			)
		)
	)
	(footprint ""
		(layer "F.Cu")
		(at 149.987 -59.182)
		(property "Reference" "C368"
			(at 0 0 0)
			(layer "F.SilkS")
			(hide yes)
			(effects
				(font
					(size 1.27 1.27)
				)
			)
		)
		(property "Value" "SC47U6D3V5MX-1-GP"
			(at 0 -4.9022 0)
			(unlocked yes)
			(layer "F.Fab")
			(hide yes)
			(effects
				(font
					(size 1.016 1.016)
					(thickness 0.1524)
				)
			)
		)
		(property "Device Type" "C805H54"
			(at 0 -6.8072 0)
			(unlocked yes)
			(layer "F.Fab")
			(hide yes)
			(effects
				(font
					(size 1.016 1.016)
					(thickness 0.1524)
				)
			)
		)
		(duplicate_pad_numbers_are_jumpers no)
		(fp_line
			(start 0.6096 0)
			(end -0.6096 0)
			(stroke
				(width 0.3048)
				(type default)
			)
			(layer "F.SilkS")
		)
		(fp_poly
			(pts
				(xy -0.9017 1.4351) (xy 0.9017 1.4351) (xy 0.9017 -1.4351) (xy -0.9017 -1.4351)
			)
			(stroke
				(width 0)
				(type default)
			)
			(fill no)
			(layer "F.CrtYd")
		)
		(fp_poly
			(pts
				(xy 0.9017 1.4351) (xy 0.9017 -1.4351) (xy -0.9017 -1.4351) (xy -0.9017 1.4351)
			)
			(stroke
				(width 0)
				(type default)
			)
			(fill no)
			(layer "F.Fab")
		)
		(pad "1" smd rect
			(at 0 -0.8382)
			(size 1.5494 0.9398)
			(layers "F.Cu" "F.Mask" "F.Paste")
			(net "PV_VDDR")
		)
		(pad "2" smd rect
			(at 0 0.8382)
			(size 1.5494 0.9398)
			(layers "F.Cu" "F.Mask" "F.Paste")
			(net "GND")
		)
	)
	(footprint ""
		(layer "F.Cu")
		(at 182.118 -17.653 180)
		(property "Reference" "PC115"
			(at 0 0 180)
			(layer "F.SilkS")
			(hide yes)
			(effects
				(font
					(size 1.27 1.27)
				)
			)
		)
		(property "Value" "SC1KP50V2KX-1GP"
			(at 1.1811 -2.7051 180)
			(unlocked yes)
			(layer "F.Fab")
			(hide yes)
			(effects
				(font
					(size 1.016 1.016)
					(thickness 0.1524)
				)
			)
		)
		(property "Device Type" "C402H22"
			(at 1.1811 -4.2291 180)
			(unlocked yes)
			(layer "F.Fab")
			(hide yes)
			(effects
				(font
					(size 1.016 1.016)
					(thickness 0.1524)
				)
			)
		)
		(duplicate_pad_numbers_are_jumpers no)
		(fp_rect
			(start -0.381 0.7366)
			(end 0.381 -0.7366)
			(stroke
				(width 0)
				(type default)
			)
			(fill no)
			(layer "F.CrtYd")
		)
		(fp_rect
			(start -0.381 0.7366)
			(end 0.381 -0.7366)
			(stroke
				(width 0)
				(type default)
			)
			(fill no)
			(layer "F.Fab")
		)
		(pad "1" smd custom
			(at 0 -0.4572 180)
			(size 0.1143 0.1143)
			(layers "F.Cu" "F.Mask" "F.Paste")
			(net "PV_VTT_DDR_B_REFIN")
			(options
				(clearance outline)
				(anchor circle)
			)
			(primitives
				(gr_poly
					(pts
						(arc
							(start -0.254 -0.1778)
							(mid -0.239121 -0.213721)
							(end -0.2032 -0.2286)
						)
						(arc
							(start 0.2032 -0.2286)
							(mid 0.239121 -0.213721)
							(end 0.254 -0.1778)
						)
						(arc
							(start 0.254 0.1778)
							(mid 0.239121 0.213721)
							(end 0.2032 0.2286)
						)
						(arc
							(start -0.2032 0.2286)
							(mid -0.239121 0.213721)
							(end -0.254 0.1778)
						)
					)
					(width 0)
					(fill yes)
				)
			)
		)
		(pad "2" smd custom
			(at 0 0.4572 180)
			(size 0.1143 0.1143)
			(layers "F.Cu" "F.Mask" "F.Paste")
			(net "GND")
			(options
				(clearance outline)
				(anchor circle)
			)
			(primitives
				(gr_poly
					(pts
						(arc
							(start -0.254 -0.1778)
							(mid -0.239121 -0.213721)
							(end -0.2032 -0.2286)
						)
						(arc
							(start 0.2032 -0.2286)
							(mid 0.239121 -0.213721)
							(end 0.254 -0.1778)
						)
						(arc
							(start 0.254 0.1778)
							(mid 0.239121 0.213721)
							(end 0.2032 0.2286)
						)
						(arc
							(start -0.2032 0.2286)
							(mid -0.239121 0.213721)
							(end -0.254 0.1778)
						)
					)
					(width 0)
					(fill yes)
				)
			)
		)
	)
	(footprint ""
		(layer "F.Cu")
		(at 185.674 -22.8854)
		(property "Reference" "PR166"
			(at 0 0 0)
			(layer "F.SilkS")
			(hide yes)
			(effects
				(font
					(size 1.27 1.27)
				)
			)
		)
		(property "Value" "0R2J-2-GP"
			(at 0.064008 -3.993896 0)
			(unlocked yes)
			(layer "F.Fab")
			(hide yes)
			(effects
				(font
					(size 1.016 1.016)
					(thickness 0.1524)
				)
			)
		)
		(property "Device Type" "R402H16"
			(at 0.064008 -5.517896 0)
			(unlocked yes)
			(layer "F.Fab")
			(hide yes)
			(effects
				(font
					(size 1.016 1.016)
					(thickness 0.1524)
				)
			)
		)
		(duplicate_pad_numbers_are_jumpers no)
		(fp_rect
			(start -0.381 0.8382)
			(end 0.381 -0.8382)
			(stroke
				(width 0)
				(type default)
			)
			(fill no)
			(layer "F.CrtYd")
		)
		(fp_rect
			(start -0.381 0.8382)
			(end 0.381 -0.8382)
			(stroke
				(width 0)
				(type default)
			)
			(fill no)
			(layer "F.Fab")
		)
		(pad "1" smd custom
			(at 0 -0.4318)
			(size 0.127 0.127)
			(layers "F.Cu" "F.Mask" "F.Paste")
			(net "PVTT_DDR_EN")
			(options
				(clearance outline)
				(anchor circle)
			)
			(primitives
				(gr_poly
					(pts
						(arc
							(start -0.2032 -0.2794)
							(mid -0.239121 -0.264521)
							(end -0.254 -0.2286)
						)
						(arc
							(start -0.254 0.2286)
							(mid -0.239121 0.264521)
							(end -0.2032 0.2794)
						)
						(arc
							(start 0.2032 0.2794)
							(mid 0.239121 0.264521)
							(end 0.254 0.2286)
						)
						(arc
							(start 0.254 -0.2286)
							(mid 0.239121 -0.264521)
							(end 0.2032 -0.2794)
						)
					)
					(width 0)
					(fill yes)
				)
			)
		)
		(pad "2" smd custom
			(at 0 0.4318)
			(size 0.127 0.127)
			(layers "F.Cu" "F.Mask" "F.Paste")
			(net "PV_VTT_DDR_B_EN")
			(options
				(clearance outline)
				(anchor circle)
			)
			(primitives
				(gr_poly
					(pts
						(arc
							(start -0.2032 -0.2794)
							(mid -0.239121 -0.264521)
							(end -0.254 -0.2286)
						)
						(arc
							(start -0.254 0.2286)
							(mid -0.239121 0.264521)
							(end -0.2032 0.2794)
						)
						(arc
							(start 0.2032 0.2794)
							(mid 0.239121 0.264521)
							(end 0.254 0.2286)
						)
						(arc
							(start 0.254 -0.2286)
							(mid 0.239121 -0.264521)
							(end 0.2032 -0.2794)
						)
					)
					(width 0)
					(fill yes)
				)
			)
		)
	)
	(footprint ""
		(layer "F.Cu")
		(at 27.94 -47.879 90)
		(property "Reference" "PR68"
			(at 0 0 90)
			(layer "F.SilkS")
			(hide yes)
			(effects
				(font
					(size 1.27 1.27)
				)
			)
		)
		(property "Value" "2M2R2J-GP"
			(at 1.7907 -1.1176 90)
			(unlocked yes)
			(layer "F.Fab")
			(hide yes)
			(effects
				(font
					(size 1.016 1.016)
					(thickness 0.1524)
				)
			)
		)
		(property "Device Type" "R402H16"
			(at 1.7907 -2.6416 90)
			(unlocked yes)
			(layer "F.Fab")
			(hide yes)
			(effects
				(font
					(size 1.016 1.016)
					(thickness 0.1524)
				)
			)
		)
		(duplicate_pad_numbers_are_jumpers no)
		(fp_rect
			(start -0.381 0.8382)
			(end 0.381 -0.8382)
			(stroke
				(width 0)
				(type default)
			)
			(fill no)
			(layer "F.CrtYd")
		)
		(fp_rect
			(start -0.381 0.8382)
			(end 0.381 -0.8382)
			(stroke
				(width 0)
				(type default)
			)
			(fill no)
			(layer "F.Fab")
		)
		(pad "1" smd custom
			(at 0 -0.4318 90)
			(size 0.127 0.127)
			(layers "F.Cu" "F.Mask" "F.Paste")
			(net "VR_PVCCP_ISUMP")
			(options
				(clearance outline)
				(anchor circle)
			)
			(primitives
				(gr_poly
					(pts
						(arc
							(start -0.2032 -0.2794)
							(mid -0.239121 -0.264521)
							(end -0.254 -0.2286)
						)
						(arc
							(start -0.254 0.2286)
							(mid -0.239121 0.264521)
							(end -0.2032 0.2794)
						)
						(arc
							(start 0.2032 0.2794)
							(mid 0.239121 0.264521)
							(end 0.254 0.2286)
						)
						(arc
							(start 0.254 -0.2286)
							(mid 0.239121 -0.264521)
							(end 0.2032 -0.2794)
						)
					)
					(width 0)
					(fill yes)
				)
			)
		)
		(pad "2" smd custom
			(at 0 0.4318 90)
			(size 0.127 0.127)
			(layers "F.Cu" "F.Mask" "F.Paste")
			(net "GND")
			(options
				(clearance outline)
				(anchor circle)
			)
			(primitives
				(gr_poly
					(pts
						(arc
							(start -0.2032 -0.2794)
							(mid -0.239121 -0.264521)
							(end -0.254 -0.2286)
						)
						(arc
							(start -0.254 0.2286)
							(mid -0.239121 0.264521)
							(end -0.2032 0.2794)
						)
						(arc
							(start 0.2032 0.2794)
							(mid 0.239121 0.264521)
							(end 0.254 0.2286)
						)
						(arc
							(start 0.254 -0.2286)
							(mid 0.239121 -0.264521)
							(end 0.2032 -0.2794)
						)
					)
					(width 0)
					(fill yes)
				)
			)
		)
	)
	(footprint ""
		(layer "F.Cu")
		(at 72.849994 -66.900044 180)
		(property "Reference" "CN1"
			(at 0 0 180)
			(layer "F.SilkS")
			(hide yes)
			(effects
				(font
					(size 1.27 1.27)
				)
			)
		)
		(property "Value" "PIN-CON2-6-GP-U"
			(at -4.9657 1.2954 180)
			(unlocked yes)
			(layer "F.Fab")
			(hide yes)
			(effects
				(font
					(size 1.016 1.016)
					(thickness 0.1524)
				)
			)
		)
		(property "Device Type" "21U-91-03TB22-U"
			(at -4.9657 -0.2286 180)
			(unlocked yes)
			(layer "F.Fab")
			(hide yes)
			(effects
				(font
					(size 1.016 1.016)
					(thickness 0.1524)
				)
			)
		)
		(duplicate_pad_numbers_are_jumpers no)
		(fp_line
			(start 3.937 1.4986)
			(end -3.937 1.4986)
			(stroke
				(width 0.1524)
				(type default)
			)
			(layer "F.SilkS")
		)
		(fp_line
			(start 3.937 -1.4986)
			(end 3.937 1.4986)
			(stroke
				(width 0.1524)
				(type default)
			)
			(layer "F.SilkS")
		)
		(fp_line
			(start -3.937 1.4986)
			(end -3.937 -1.4986)
			(stroke
				(width 0.1524)
				(type default)
			)
			(layer "F.SilkS")
		)
		(fp_line
			(start -3.937 -1.4986)
			(end 3.937 -1.4986)
			(stroke
				(width 0.1524)
				(type default)
			)
			(layer "F.SilkS")
		)
		(fp_circle
			(center 2.54 0)
			(end 1.4732 0)
			(stroke
				(width 0.3048)
				(type default)
			)
			(fill no)
			(layer "F.SilkS")
		)
		(fp_circle
			(center -2.54 0)
			(end -3.6068 0)
			(stroke
				(width 0.3048)
				(type default)
			)
			(fill no)
			(layer "F.SilkS")
		)
		(fp_rect
			(start -3.683 1.2446)
			(end 3.683 -1.2446)
			(stroke
				(width 0)
				(type default)
			)
			(fill no)
			(layer "F.CrtYd")
		)
		(fp_poly
			(pts
				(xy -4.191 1.7526) (xy -4.191 -1.7526) (xy 4.191 -1.7526) (xy 4.191 -0.00635) (xy 3.683 -0.00635)
				(xy 3.683 -1.2446) (xy -3.683 -1.2446) (xy -3.683 1.2446) (xy 3.683 1.2446) (xy 3.683 0.00635) (xy 4.191 0.00635)
				(xy 4.191 1.7526)
			)
			(stroke
				(width 0)
				(type default)
			)
			(fill no)
			(layer "F.CrtYd")
		)
		(fp_rect
			(start -4.191 1.7526)
			(end 4.191 -1.7526)
			(stroke
				(width 0)
				(type default)
			)
			(fill no)
			(layer "F.Fab")
		)
		(pad "1" thru_hole circle
			(at -2.54 0 180)
			(size 1.4224 1.4224)
			(drill 1.016)
			(layers "*.Cu" "*.Mask")
			(remove_unused_layers no)
			(net "DYMMY_NET1")
			(clearance 0.1524)
			(thermal_gap 0.1524)
		)
		(pad "2" thru_hole circle
			(at 2.54 0 180)
			(size 1.4224 1.4224)
			(drill 1.016)
			(layers "*.Cu" "*.Mask")
			(remove_unused_layers no)
			(net "DYMMY_NET1")
			(clearance 0.1524)
			(thermal_gap 0.1524)
		)
	)
	(footprint ""
		(layer "F.Cu")
		(at 29.845 -49.911 90)
		(property "Reference" "PC130"
			(at 0 0 90)
			(layer "F.SilkS")
			(hide yes)
			(effects
				(font
					(size 1.27 1.27)
				)
			)
		)
		(property "Value" "SC10U6D3V5KX-4GP"
			(at 0 -4.9022 90)
			(unlocked yes)
			(layer "F.Fab")
			(hide yes)
			(effects
				(font
					(size 1.016 1.016)
					(thickness 0.1524)
				)
			)
		)
		(property "Device Type" "C805H58"
			(at 0 -6.8072 90)
			(unlocked yes)
			(layer "F.Fab")
			(hide yes)
			(effects
				(font
					(size 1.016 1.016)
					(thickness 0.1524)
				)
			)
		)
		(duplicate_pad_numbers_are_jumpers no)
		(fp_line
			(start 0.6096 0)
			(end -0.6096 0)
			(stroke
				(width 0.3048)
				(type default)
			)
			(layer "F.SilkS")
		)
		(fp_poly
			(pts
				(xy -0.9017 1.4351) (xy 0.9017 1.4351) (xy 0.9017 -1.4351) (xy -0.9017 -1.4351)
			)
			(stroke
				(width 0)
				(type default)
			)
			(fill no)
			(layer "F.CrtYd")
		)
		(fp_poly
			(pts
				(xy 0.9017 1.4351) (xy 0.9017 -1.4351) (xy -0.9017 -1.4351) (xy -0.9017 1.4351)
			)
			(stroke
				(width 0)
				(type default)
			)
			(fill no)
			(layer "F.Fab")
		)
		(pad "1" smd rect
			(at 0 -0.8382 90)
			(size 1.5494 0.9398)
			(layers "F.Cu" "F.Mask" "F.Paste")
			(net "P1V5_STBY_IN")
		)
		(pad "2" smd rect
			(at 0 0.8382 90)
			(size 1.5494 0.9398)
			(layers "F.Cu" "F.Mask" "F.Paste")
			(net "GND")
		)
	)
	(footprint ""
		(layer "F.Cu")
		(at 202.954128 -11.946128 -90)
		(property "Reference" "CN3"
			(at 0 0 270)
			(layer "F.SilkS")
			(hide yes)
			(effects
				(font
					(size 1.27 1.27)
				)
			)
		)
		(property "Value" "FOX-CONN10A-S8-GP"
			(at -7.874 -9.0932 270)
			(unlocked yes)
			(layer "F.Fab")
			(hide yes)
			(effects
				(font
					(size 1.016 1.016)
					(thickness 0.1524)
				)
			)
		)
		(property "Device Type" "HC3105F"
			(at -7.874 -10.6172 270)
			(unlocked yes)
			(layer "F.Fab")
			(hide yes)
			(effects
				(font
					(size 1.016 1.016)
					(thickness 0.1524)
				)
			)
		)
		(duplicate_pad_numbers_are_jumpers no)
		(fp_line
			(start -6.604 2.8702)
			(end -5.334 2.8702)
			(stroke
				(width 0.4064)
				(type default)
			)
			(layer "F.SilkS")
		)
		(fp_line
			(start -6.477 2.7432)
			(end 6.477 2.7432)
			(stroke
				(width 0.1524)
				(type default)
			)
			(layer "F.SilkS")
		)
		(fp_line
			(start 6.477 2.7432)
			(end 6.477 -2.7432)
			(stroke
				(width 0.1524)
				(type default)
			)
			(layer "F.SilkS")
		)
		(fp_line
			(start -6.604 1.6002)
			(end -6.604 2.8702)
			(stroke
				(width 0.4064)
				(type default)
			)
			(layer "F.SilkS")
		)
		(fp_line
			(start -6.477 -2.7432)
			(end -6.477 2.7432)
			(stroke
				(width 0.1524)
				(type default)
			)
			(layer "F.SilkS")
		)
		(fp_line
			(start 6.477 -2.7432)
			(end -6.477 -2.7432)
			(stroke
				(width 0.1524)
				(type default)
			)
			(layer "F.SilkS")
		)
		(fp_circle
			(center -5.08 1.27)
			(end -5.08 0.1524)
			(stroke
				(width 0.3048)
				(type default)
			)
			(fill no)
			(layer "F.SilkS")
		)
		(fp_circle
			(center -2.54 1.27)
			(end -2.54 0.1524)
			(stroke
				(width 0.3048)
				(type default)
			)
			(fill no)
			(layer "F.SilkS")
		)
		(fp_circle
			(center 0 1.27)
			(end 0 0.1524)
			(stroke
				(width 0.3048)
				(type default)
			)
			(fill no)
			(layer "F.SilkS")
		)
		(fp_circle
			(center 2.54 1.27)
			(end 2.54 0.1524)
			(stroke
				(width 0.3048)
				(type default)
			)
			(fill no)
			(layer "F.SilkS")
		)
		(fp_circle
			(center 5.08 1.27)
			(end 5.08 0.1524)
			(stroke
				(width 0.3048)
				(type default)
			)
			(fill no)
			(layer "F.SilkS")
		)
		(fp_circle
			(center -5.08 -1.27)
			(end -5.08 -2.3876)
			(stroke
				(width 0.3048)
				(type default)
			)
			(fill no)
			(layer "F.SilkS")
		)
		(fp_circle
			(center -2.54 -1.27)
			(end -2.54 -2.3876)
			(stroke
				(width 0.3048)
				(type default)
			)
			(fill no)
			(layer "F.SilkS")
		)
		(fp_circle
			(center 0 -1.27)
			(end 0 -2.3876)
			(stroke
				(width 0.3048)
				(type default)
			)
			(fill no)
			(layer "F.SilkS")
		)
		(fp_circle
			(center 2.54 -1.27)
			(end 2.54 -2.3876)
			(stroke
				(width 0.3048)
				(type default)
			)
			(fill no)
			(layer "F.SilkS")
		)
		(fp_circle
			(center 5.08 -1.27)
			(end 5.08 -2.3876)
			(stroke
				(width 0.3048)
				(type default)
			)
			(fill no)
			(layer "F.SilkS")
		)
		(fp_rect
			(start -6.223 2.4892)
			(end 6.223 -2.4892)
			(stroke
				(width 0)
				(type default)
			)
			(fill no)
			(layer "F.CrtYd")
		)
		(fp_poly
			(pts
				(xy 6.731 -2.4892) (xy -6.223 -2.4892) (xy -6.223 2.4892) (xy 6.223 2.4892) (xy 6.223 -2.4765) (xy 6.731 -2.4765)
				(xy 6.731 2.9972) (xy -6.731 2.9972) (xy -6.731 -2.9972) (xy 6.731 -2.9972)
			)
			(stroke
				(width 0)
				(type default)
			)
			(fill no)
			(layer "F.CrtYd")
		)
		(fp_rect
			(start -6.731 2.9972)
			(end 6.731 -2.9972)
			(stroke
				(width 0)
				(type default)
			)
			(fill no)
			(layer "F.Fab")
		)
		(pad "1" thru_hole circle
			(at -5.08 1.27 270)
			(size 1.524 1.524)
			(drill 1.1176)
			(layers "*.Cu" "*.Mask")
			(remove_unused_layers no)
			(net "JTAG_PLD_TCK")
			(clearance 0.1524)
			(thermal_gap 0.1524)
		)
		(pad "2" thru_hole circle
			(at -5.08 -1.27 270)
			(size 1.524 1.524)
			(drill 1.1176)
			(layers "*.Cu" "*.Mask")
			(remove_unused_layers no)
			(net "GND")
			(clearance 0.1524)
			(thermal_gap 0.1524)
		)
		(pad "3" thru_hole circle
			(at -2.54 1.27 270)
			(size 1.524 1.524)
			(drill 1.1176)
			(layers "*.Cu" "*.Mask")
			(remove_unused_layers no)
			(net "JTAG_CPU_PLD_TDO")
			(clearance 0.1524)
			(thermal_gap 0.1524)
		)
		(pad "4" thru_hole circle
			(at -2.54 -1.27 270)
			(size 1.524 1.524)
			(drill 1.1176)
			(layers "*.Cu" "*.Mask")
			(remove_unused_layers no)
			(net "P3V3_STBY")
			(clearance 0.1524)
			(thermal_gap 0.1524)
		)
		(pad "5" thru_hole circle
			(at 0 1.27 270)
			(size 1.524 1.524)
			(drill 1.1176)
			(layers "*.Cu" "*.Mask")
			(remove_unused_layers no)
			(net "JTAG_PLD_TMS")
			(clearance 0.1524)
			(thermal_gap 0.1524)
		)
		(pad "6" thru_hole circle
			(at 0 -1.27 270)
			(size 1.524 1.524)
			(drill 1.1176)
			(layers "*.Cu" "*.Mask")
			(remove_unused_layers no)
			(net "C_NCE_R#")
			(clearance 0.1524)
			(thermal_gap 0.1524)
		)
		(pad "7" thru_hole circle
			(at 2.54 1.27 270)
			(size 1.524 1.524)
			(drill 1.1176)
			(layers "*.Cu" "*.Mask")
			(remove_unused_layers no)
			(net "Net_89")
			(clearance 0.1524)
			(thermal_gap 0.1524)
		)
		(pad "8" thru_hole circle
			(at 2.54 -1.27 270)
			(size 1.524 1.524)
			(drill 1.1176)
			(layers "*.Cu" "*.Mask")
			(remove_unused_layers no)
			(net "JTAG_RST#")
			(clearance 0.1524)
			(thermal_gap 0.1524)
		)
		(pad "9" thru_hole circle
			(at 5.08 1.27 270)
			(size 1.524 1.524)
			(drill 1.1176)
			(layers "*.Cu" "*.Mask")
			(remove_unused_layers no)
			(net "JTAG_PLD_TDI")
			(clearance 0.1524)
			(thermal_gap 0.1524)
		)
		(pad "10" thru_hole circle
			(at 5.08 -1.27 270)
			(size 1.524 1.524)
			(drill 1.1176)
			(layers "*.Cu" "*.Mask")
			(remove_unused_layers no)
			(net "GND")
			(clearance 0.1524)
			(thermal_gap 0.1524)
		)
	)
	(footprint ""
		(layer "F.Cu")
		(at 5.1562 -43.0022 90)
		(property "Reference" "R3"
			(at 0 0 90)
			(layer "F.SilkS")
			(hide yes)
			(effects
				(font
					(size 1.27 1.27)
				)
			)
		)
		(property "Value" "4K7R2F-GP"
			(at 0.064008 -3.993896 90)
			(unlocked yes)
			(layer "F.Fab")
			(hide yes)
			(effects
				(font
					(size 1.016 1.016)
					(thickness 0.1524)
				)
			)
		)
		(property "Device Type" "R402H16"
			(at 0.064008 -5.517896 90)
			(unlocked yes)
			(layer "F.Fab")
			(hide yes)
			(effects
				(font
					(size 1.016 1.016)
					(thickness 0.1524)
				)
			)
		)
		(duplicate_pad_numbers_are_jumpers no)
		(fp_rect
			(start -0.381 0.8382)
			(end 0.381 -0.8382)
			(stroke
				(width 0)
				(type default)
			)
			(fill no)
			(layer "F.CrtYd")
		)
		(fp_rect
			(start -0.381 0.8382)
			(end 0.381 -0.8382)
			(stroke
				(width 0)
				(type default)
			)
			(fill no)
			(layer "F.Fab")
		)
		(pad "1" smd custom
			(at 0 -0.4318 90)
			(size 0.127 0.127)
			(layers "F.Cu" "F.Mask" "F.Paste")
			(net "P3V3_STBY")
			(options
				(clearance outline)
				(anchor circle)
			)
			(primitives
				(gr_poly
					(pts
						(arc
							(start -0.2032 -0.2794)
							(mid -0.239121 -0.264521)
							(end -0.254 -0.2286)
						)
						(arc
							(start -0.254 0.2286)
							(mid -0.239121 0.264521)
							(end -0.2032 0.2794)
						)
						(arc
							(start 0.2032 0.2794)
							(mid 0.239121 0.264521)
							(end 0.254 0.2286)
						)
						(arc
							(start 0.254 -0.2286)
							(mid 0.239121 -0.264521)
							(end 0.2032 -0.2794)
						)
					)
					(width 0)
					(fill yes)
				)
			)
		)
		(pad "2" smd custom
			(at 0 0.4318 90)
			(size 0.127 0.127)
			(layers "F.Cu" "F.Mask" "F.Paste")
			(net "TEMP_1_ALERT#")
			(options
				(clearance outline)
				(anchor circle)
			)
			(primitives
				(gr_poly
					(pts
						(arc
							(start -0.2032 -0.2794)
							(mid -0.239121 -0.264521)
							(end -0.254 -0.2286)
						)
						(arc
							(start -0.254 0.2286)
							(mid -0.239121 0.264521)
							(end -0.2032 0.2794)
						)
						(arc
							(start 0.2032 0.2794)
							(mid 0.239121 0.264521)
							(end 0.254 0.2286)
						)
						(arc
							(start 0.254 -0.2286)
							(mid 0.239121 -0.264521)
							(end 0.2032 -0.2794)
						)
					)
					(width 0)
					(fill yes)
				)
			)
		)
	)
	(footprint ""
		(layer "F.Cu")
		(at 157.226 -52.832 -90)
		(property "Reference" "C311"
			(at 0 0 270)
			(layer "F.SilkS")
			(hide yes)
			(effects
				(font
					(size 1.27 1.27)
				)
			)
		)
		(property "Value" "SCD1U16V2KX-3GP"
			(at 1.8923 -1.2065 270)
			(unlocked yes)
			(layer "F.Fab")
			(hide yes)
			(effects
				(font
					(size 1.016 1.016)
					(thickness 0.1524)
				)
			)
		)
		(property "Device Type" "C402H22"
			(at 1.8923 -2.7305 270)
			(unlocked yes)
			(layer "F.Fab")
			(hide yes)
			(effects
				(font
					(size 1.016 1.016)
					(thickness 0.1524)
				)
			)
		)
		(duplicate_pad_numbers_are_jumpers no)
		(fp_rect
			(start -0.381 0.7366)
			(end 0.381 -0.7366)
			(stroke
				(width 0)
				(type default)
			)
			(fill no)
			(layer "F.CrtYd")
		)
		(fp_rect
			(start -0.381 0.7366)
			(end 0.381 -0.7366)
			(stroke
				(width 0)
				(type default)
			)
			(fill no)
			(layer "F.Fab")
		)
		(pad "1" smd custom
			(at 0 -0.4572 270)
			(size 0.1143 0.1143)
			(layers "F.Cu" "F.Mask" "F.Paste")
			(net "P3V3_STBY")
			(options
				(clearance outline)
				(anchor circle)
			)
			(primitives
				(gr_poly
					(pts
						(arc
							(start -0.254 -0.1778)
							(mid -0.239121 -0.213721)
							(end -0.2032 -0.2286)
						)
						(arc
							(start 0.2032 -0.2286)
							(mid 0.239121 -0.213721)
							(end 0.254 -0.1778)
						)
						(arc
							(start 0.254 0.1778)
							(mid 0.239121 0.213721)
							(end 0.2032 0.2286)
						)
						(arc
							(start -0.2032 0.2286)
							(mid -0.239121 0.213721)
							(end -0.254 0.1778)
						)
					)
					(width 0)
					(fill yes)
				)
			)
		)
		(pad "2" smd custom
			(at 0 0.4572 270)
			(size 0.1143 0.1143)
			(layers "F.Cu" "F.Mask" "F.Paste")
			(net "GND")
			(options
				(clearance outline)
				(anchor circle)
			)
			(primitives
				(gr_poly
					(pts
						(arc
							(start -0.254 -0.1778)
							(mid -0.239121 -0.213721)
							(end -0.2032 -0.2286)
						)
						(arc
							(start 0.2032 -0.2286)
							(mid 0.239121 -0.213721)
							(end 0.254 -0.1778)
						)
						(arc
							(start 0.254 0.1778)
							(mid 0.239121 0.213721)
							(end 0.2032 0.2286)
						)
						(arc
							(start -0.2032 0.2286)
							(mid -0.239121 0.213721)
							(end -0.254 0.1778)
						)
					)
					(width 0)
					(fill yes)
				)
			)
		)
	)
	(footprint ""
		(layer "F.Cu")
		(at 31.623 -33.02)
		(property "Reference" "R274"
			(at 0 0 0)
			(layer "F.SilkS")
			(hide yes)
			(effects
				(font
					(size 1.27 1.27)
				)
			)
		)
		(property "Value" "1KR2F-3-GP"
			(at 0.064008 -3.993896 0)
			(unlocked yes)
			(layer "F.Fab")
			(hide yes)
			(effects
				(font
					(size 1.016 1.016)
					(thickness 0.1524)
				)
			)
		)
		(property "Device Type" "R402H16"
			(at 0.064008 -5.517896 0)
			(unlocked yes)
			(layer "F.Fab")
			(hide yes)
			(effects
				(font
					(size 1.016 1.016)
					(thickness 0.1524)
				)
			)
		)
		(duplicate_pad_numbers_are_jumpers no)
		(fp_rect
			(start -0.381 0.8382)
			(end 0.381 -0.8382)
			(stroke
				(width 0)
				(type default)
			)
			(fill no)
			(layer "F.CrtYd")
		)
		(fp_rect
			(start -0.381 0.8382)
			(end 0.381 -0.8382)
			(stroke
				(width 0)
				(type default)
			)
			(fill no)
			(layer "F.Fab")
		)
		(pad "1" smd custom
			(at 0 -0.4318)
			(size 0.127 0.127)
			(layers "F.Cu" "F.Mask" "F.Paste")
			(net "P3V3")
			(options
				(clearance outline)
				(anchor circle)
			)
			(primitives
				(gr_poly
					(pts
						(arc
							(start -0.2032 -0.2794)
							(mid -0.239121 -0.264521)
							(end -0.254 -0.2286)
						)
						(arc
							(start -0.254 0.2286)
							(mid -0.239121 0.264521)
							(end -0.2032 0.2794)
						)
						(arc
							(start 0.2032 0.2794)
							(mid 0.239121 0.264521)
							(end 0.254 0.2286)
						)
						(arc
							(start 0.254 -0.2286)
							(mid 0.239121 -0.264521)
							(end 0.2032 -0.2794)
						)
					)
					(width 0)
					(fill yes)
				)
			)
		)
		(pad "2" smd custom
			(at 0 0.4318)
			(size 0.127 0.127)
			(layers "F.Cu" "F.Mask" "F.Paste")
			(net "XDP_RST_BTN_R#")
			(options
				(clearance outline)
				(anchor circle)
			)
			(primitives
				(gr_poly
					(pts
						(arc
							(start -0.2032 -0.2794)
							(mid -0.239121 -0.264521)
							(end -0.254 -0.2286)
						)
						(arc
							(start -0.254 0.2286)
							(mid -0.239121 0.264521)
							(end -0.2032 0.2794)
						)
						(arc
							(start 0.2032 0.2794)
							(mid 0.239121 0.264521)
							(end 0.254 0.2286)
						)
						(arc
							(start 0.254 -0.2286)
							(mid 0.239121 -0.264521)
							(end 0.2032 -0.2794)
						)
					)
					(width 0)
					(fill yes)
				)
			)
		)
	)
	(footprint ""
		(layer "F.Cu")
		(at 78.232 -65.913)
		(property "Reference" "R189"
			(at 0 0 0)
			(layer "F.SilkS")
			(hide yes)
			(effects
				(font
					(size 1.27 1.27)
				)
			)
		)
		(property "Value" "0R2J-2-GP"
			(at 0.064008 -3.993896 0)
			(unlocked yes)
			(layer "F.Fab")
			(hide yes)
			(effects
				(font
					(size 1.016 1.016)
					(thickness 0.1524)
				)
			)
		)
		(property "Device Type" "R402H16"
			(at 0.064008 -5.517896 0)
			(unlocked yes)
			(layer "F.Fab")
			(hide yes)
			(effects
				(font
					(size 1.016 1.016)
					(thickness 0.1524)
				)
			)
		)
		(duplicate_pad_numbers_are_jumpers no)
		(fp_rect
			(start -0.381 0.8382)
			(end 0.381 -0.8382)
			(stroke
				(width 0)
				(type default)
			)
			(fill no)
			(layer "F.CrtYd")
		)
		(fp_rect
			(start -0.381 0.8382)
			(end 0.381 -0.8382)
			(stroke
				(width 0)
				(type default)
			)
			(fill no)
			(layer "F.Fab")
		)
		(pad "1" smd custom
			(at 0 -0.4318)
			(size 0.127 0.127)
			(layers "F.Cu" "F.Mask" "F.Paste")
			(net "PVCCP")
			(options
				(clearance outline)
				(anchor circle)
			)
			(primitives
				(gr_poly
					(pts
						(arc
							(start -0.2032 -0.2794)
							(mid -0.239121 -0.264521)
							(end -0.254 -0.2286)
						)
						(arc
							(start -0.254 0.2286)
							(mid -0.239121 0.264521)
							(end -0.2032 0.2794)
						)
						(arc
							(start 0.2032 0.2794)
							(mid 0.239121 0.264521)
							(end 0.254 0.2286)
						)
						(arc
							(start 0.254 -0.2286)
							(mid 0.239121 -0.264521)
							(end 0.2032 -0.2794)
						)
					)
					(width 0)
					(fill yes)
				)
			)
		)
		(pad "2" smd custom
			(at 0 0.4318)
			(size 0.127 0.127)
			(layers "F.Cu" "F.Mask" "F.Paste")
			(net "PVCCP_SENSE")
			(options
				(clearance outline)
				(anchor circle)
			)
			(primitives
				(gr_poly
					(pts
						(arc
							(start -0.2032 -0.2794)
							(mid -0.239121 -0.264521)
							(end -0.254 -0.2286)
						)
						(arc
							(start -0.254 0.2286)
							(mid -0.239121 0.264521)
							(end -0.2032 0.2794)
						)
						(arc
							(start 0.2032 0.2794)
							(mid 0.239121 0.264521)
							(end 0.254 0.2286)
						)
						(arc
							(start 0.254 -0.2286)
							(mid 0.239121 -0.264521)
							(end 0.2032 -0.2794)
						)
					)
					(width 0)
					(fill yes)
				)
			)
		)
	)
	(footprint ""
		(layer "F.Cu")
		(at 7.5184 -21.463 -90)
		(property "Reference" "PR111"
			(at 0 0 270)
			(layer "F.SilkS")
			(hide yes)
			(effects
				(font
					(size 1.27 1.27)
				)
			)
		)
		(property "Value" "187KR2F-GP"
			(at 1.7907 -1.1176 270)
			(unlocked yes)
			(layer "F.Fab")
			(hide yes)
			(effects
				(font
					(size 1.016 1.016)
					(thickness 0.1524)
				)
			)
		)
		(property "Device Type" "R402H16"
			(at 1.7907 -2.6416 270)
			(unlocked yes)
			(layer "F.Fab")
			(hide yes)
			(effects
				(font
					(size 1.016 1.016)
					(thickness 0.1524)
				)
			)
		)
		(duplicate_pad_numbers_are_jumpers no)
		(fp_rect
			(start -0.381 0.8382)
			(end 0.381 -0.8382)
			(stroke
				(width 0)
				(type default)
			)
			(fill no)
			(layer "F.CrtYd")
		)
		(fp_rect
			(start -0.381 0.8382)
			(end 0.381 -0.8382)
			(stroke
				(width 0)
				(type default)
			)
			(fill no)
			(layer "F.Fab")
		)
		(pad "1" smd custom
			(at 0 -0.4318 270)
			(size 0.127 0.127)
			(layers "F.Cu" "F.Mask" "F.Paste")
			(net "P1V0_RF")
			(options
				(clearance outline)
				(anchor circle)
			)
			(primitives
				(gr_poly
					(pts
						(arc
							(start -0.2032 -0.2794)
							(mid -0.239121 -0.264521)
							(end -0.254 -0.2286)
						)
						(arc
							(start -0.254 0.2286)
							(mid -0.239121 0.264521)
							(end -0.2032 0.2794)
						)
						(arc
							(start 0.2032 0.2794)
							(mid 0.239121 0.264521)
							(end 0.254 0.2286)
						)
						(arc
							(start 0.254 -0.2286)
							(mid 0.239121 -0.264521)
							(end 0.2032 -0.2794)
						)
					)
					(width 0)
					(fill yes)
				)
			)
		)
		(pad "2" smd custom
			(at 0 0.4318 270)
			(size 0.127 0.127)
			(layers "F.Cu" "F.Mask" "F.Paste")
			(net "AGND_P1V0")
			(options
				(clearance outline)
				(anchor circle)
			)
			(primitives
				(gr_poly
					(pts
						(arc
							(start -0.2032 -0.2794)
							(mid -0.239121 -0.264521)
							(end -0.254 -0.2286)
						)
						(arc
							(start -0.254 0.2286)
							(mid -0.239121 0.264521)
							(end -0.2032 0.2794)
						)
						(arc
							(start 0.2032 0.2794)
							(mid 0.239121 0.264521)
							(end 0.254 0.2286)
						)
						(arc
							(start 0.254 -0.2286)
							(mid 0.239121 -0.264521)
							(end 0.2032 -0.2794)
						)
					)
					(width 0)
					(fill yes)
				)
			)
		)
	)
	(footprint ""
		(layer "F.Cu")
		(at 74.168 -42.418 90)
		(property "Reference" "R72"
			(at 0 0 90)
			(layer "F.SilkS")
			(hide yes)
			(effects
				(font
					(size 1.27 1.27)
				)
			)
		)
		(property "Value" "4K7R2F-GP"
			(at 0.064008 -3.993896 90)
			(unlocked yes)
			(layer "F.Fab")
			(hide yes)
			(effects
				(font
					(size 1.016 1.016)
					(thickness 0.1524)
				)
			)
		)
		(property "Device Type" "R402H16"
			(at 0.064008 -5.517896 90)
			(unlocked yes)
			(layer "F.Fab")
			(hide yes)
			(effects
				(font
					(size 1.016 1.016)
					(thickness 0.1524)
				)
			)
		)
		(duplicate_pad_numbers_are_jumpers no)
		(fp_rect
			(start -0.381 0.8382)
			(end 0.381 -0.8382)
			(stroke
				(width 0)
				(type default)
			)
			(fill no)
			(layer "F.CrtYd")
		)
		(fp_rect
			(start -0.381 0.8382)
			(end 0.381 -0.8382)
			(stroke
				(width 0)
				(type default)
			)
			(fill no)
			(layer "F.Fab")
		)
		(pad "1" smd custom
			(at 0 -0.4318 90)
			(size 0.127 0.127)
			(layers "F.Cu" "F.Mask" "F.Paste")
			(net "P3V3")
			(options
				(clearance outline)
				(anchor circle)
			)
			(primitives
				(gr_poly
					(pts
						(arc
							(start -0.2032 -0.2794)
							(mid -0.239121 -0.264521)
							(end -0.254 -0.2286)
						)
						(arc
							(start -0.254 0.2286)
							(mid -0.239121 0.264521)
							(end -0.2032 0.2794)
						)
						(arc
							(start 0.2032 0.2794)
							(mid 0.239121 0.264521)
							(end 0.254 0.2286)
						)
						(arc
							(start 0.254 -0.2286)
							(mid 0.239121 -0.264521)
							(end 0.2032 -0.2794)
						)
					)
					(width 0)
					(fill yes)
				)
			)
		)
		(pad "2" smd custom
			(at 0 0.4318 90)
			(size 0.127 0.127)
			(layers "F.Cu" "F.Mask" "F.Paste")
			(net "CPU_ERR_N2")
			(options
				(clearance outline)
				(anchor circle)
			)
			(primitives
				(gr_poly
					(pts
						(arc
							(start -0.2032 -0.2794)
							(mid -0.239121 -0.264521)
							(end -0.254 -0.2286)
						)
						(arc
							(start -0.254 0.2286)
							(mid -0.239121 0.264521)
							(end -0.2032 0.2794)
						)
						(arc
							(start 0.2032 0.2794)
							(mid 0.239121 0.264521)
							(end 0.254 0.2286)
						)
						(arc
							(start 0.254 -0.2286)
							(mid 0.239121 -0.264521)
							(end 0.2032 -0.2794)
						)
					)
					(width 0)
					(fill yes)
				)
			)
		)
	)
	(footprint ""
		(layer "F.Cu")
		(at 27.5717 -36.576)
		(property "Reference" "PR200"
			(at 0 0 0)
			(layer "F.SilkS")
			(hide yes)
			(effects
				(font
					(size 1.27 1.27)
				)
			)
		)
		(property "Value" "10R3F-GP"
			(at -0.0254 -2.0193 0)
			(unlocked yes)
			(layer "F.Fab")
			(hide yes)
			(effects
				(font
					(size 1.016 1.016)
					(thickness 0.1524)
				)
			)
		)
		(property "Device Type" "R603H22"
			(at -0.0254 -3.5433 0)
			(unlocked yes)
			(layer "F.Fab")
			(hide yes)
			(effects
				(font
					(size 1.016 1.016)
					(thickness 0.1524)
				)
			)
		)
		(duplicate_pad_numbers_are_jumpers no)
		(fp_line
			(start -0.2032 0)
			(end -0.4191 0)
			(stroke
				(width 0.2032)
				(type default)
			)
			(layer "F.SilkS")
		)
		(fp_line
			(start 0.4318 0)
			(end 0.2032 0)
			(stroke
				(width 0.2032)
				(type default)
			)
			(layer "F.SilkS")
		)
		(fp_rect
			(start -0.635 1.1811)
			(end 0.635 -1.1811)
			(stroke
				(width 0)
				(type default)
			)
			(fill no)
			(layer "F.CrtYd")
		)
		(fp_rect
			(start -0.635 1.1811)
			(end 0.635 -1.1811)
			(stroke
				(width 0)
				(type default)
			)
			(fill no)
			(layer "F.Fab")
		)
		(pad "1" smd custom
			(at 0 -0.6604)
			(size 0.19685 0.19685)
			(layers "F.Cu" "F.Mask" "F.Paste")
			(net "P3V3_STBY_OUT")
			(options
				(clearance outline)
				(anchor circle)
			)
			(primitives
				(gr_poly
					(pts
						(arc
							(start 0.508 -0.2921)
							(mid 0.478242 -0.363942)
							(end 0.4064 -0.3937)
						)
						(arc
							(start -0.4064 -0.3937)
							(mid -0.478242 -0.363942)
							(end -0.508 -0.2921)
						)
						(arc
							(start -0.508 0.2921)
							(mid -0.478242 0.363942)
							(end -0.4064 0.3937)
						)
						(arc
							(start 0.4064 0.3937)
							(mid 0.478242 0.363942)
							(end 0.508 0.2921)
						)
					)
					(width 0)
					(fill yes)
				)
			)
		)
		(pad "2" smd custom
			(at 0 0.6604)
			(size 0.19685 0.19685)
			(layers "F.Cu" "F.Mask" "F.Paste")
			(net "P3V3_STBY_VFB_R")
			(options
				(clearance outline)
				(anchor circle)
			)
			(primitives
				(gr_poly
					(pts
						(arc
							(start 0.508 -0.2921)
							(mid 0.478242 -0.363942)
							(end 0.4064 -0.3937)
						)
						(arc
							(start -0.4064 -0.3937)
							(mid -0.478242 -0.363942)
							(end -0.508 -0.2921)
						)
						(arc
							(start -0.508 0.2921)
							(mid -0.478242 0.363942)
							(end -0.4064 0.3937)
						)
						(arc
							(start 0.4064 0.3937)
							(mid 0.478242 0.363942)
							(end 0.508 0.2921)
						)
					)
					(width 0)
					(fill yes)
				)
			)
		)
	)
	(footprint ""
		(layer "F.Cu")
		(at 56.007 -34.544 -90)
		(property "Reference" "R116"
			(at 0 0 270)
			(layer "F.SilkS")
			(hide yes)
			(effects
				(font
					(size 1.27 1.27)
				)
			)
		)
		(property "Value" "2K2R2F-GP"
			(at 0.064008 -3.993896 270)
			(unlocked yes)
			(layer "F.Fab")
			(hide yes)
			(effects
				(font
					(size 1.016 1.016)
					(thickness 0.1524)
				)
			)
		)
		(property "Device Type" "R402H16"
			(at 0.064008 -5.517896 270)
			(unlocked yes)
			(layer "F.Fab")
			(hide yes)
			(effects
				(font
					(size 1.016 1.016)
					(thickness 0.1524)
				)
			)
		)
		(duplicate_pad_numbers_are_jumpers no)
		(fp_rect
			(start -0.381 0.8382)
			(end 0.381 -0.8382)
			(stroke
				(width 0)
				(type default)
			)
			(fill no)
			(layer "F.CrtYd")
		)
		(fp_rect
			(start -0.381 0.8382)
			(end 0.381 -0.8382)
			(stroke
				(width 0)
				(type default)
			)
			(fill no)
			(layer "F.Fab")
		)
		(pad "1" smd custom
			(at 0 -0.4318 270)
			(size 0.127 0.127)
			(layers "F.Cu" "F.Mask" "F.Paste")
			(net "P3V3_CPU")
			(options
				(clearance outline)
				(anchor circle)
			)
			(primitives
				(gr_poly
					(pts
						(arc
							(start -0.2032 -0.2794)
							(mid -0.239121 -0.264521)
							(end -0.254 -0.2286)
						)
						(arc
							(start -0.254 0.2286)
							(mid -0.239121 0.264521)
							(end -0.2032 0.2794)
						)
						(arc
							(start 0.2032 0.2794)
							(mid 0.239121 0.264521)
							(end 0.254 0.2286)
						)
						(arc
							(start 0.254 -0.2286)
							(mid 0.239121 -0.264521)
							(end 0.2032 -0.2794)
						)
					)
					(width 0)
					(fill yes)
				)
			)
		)
		(pad "2" smd custom
			(at 0 0.4318 270)
			(size 0.127 0.127)
			(layers "F.Cu" "F.Mask" "F.Paste")
			(net "SPI_WP_R_N_1")
			(options
				(clearance outline)
				(anchor circle)
			)
			(primitives
				(gr_poly
					(pts
						(arc
							(start -0.2032 -0.2794)
							(mid -0.239121 -0.264521)
							(end -0.254 -0.2286)
						)
						(arc
							(start -0.254 0.2286)
							(mid -0.239121 0.264521)
							(end -0.2032 0.2794)
						)
						(arc
							(start 0.2032 0.2794)
							(mid 0.239121 0.264521)
							(end 0.254 0.2286)
						)
						(arc
							(start 0.254 -0.2286)
							(mid 0.239121 -0.264521)
							(end 0.2032 -0.2794)
						)
					)
					(width 0)
					(fill yes)
				)
			)
		)
	)
	(footprint ""
		(layer "F.Cu")
		(at 143.891 -21.082 180)
		(property "Reference" "R89"
			(at 0 0 180)
			(layer "F.SilkS")
			(hide yes)
			(effects
				(font
					(size 1.27 1.27)
				)
			)
		)
		(property "Value" "300R2F-GP"
			(at 0.064008 -3.993896 180)
			(unlocked yes)
			(layer "F.Fab")
			(hide yes)
			(effects
				(font
					(size 1.016 1.016)
					(thickness 0.1524)
				)
			)
		)
		(property "Device Type" "R402H16"
			(at 0.064008 -5.517896 180)
			(unlocked yes)
			(layer "F.Fab")
			(hide yes)
			(effects
				(font
					(size 1.016 1.016)
					(thickness 0.1524)
				)
			)
		)
		(duplicate_pad_numbers_are_jumpers no)
		(fp_rect
			(start -0.381 0.8382)
			(end 0.381 -0.8382)
			(stroke
				(width 0)
				(type default)
			)
			(fill no)
			(layer "F.CrtYd")
		)
		(fp_rect
			(start -0.381 0.8382)
			(end 0.381 -0.8382)
			(stroke
				(width 0)
				(type default)
			)
			(fill no)
			(layer "F.Fab")
		)
		(pad "1" smd custom
			(at 0 -0.4318 180)
			(size 0.127 0.127)
			(layers "F.Cu" "F.Mask" "F.Paste")
			(net "C_CONF_DONE")
			(options
				(clearance outline)
				(anchor circle)
			)
			(primitives
				(gr_poly
					(pts
						(arc
							(start -0.2032 -0.2794)
							(mid -0.239121 -0.264521)
							(end -0.254 -0.2286)
						)
						(arc
							(start -0.254 0.2286)
							(mid -0.239121 0.264521)
							(end -0.2032 0.2794)
						)
						(arc
							(start 0.2032 0.2794)
							(mid 0.239121 0.264521)
							(end 0.254 0.2286)
						)
						(arc
							(start 0.254 -0.2286)
							(mid 0.239121 -0.264521)
							(end 0.2032 -0.2794)
						)
					)
					(width 0)
					(fill yes)
				)
			)
		)
		(pad "2" smd custom
			(at 0 0.4318 180)
			(size 0.127 0.127)
			(layers "F.Cu" "F.Mask" "F.Paste")
			(net "P3V3_STBY")
			(options
				(clearance outline)
				(anchor circle)
			)
			(primitives
				(gr_poly
					(pts
						(arc
							(start -0.2032 -0.2794)
							(mid -0.239121 -0.264521)
							(end -0.254 -0.2286)
						)
						(arc
							(start -0.254 0.2286)
							(mid -0.239121 0.264521)
							(end -0.2032 0.2794)
						)
						(arc
							(start 0.2032 0.2794)
							(mid 0.239121 0.264521)
							(end 0.254 0.2286)
						)
						(arc
							(start 0.254 -0.2286)
							(mid 0.239121 -0.264521)
							(end 0.2032 -0.2794)
						)
					)
					(width 0)
					(fill yes)
				)
			)
		)
	)
	(footprint ""
		(layer "F.Cu")
		(at 17.4752 -34.544 180)
		(property "Reference" "PC164"
			(at 0 0 180)
			(layer "F.SilkS")
			(hide yes)
			(effects
				(font
					(size 1.27 1.27)
				)
			)
		)
		(property "Value" "SCD1U50V3KX-GP"
			(at -0.0254 -2.0193 180)
			(unlocked yes)
			(layer "F.Fab")
			(hide yes)
			(effects
				(font
					(size 1.016 1.016)
					(thickness 0.1524)
				)
			)
		)
		(property "Device Type" "C603H36"
			(at -0.0254 -3.5433 180)
			(unlocked yes)
			(layer "F.Fab")
			(hide yes)
			(effects
				(font
					(size 1.016 1.016)
					(thickness 0.1524)
				)
			)
		)
		(duplicate_pad_numbers_are_jumpers no)
		(fp_line
			(start -0.4064 0)
			(end 0.4064 0)
			(stroke
				(width 0.2286)
				(type default)
			)
			(layer "F.SilkS")
		)
		(fp_rect
			(start -0.635 1.1811)
			(end 0.635 -1.1811)
			(stroke
				(width 0)
				(type default)
			)
			(fill no)
			(layer "F.CrtYd")
		)
		(fp_rect
			(start -0.635 1.1811)
			(end 0.635 -1.1811)
			(stroke
				(width 0)
				(type default)
			)
			(fill no)
			(layer "F.Fab")
		)
		(pad "1" smd custom
			(at 0 -0.6604 180)
			(size 0.19685 0.19685)
			(layers "F.Cu" "F.Mask" "F.Paste")
			(net "P3V3_STBY_VBST_RC")
			(options
				(clearance outline)
				(anchor circle)
			)
			(primitives
				(gr_poly
					(pts
						(arc
							(start 0.508 -0.2921)
							(mid 0.478242 -0.363942)
							(end 0.4064 -0.3937)
						)
						(arc
							(start -0.4064 -0.3937)
							(mid -0.478242 -0.363942)
							(end -0.508 -0.2921)
						)
						(arc
							(start -0.508 0.2921)
							(mid -0.478242 0.363942)
							(end -0.4064 0.3937)
						)
						(arc
							(start 0.4064 0.3937)
							(mid 0.478242 0.363942)
							(end 0.508 0.2921)
						)
					)
					(width 0)
					(fill yes)
				)
			)
		)
		(pad "2" smd custom
			(at 0 0.6604 180)
			(size 0.19685 0.19685)
			(layers "F.Cu" "F.Mask" "F.Paste")
			(net "P3V3_STBY_LL")
			(options
				(clearance outline)
				(anchor circle)
			)
			(primitives
				(gr_poly
					(pts
						(arc
							(start 0.508 -0.2921)
							(mid 0.478242 -0.363942)
							(end 0.4064 -0.3937)
						)
						(arc
							(start -0.4064 -0.3937)
							(mid -0.478242 -0.363942)
							(end -0.508 -0.2921)
						)
						(arc
							(start -0.508 0.2921)
							(mid -0.478242 0.363942)
							(end -0.4064 0.3937)
						)
						(arc
							(start 0.4064 0.3937)
							(mid 0.478242 0.363942)
							(end 0.508 0.2921)
						)
					)
					(width 0)
					(fill yes)
				)
			)
		)
	)
	(footprint ""
		(layer "F.Cu")
		(at 64.77 -47.371 -90)
		(property "Reference" "R40"
			(at 0 0 270)
			(layer "F.SilkS")
			(hide yes)
			(effects
				(font
					(size 1.27 1.27)
				)
			)
		)
		(property "Value" "0R2J-2-GP"
			(at 0.064008 -3.993896 270)
			(unlocked yes)
			(layer "F.Fab")
			(hide yes)
			(effects
				(font
					(size 1.016 1.016)
					(thickness 0.1524)
				)
			)
		)
		(property "Device Type" "R402H16"
			(at 0.064008 -5.517896 270)
			(unlocked yes)
			(layer "F.Fab")
			(hide yes)
			(effects
				(font
					(size 1.016 1.016)
					(thickness 0.1524)
				)
			)
		)
		(duplicate_pad_numbers_are_jumpers no)
		(fp_rect
			(start -0.381 0.8382)
			(end 0.381 -0.8382)
			(stroke
				(width 0)
				(type default)
			)
			(fill no)
			(layer "F.CrtYd")
		)
		(fp_rect
			(start -0.381 0.8382)
			(end 0.381 -0.8382)
			(stroke
				(width 0)
				(type default)
			)
			(fill no)
			(layer "F.Fab")
		)
		(pad "1" smd custom
			(at 0 -0.4318 270)
			(size 0.127 0.127)
			(layers "F.Cu" "F.Mask" "F.Paste")
			(net "SMB_HOST_LV_R_DATA")
			(options
				(clearance outline)
				(anchor circle)
			)
			(primitives
				(gr_poly
					(pts
						(arc
							(start -0.2032 -0.2794)
							(mid -0.239121 -0.264521)
							(end -0.254 -0.2286)
						)
						(arc
							(start -0.254 0.2286)
							(mid -0.239121 0.264521)
							(end -0.2032 0.2794)
						)
						(arc
							(start 0.2032 0.2794)
							(mid 0.239121 0.264521)
							(end 0.254 0.2286)
						)
						(arc
							(start 0.254 -0.2286)
							(mid 0.239121 -0.264521)
							(end 0.2032 -0.2794)
						)
					)
					(width 0)
					(fill yes)
				)
			)
		)
		(pad "2" smd custom
			(at 0 0.4318 270)
			(size 0.127 0.127)
			(layers "F.Cu" "F.Mask" "F.Paste")
			(net "SMB_HOST_LV_DATA")
			(options
				(clearance outline)
				(anchor circle)
			)
			(primitives
				(gr_poly
					(pts
						(arc
							(start -0.2032 -0.2794)
							(mid -0.239121 -0.264521)
							(end -0.254 -0.2286)
						)
						(arc
							(start -0.254 0.2286)
							(mid -0.239121 0.264521)
							(end -0.2032 0.2794)
						)
						(arc
							(start 0.2032 0.2794)
							(mid 0.239121 0.264521)
							(end 0.254 0.2286)
						)
						(arc
							(start 0.254 -0.2286)
							(mid 0.239121 -0.264521)
							(end 0.2032 -0.2794)
						)
					)
					(width 0)
					(fill yes)
				)
			)
		)
	)
	(footprint ""
		(layer "F.Cu")
		(at 118.237 -64.389 180)
		(property "Reference" "R226"
			(at 0 0 180)
			(layer "F.SilkS")
			(hide yes)
			(effects
				(font
					(size 1.27 1.27)
				)
			)
		)
		(property "Value" "0R2J-2-GP"
			(at 0.064008 -3.993896 180)
			(unlocked yes)
			(layer "F.Fab")
			(hide yes)
			(effects
				(font
					(size 1.016 1.016)
					(thickness 0.1524)
				)
			)
		)
		(property "Device Type" "R402H16"
			(at 0.064008 -5.517896 180)
			(unlocked yes)
			(layer "F.Fab")
			(hide yes)
			(effects
				(font
					(size 1.016 1.016)
					(thickness 0.1524)
				)
			)
		)
		(duplicate_pad_numbers_are_jumpers no)
		(fp_rect
			(start -0.381 0.8382)
			(end 0.381 -0.8382)
			(stroke
				(width 0)
				(type default)
			)
			(fill no)
			(layer "F.CrtYd")
		)
		(fp_rect
			(start -0.381 0.8382)
			(end 0.381 -0.8382)
			(stroke
				(width 0)
				(type default)
			)
			(fill no)
			(layer "F.Fab")
		)
		(pad "1" smd custom
			(at 0 -0.4318 180)
			(size 0.127 0.127)
			(layers "F.Cu" "F.Mask" "F.Paste")
			(net "SMB_M_A1_R_CLK")
			(options
				(clearance outline)
				(anchor circle)
			)
			(primitives
				(gr_poly
					(pts
						(arc
							(start -0.2032 -0.2794)
							(mid -0.239121 -0.264521)
							(end -0.254 -0.2286)
						)
						(arc
							(start -0.254 0.2286)
							(mid -0.239121 0.264521)
							(end -0.2032 0.2794)
						)
						(arc
							(start 0.2032 0.2794)
							(mid 0.239121 0.264521)
							(end 0.254 0.2286)
						)
						(arc
							(start 0.254 -0.2286)
							(mid 0.239121 -0.264521)
							(end 0.2032 -0.2794)
						)
					)
					(width 0)
					(fill yes)
				)
			)
		)
		(pad "2" smd custom
			(at 0 0.4318 180)
			(size 0.127 0.127)
			(layers "F.Cu" "F.Mask" "F.Paste")
			(net "SMB_HOST_LV_CLK")
			(options
				(clearance outline)
				(anchor circle)
			)
			(primitives
				(gr_poly
					(pts
						(arc
							(start -0.2032 -0.2794)
							(mid -0.239121 -0.264521)
							(end -0.254 -0.2286)
						)
						(arc
							(start -0.254 0.2286)
							(mid -0.239121 0.264521)
							(end -0.2032 0.2794)
						)
						(arc
							(start 0.2032 0.2794)
							(mid 0.239121 0.264521)
							(end 0.254 0.2286)
						)
						(arc
							(start 0.254 -0.2286)
							(mid 0.239121 -0.264521)
							(end 0.2032 -0.2794)
						)
					)
					(width 0)
					(fill yes)
				)
			)
		)
	)
	(footprint ""
		(layer "F.Cu")
		(at 181.61 -36.068)
		(property "Reference" "PR134"
			(at 0 0 0)
			(layer "F.SilkS")
			(hide yes)
			(effects
				(font
					(size 1.27 1.27)
				)
			)
		)
		(property "Value" "0R2J-2-GP"
			(at 0.064008 -3.993896 0)
			(unlocked yes)
			(layer "F.Fab")
			(hide yes)
			(effects
				(font
					(size 1.016 1.016)
					(thickness 0.1524)
				)
			)
		)
		(property "Device Type" "R402H16"
			(at 0.064008 -5.517896 0)
			(unlocked yes)
			(layer "F.Fab")
			(hide yes)
			(effects
				(font
					(size 1.016 1.016)
					(thickness 0.1524)
				)
			)
		)
		(duplicate_pad_numbers_are_jumpers no)
		(fp_rect
			(start -0.381 0.8382)
			(end 0.381 -0.8382)
			(stroke
				(width 0)
				(type default)
			)
			(fill no)
			(layer "F.CrtYd")
		)
		(fp_rect
			(start -0.381 0.8382)
			(end 0.381 -0.8382)
			(stroke
				(width 0)
				(type default)
			)
			(fill no)
			(layer "F.Fab")
		)
		(pad "1" smd custom
			(at 0 -0.4318)
			(size 0.127 0.127)
			(layers "F.Cu" "F.Mask" "F.Paste")
			(net "VR_PWREN_PVDDR_A")
			(options
				(clearance outline)
				(anchor circle)
			)
			(primitives
				(gr_poly
					(pts
						(arc
							(start -0.2032 -0.2794)
							(mid -0.239121 -0.264521)
							(end -0.254 -0.2286)
						)
						(arc
							(start -0.254 0.2286)
							(mid -0.239121 0.264521)
							(end -0.2032 0.2794)
						)
						(arc
							(start 0.2032 0.2794)
							(mid 0.239121 0.264521)
							(end 0.254 0.2286)
						)
						(arc
							(start 0.254 -0.2286)
							(mid 0.239121 -0.264521)
							(end 0.2032 -0.2794)
						)
					)
					(width 0)
					(fill yes)
				)
			)
		)
		(pad "2" smd custom
			(at 0 0.4318)
			(size 0.127 0.127)
			(layers "F.Cu" "F.Mask" "F.Paste")
			(net "PMU_SLP_S45#")
			(options
				(clearance outline)
				(anchor circle)
			)
			(primitives
				(gr_poly
					(pts
						(arc
							(start -0.2032 -0.2794)
							(mid -0.239121 -0.264521)
							(end -0.254 -0.2286)
						)
						(arc
							(start -0.254 0.2286)
							(mid -0.239121 0.264521)
							(end -0.2032 0.2794)
						)
						(arc
							(start 0.2032 0.2794)
							(mid 0.239121 0.264521)
							(end 0.254 0.2286)
						)
						(arc
							(start 0.254 -0.2286)
							(mid 0.239121 -0.264521)
							(end 0.2032 -0.2794)
						)
					)
					(width 0)
					(fill yes)
				)
			)
		)
	)
	(footprint ""
		(layer "F.Cu")
		(at 188.341 -45.974)
		(property "Reference" "R220"
			(at 0 0 0)
			(layer "F.SilkS")
			(hide yes)
			(effects
				(font
					(size 1.27 1.27)
				)
			)
		)
		(property "Value" "100R2F-L1-GP-U"
			(at 0.064008 -3.993896 0)
			(unlocked yes)
			(layer "F.Fab")
			(hide yes)
			(effects
				(font
					(size 1.016 1.016)
					(thickness 0.1524)
				)
			)
		)
		(property "Device Type" "R402H14"
			(at 0.064008 -5.517896 0)
			(unlocked yes)
			(layer "F.Fab")
			(hide yes)
			(effects
				(font
					(size 1.016 1.016)
					(thickness 0.1524)
				)
			)
		)
		(duplicate_pad_numbers_are_jumpers no)
		(fp_rect
			(start -0.381 0.8382)
			(end 0.381 -0.8382)
			(stroke
				(width 0)
				(type default)
			)
			(fill no)
			(layer "F.CrtYd")
		)
		(fp_rect
			(start -0.381 0.8382)
			(end 0.381 -0.8382)
			(stroke
				(width 0)
				(type default)
			)
			(fill no)
			(layer "F.Fab")
		)
		(pad "1" smd custom
			(at 0 -0.4318)
			(size 0.127 0.127)
			(layers "F.Cu" "F.Mask" "F.Paste")
			(net "PV_VDDR_VREF_B_FB")
			(options
				(clearance outline)
				(anchor circle)
			)
			(primitives
				(gr_poly
					(pts
						(arc
							(start -0.2032 -0.2794)
							(mid -0.239121 -0.264521)
							(end -0.254 -0.2286)
						)
						(arc
							(start -0.254 0.2286)
							(mid -0.239121 0.264521)
							(end -0.2032 0.2794)
						)
						(arc
							(start 0.2032 0.2794)
							(mid 0.239121 0.264521)
							(end 0.254 0.2286)
						)
						(arc
							(start 0.254 -0.2286)
							(mid 0.239121 -0.264521)
							(end 0.2032 -0.2794)
						)
					)
					(width 0)
					(fill yes)
				)
			)
		)
		(pad "2" smd custom
			(at 0 0.4318)
			(size 0.127 0.127)
			(layers "F.Cu" "F.Mask" "F.Paste")
			(net "GND")
			(options
				(clearance outline)
				(anchor circle)
			)
			(primitives
				(gr_poly
					(pts
						(arc
							(start -0.2032 -0.2794)
							(mid -0.239121 -0.264521)
							(end -0.254 -0.2286)
						)
						(arc
							(start -0.254 0.2286)
							(mid -0.239121 0.264521)
							(end -0.2032 0.2794)
						)
						(arc
							(start 0.2032 0.2794)
							(mid 0.239121 0.264521)
							(end 0.254 0.2286)
						)
						(arc
							(start 0.254 -0.2286)
							(mid 0.239121 -0.264521)
							(end 0.2032 -0.2794)
						)
					)
					(width 0)
					(fill yes)
				)
			)
		)
	)
	(footprint ""
		(layer "F.Cu")
		(at 53.848 -12.827)
		(property "Reference" "R412"
			(at 0 0 0)
			(layer "F.SilkS")
			(hide yes)
			(effects
				(font
					(size 1.27 1.27)
				)
			)
		)
		(property "Value" "0R2J-2-GP"
			(at 1.7907 -1.1176 0)
			(unlocked yes)
			(layer "F.Fab")
			(hide yes)
			(effects
				(font
					(size 1.016 1.016)
					(thickness 0.1524)
				)
			)
		)
		(property "Device Type" "R402H16"
			(at 1.7907 -2.6416 0)
			(unlocked yes)
			(layer "F.Fab")
			(hide yes)
			(effects
				(font
					(size 1.016 1.016)
					(thickness 0.1524)
				)
			)
		)
		(duplicate_pad_numbers_are_jumpers no)
		(fp_rect
			(start -0.381 0.8382)
			(end 0.381 -0.8382)
			(stroke
				(width 0)
				(type default)
			)
			(fill no)
			(layer "F.CrtYd")
		)
		(fp_rect
			(start -0.381 0.8382)
			(end 0.381 -0.8382)
			(stroke
				(width 0)
				(type default)
			)
			(fill no)
			(layer "F.Fab")
		)
		(pad "1" smd custom
			(at 0 -0.4318)
			(size 0.127 0.127)
			(layers "F.Cu" "F.Mask" "F.Paste")
			(net "GF_GBE_SMBALRT#")
			(options
				(clearance outline)
				(anchor circle)
			)
			(primitives
				(gr_poly
					(pts
						(arc
							(start -0.2032 -0.2794)
							(mid -0.239121 -0.264521)
							(end -0.254 -0.2286)
						)
						(arc
							(start -0.254 0.2286)
							(mid -0.239121 0.264521)
							(end -0.2032 0.2794)
						)
						(arc
							(start 0.2032 0.2794)
							(mid 0.239121 0.264521)
							(end 0.254 0.2286)
						)
						(arc
							(start 0.254 -0.2286)
							(mid 0.239121 -0.264521)
							(end 0.2032 -0.2794)
						)
					)
					(width 0)
					(fill yes)
				)
			)
		)
		(pad "2" smd custom
			(at 0 0.4318)
			(size 0.127 0.127)
			(layers "F.Cu" "F.Mask" "F.Paste")
			(net "GBE_R_SMBALRT#")
			(options
				(clearance outline)
				(anchor circle)
			)
			(primitives
				(gr_poly
					(pts
						(arc
							(start -0.2032 -0.2794)
							(mid -0.239121 -0.264521)
							(end -0.254 -0.2286)
						)
						(arc
							(start -0.254 0.2286)
							(mid -0.239121 0.264521)
							(end -0.2032 0.2794)
						)
						(arc
							(start 0.2032 0.2794)
							(mid 0.239121 0.264521)
							(end 0.254 0.2286)
						)
						(arc
							(start 0.254 -0.2286)
							(mid 0.239121 -0.264521)
							(end 0.2032 -0.2794)
						)
					)
					(width 0)
					(fill yes)
				)
			)
		)
	)
	(footprint ""
		(layer "F.Cu")
		(at 28.7274 -59.9948)
		(property "Reference" "PR85"
			(at 0 0 0)
			(layer "F.SilkS")
			(hide yes)
			(effects
				(font
					(size 1.27 1.27)
				)
			)
		)
		(property "Value" "0R2J-2-GP"
			(at 1.7907 -1.1176 0)
			(unlocked yes)
			(layer "F.Fab")
			(hide yes)
			(effects
				(font
					(size 1.016 1.016)
					(thickness 0.1524)
				)
			)
		)
		(property "Device Type" "R402H16"
			(at 1.7907 -2.6416 0)
			(unlocked yes)
			(layer "F.Fab")
			(hide yes)
			(effects
				(font
					(size 1.016 1.016)
					(thickness 0.1524)
				)
			)
		)
		(duplicate_pad_numbers_are_jumpers no)
		(fp_rect
			(start -0.381 0.8382)
			(end 0.381 -0.8382)
			(stroke
				(width 0)
				(type default)
			)
			(fill no)
			(layer "F.CrtYd")
		)
		(fp_rect
			(start -0.381 0.8382)
			(end 0.381 -0.8382)
			(stroke
				(width 0)
				(type default)
			)
			(fill no)
			(layer "F.Fab")
		)
		(pad "1" smd custom
			(at 0 -0.4318)
			(size 0.127 0.127)
			(layers "F.Cu" "F.Mask" "F.Paste")
			(net "VCCP_5VBIAS")
			(options
				(clearance outline)
				(anchor circle)
			)
			(primitives
				(gr_poly
					(pts
						(arc
							(start -0.2032 -0.2794)
							(mid -0.239121 -0.264521)
							(end -0.254 -0.2286)
						)
						(arc
							(start -0.254 0.2286)
							(mid -0.239121 0.264521)
							(end -0.2032 0.2794)
						)
						(arc
							(start 0.2032 0.2794)
							(mid 0.239121 0.264521)
							(end 0.254 0.2286)
						)
						(arc
							(start 0.254 -0.2286)
							(mid 0.239121 -0.264521)
							(end 0.2032 -0.2794)
						)
					)
					(width 0)
					(fill yes)
				)
			)
		)
		(pad "2" smd custom
			(at 0 0.4318)
			(size 0.127 0.127)
			(layers "F.Cu" "F.Mask" "F.Paste")
			(net "VR_PVCCP_PVNN_VDD")
			(options
				(clearance outline)
				(anchor circle)
			)
			(primitives
				(gr_poly
					(pts
						(arc
							(start -0.2032 -0.2794)
							(mid -0.239121 -0.264521)
							(end -0.254 -0.2286)
						)
						(arc
							(start -0.254 0.2286)
							(mid -0.239121 0.264521)
							(end -0.2032 0.2794)
						)
						(arc
							(start 0.2032 0.2794)
							(mid 0.239121 0.264521)
							(end 0.254 0.2286)
						)
						(arc
							(start 0.254 -0.2286)
							(mid 0.239121 -0.264521)
							(end 0.2032 -0.2794)
						)
					)
					(width 0)
					(fill yes)
				)
			)
		)
	)
	(footprint ""
		(layer "F.Cu")
		(at 71.247 -14.986 90)
		(property "Reference" "R464"
			(at 0 0 90)
			(layer "F.SilkS")
			(hide yes)
			(effects
				(font
					(size 1.27 1.27)
				)
			)
		)
		(property "Value" "4K7R2F-GP"
			(at 1.7907 -1.1176 90)
			(unlocked yes)
			(layer "F.Fab")
			(hide yes)
			(effects
				(font
					(size 1.016 1.016)
					(thickness 0.1524)
				)
			)
		)
		(property "Device Type" "R402H16"
			(at 1.7907 -2.6416 90)
			(unlocked yes)
			(layer "F.Fab")
			(hide yes)
			(effects
				(font
					(size 1.016 1.016)
					(thickness 0.1524)
				)
			)
		)
		(duplicate_pad_numbers_are_jumpers no)
		(fp_rect
			(start -0.381 0.8382)
			(end 0.381 -0.8382)
			(stroke
				(width 0)
				(type default)
			)
			(fill no)
			(layer "F.CrtYd")
		)
		(fp_rect
			(start -0.381 0.8382)
			(end 0.381 -0.8382)
			(stroke
				(width 0)
				(type default)
			)
			(fill no)
			(layer "F.Fab")
		)
		(pad "1" smd custom
			(at 0 -0.4318 90)
			(size 0.127 0.127)
			(layers "F.Cu" "F.Mask" "F.Paste")
			(net "P3V3_STBY")
			(options
				(clearance outline)
				(anchor circle)
			)
			(primitives
				(gr_poly
					(pts
						(arc
							(start -0.2032 -0.2794)
							(mid -0.239121 -0.264521)
							(end -0.254 -0.2286)
						)
						(arc
							(start -0.254 0.2286)
							(mid -0.239121 0.264521)
							(end -0.2032 0.2794)
						)
						(arc
							(start 0.2032 0.2794)
							(mid 0.239121 0.264521)
							(end 0.254 0.2286)
						)
						(arc
							(start 0.254 -0.2286)
							(mid 0.239121 -0.264521)
							(end 0.2032 -0.2794)
						)
					)
					(width 0)
					(fill yes)
				)
			)
		)
		(pad "2" smd custom
			(at 0 0.4318 90)
			(size 0.127 0.127)
			(layers "F.Cu" "F.Mask" "F.Paste")
			(net "PCIE_GF_I2C_ALERT#")
			(options
				(clearance outline)
				(anchor circle)
			)
			(primitives
				(gr_poly
					(pts
						(arc
							(start -0.2032 -0.2794)
							(mid -0.239121 -0.264521)
							(end -0.254 -0.2286)
						)
						(arc
							(start -0.254 0.2286)
							(mid -0.239121 0.264521)
							(end -0.2032 0.2794)
						)
						(arc
							(start 0.2032 0.2794)
							(mid 0.239121 0.264521)
							(end 0.254 0.2286)
						)
						(arc
							(start 0.254 -0.2286)
							(mid 0.239121 -0.264521)
							(end 0.2032 -0.2794)
						)
					)
					(width 0)
					(fill yes)
				)
			)
		)
	)
	(footprint ""
		(layer "F.Cu")
		(at 159.999934 -5.790692)
		(property "Reference" "DIMM4"
			(at 0 0 0)
			(layer "F.SilkS")
			(hide yes)
			(effects
				(font
					(size 1.27 1.27)
				)
			)
		)
		(property "Value" "DDR3-204P-174-COLAY-1-GP"
			(at -40.682164 -17.468088 0)
			(unlocked yes)
			(layer "F.Fab")
			(hide yes)
			(effects
				(font
					(size 1.016 1.016)
					(thickness 0.1524)
				)
			)
		)
		(property "Device Type" "AS0A626-H8SN-7H-COLAY-1"
			(at -40.682164 -18.992088 0)
			(unlocked yes)
			(layer "F.Fab")
			(hide yes)
			(effects
				(font
					(size 1.016 1.016)
					(thickness 0.1524)
				)
			)
		)
		(duplicate_pad_numbers_are_jumpers no)
		(fp_line
			(start -39.9542 -14.9606)
			(end -38.2524 -14.9606)
			(stroke
				(width 0.1524)
				(type default)
			)
			(layer "F.SilkS")
		)
		(fp_line
			(start -39.9542 -7.6327)
			(end -39.9542 -14.9606)
			(stroke
				(width 0.1524)
				(type default)
			)
			(layer "F.SilkS")
		)
		(fp_line
			(start -38.2524 -23.749)
			(end -31.8008 -23.749)
			(stroke
				(width 0.1524)
				(type default)
			)
			(layer "F.SilkS")
		)
		(fp_line
			(start -38.2524 -14.9606)
			(end -38.2524 -23.749)
			(stroke
				(width 0.1524)
				(type default)
			)
			(layer "F.SilkS")
		)
		(fp_line
			(start -37.2491 -7.6327)
			(end -39.9542 -7.6327)
			(stroke
				(width 0.1524)
				(type default)
			)
			(layer "F.SilkS")
		)
		(fp_line
			(start -37.2491 0.254)
			(end -37.2491 -7.6327)
			(stroke
				(width 0.1524)
				(type default)
			)
			(layer "F.SilkS")
		)
		(fp_line
			(start -36.2585 0.254)
			(end -37.2491 0.254)
			(stroke
				(width 0.1524)
				(type default)
			)
			(layer "F.SilkS")
		)
		(fp_line
			(start -36.2585 5.2578)
			(end -36.2585 0.254)
			(stroke
				(width 0.1524)
				(type default)
			)
			(layer "F.SilkS")
		)
		(fp_line
			(start -32.1437 5.7912)
			(end -32.1183 5.8166)
			(stroke
				(width 0.1524)
				(type default)
			)
			(layer "F.SilkS")
		)
		(fp_line
			(start -32.1183 5.8166)
			(end -31.1531 5.8166)
			(stroke
				(width 0.1524)
				(type default)
			)
			(layer "F.SilkS")
		)
		(fp_line
			(start -31.8008 -23.749)
			(end -31.8008 -21.3106)
			(stroke
				(width 0.1524)
				(type default)
			)
			(layer "F.SilkS")
		)
		(fp_line
			(start -31.8008 -21.3106)
			(end -31.3436 -21.3106)
			(stroke
				(width 0.1524)
				(type default)
			)
			(layer "F.SilkS")
		)
		(fp_line
			(start -31.6484 5.2705)
			(end -31.6484 6.35)
			(stroke
				(width 0.1524)
				(type default)
			)
			(layer "F.SilkS")
		)
		(fp_line
			(start -31.6484 5.2832)
			(end -31.6484 5.2959)
			(stroke
				(width 0.1524)
				(type default)
			)
			(layer "F.SilkS")
		)
		(fp_line
			(start -31.6484 5.2959)
			(end -32.1437 5.7912)
			(stroke
				(width 0.1524)
				(type default)
			)
			(layer "F.SilkS")
		)
		(fp_line
			(start -31.4579 5.3594)
			(end -31.8389 5.3594)
			(stroke
				(width 0.3302)
				(type default)
			)
			(layer "F.SilkS")
		)
		(fp_line
			(start -31.3436 -21.3106)
			(end -31.3436 -14.5542)
			(stroke
				(width 0.1524)
				(type default)
			)
			(layer "F.SilkS")
		)
		(fp_line
			(start -31.3436 -14.5542)
			(end -30.7975 -14.5542)
			(stroke
				(width 0.1524)
				(type default)
			)
			(layer "F.SilkS")
		)
		(fp_line
			(start -31.3436 -9.4488)
			(end -31.3436 -5.2578)
			(stroke
				(width 0.1524)
				(type default)
			)
			(layer "F.SilkS")
		)
		(fp_line
			(start -31.3436 -5.2578)
			(end 31.3436 -5.2578)
			(stroke
				(width 0.1524)
				(type default)
			)
			(layer "F.SilkS")
		)
		(fp_line
			(start -31.1531 5.7658)
			(end -31.6484 5.2705)
			(stroke
				(width 0.1524)
				(type default)
			)
			(layer "F.SilkS")
		)
		(fp_line
			(start -31.1531 5.8166)
			(end -31.1531 5.7658)
			(stroke
				(width 0.1524)
				(type default)
			)
			(layer "F.SilkS")
		)
		(fp_line
			(start -30.7975 -14.5542)
			(end -30.7975 -9.4488)
			(stroke
				(width 0.1524)
				(type default)
			)
			(layer "F.SilkS")
		)
		(fp_line
			(start -30.7975 -9.4488)
			(end -31.3436 -9.4488)
			(stroke
				(width 0.1524)
				(type default)
			)
			(layer "F.SilkS")
		)
		(fp_line
			(start 30.7975 -14.5542)
			(end 31.3436 -14.5542)
			(stroke
				(width 0.1524)
				(type default)
			)
			(layer "F.SilkS")
		)
		(fp_line
			(start 30.7975 -9.4488)
			(end 30.7975 -14.5542)
			(stroke
				(width 0.1524)
				(type default)
			)
			(layer "F.SilkS")
		)
		(fp_line
			(start 31.1658 -5.7785)
			(end 31.1658 -5.7531)
			(stroke
				(width 0.1524)
				(type default)
			)
			(layer "F.SilkS")
		)
		(fp_line
			(start 31.1658 -5.7531)
			(end 31.6357 -5.2832)
			(stroke
				(width 0.1524)
				(type default)
			)
			(layer "F.SilkS")
		)
		(fp_line
			(start 31.3436 -21.3106)
			(end 31.8008 -21.3106)
			(stroke
				(width 0.1524)
				(type default)
			)
			(layer "F.SilkS")
		)
		(fp_line
			(start 31.3436 -14.5542)
			(end 31.3436 -21.3106)
			(stroke
				(width 0.1524)
				(type default)
			)
			(layer "F.SilkS")
		)
		(fp_line
			(start 31.3436 -9.4488)
			(end 30.7975 -9.4488)
			(stroke
				(width 0.1524)
				(type default)
			)
			(layer "F.SilkS")
		)
		(fp_line
			(start 31.3436 -5.2578)
			(end 31.3436 -9.4488)
			(stroke
				(width 0.1524)
				(type default)
			)
			(layer "F.SilkS")
		)
		(fp_line
			(start 31.6357 -5.2832)
			(end 31.6357 -6.4008)
			(stroke
				(width 0.1524)
				(type default)
			)
			(layer "F.SilkS")
		)
		(fp_line
			(start 31.6484 -5.2959)
			(end 32.131 -5.7785)
			(stroke
				(width 0.1524)
				(type default)
			)
			(layer "F.SilkS")
		)
		(fp_line
			(start 31.8008 -23.749)
			(end 38.2524 -23.749)
			(stroke
				(width 0.1524)
				(type default)
			)
			(layer "F.SilkS")
		)
		(fp_line
			(start 31.8008 -21.3106)
			(end 31.8008 -23.749)
			(stroke
				(width 0.1524)
				(type default)
			)
			(layer "F.SilkS")
		)
		(fp_line
			(start 32.131 -5.7785)
			(end 31.1658 -5.7785)
			(stroke
				(width 0.1524)
				(type default)
			)
			(layer "F.SilkS")
		)
		(fp_line
			(start 36.2585 0.254)
			(end 36.2585 5.2578)
			(stroke
				(width 0.1524)
				(type default)
			)
			(layer "F.SilkS")
		)
		(fp_line
			(start 36.2585 5.2578)
			(end -36.2585 5.2578)
			(stroke
				(width 0.1524)
				(type default)
			)
			(layer "F.SilkS")
		)
		(fp_line
			(start 37.2491 -7.6327)
			(end 37.2491 0.254)
			(stroke
				(width 0.1524)
				(type default)
			)
			(layer "F.SilkS")
		)
		(fp_line
			(start 37.2491 0.254)
			(end 36.2585 0.254)
			(stroke
				(width 0.1524)
				(type default)
			)
			(layer "F.SilkS")
		)
		(fp_line
			(start 38.2524 -23.749)
			(end 38.2524 -14.9606)
			(stroke
				(width 0.1524)
				(type default)
			)
			(layer "F.SilkS")
		)
		(fp_line
			(start 38.2524 -14.9606)
			(end 39.9542 -14.9606)
			(stroke
				(width 0.1524)
				(type default)
			)
			(layer "F.SilkS")
		)
		(fp_line
			(start 39.9542 -14.9606)
			(end 39.9542 -7.6327)
			(stroke
				(width 0.1524)
				(type default)
			)
			(layer "F.SilkS")
		)
		(fp_line
			(start 39.9542 -7.6327)
			(end 37.2491 -7.6327)
			(stroke
				(width 0.1524)
				(type default)
			)
			(layer "F.SilkS")
		)
		(fp_poly
			(pts
				(xy 32.512 -3.001772) (xy 32.512 3.001772) (xy -32.2834 3.001772) (xy -32.2834 -3.001772)
			)
			(stroke
				(width 0)
				(type default)
			)
			(fill yes)
			(layer "F.SilkS")
		)
		(fp_poly
			(pts
				(xy -35.8013 4.8514) (xy -35.8013 0) (xy -36.9951 0) (xy -36.9951 -10.4902) (xy -38.8493 -10.4902)
				(xy -38.8493 -13.4874) (xy -36.9951 -13.4874) (xy -36.9951 -17.145) (xy -37.5031 -21.0566) (xy -32.0548 -21.0566)
				(xy -32.0548 -4.3942) (xy 32.0548 -4.3942) (xy 32.0548 -21.0566) (xy 37.5031 -21.0566) (xy 36.9951 -17.145)
				(xy 36.9951 -13.4874) (xy 38.8493 -13.4874) (xy 38.8493 -10.4902) (xy 36.9951 -10.4902) (xy 36.9951 0)
				(xy 35.8013 0) (xy 35.8013 4.8514)
			)
			(stroke
				(width 0)
				(type default)
			)
			(fill no)
			(layer "F.CrtYd")
		)
		(fp_poly
			(pts
				(xy -36.2585 5.2578) (xy -36.2585 0.254) (xy -37.2491 0.254) (xy -37.2491 -7.6327) (xy -39.9542 -7.6327)
				(xy -39.9542 -14.9606) (xy -38.2524 -14.9606) (xy -38.2524 -23.749) (xy -31.8008 -23.749) (xy -31.8008 -21.3106)
				(xy -31.3436 -21.3106) (xy -31.3436 -14.5542) (xy -30.7975 -14.5542) (xy -30.7975 -9.4488) (xy -31.3436 -9.4488)
				(xy -31.3436 -5.2578) (xy 31.3436 -5.2578) (xy 31.3436 -9.4488) (xy 30.7975 -9.4488) (xy 30.7975 -14.5542)
				(xy 31.3436 -14.5542) (xy 31.3436 -21.3106) (xy 31.8008 -21.3106) (xy 31.8008 -23.749) (xy 38.2524 -23.749)
				(xy 38.2524 -14.9606) (xy 39.9542 -14.9606) (xy 39.9542 -7.6327) (xy 37.2491 -7.6327) (xy 37.2491 -4.1656)
				(xy 36.9951 -4.1656) (xy 36.9951 -10.4902) (xy 38.8493 -10.4902) (xy 38.8493 -13.4874) (xy 36.9951 -13.4874)
				(xy 36.9951 -17.142968) (xy 37.503354 -21.0566) (xy 32.0548 -21.0566) (xy 32.0548 -4.3942) (xy -32.0548 -4.3942)
				(xy -32.0548 -21.0566) (xy -37.503354 -21.0566) (xy -36.9951 -17.142968) (xy -36.9951 -13.4874)
				(xy -38.8493 -13.4874) (xy -38.8493 -10.4902) (xy -36.9951 -10.4902) (xy -36.9951 0) (xy -35.8013 0.000254)
				(xy -35.8013 4.8514) (xy 35.8013 4.8514) (xy 35.8013 0) (xy 36.9951 0) (xy 36.9951 -4.1529) (xy 37.2491 -4.1529)
				(xy 37.2491 0.254) (xy 36.2585 0.254) (xy 36.2585 5.2578)
			)
			(stroke
				(width 0)
				(type default)
			)
			(fill no)
			(layer "F.CrtYd")
		)
		(fp_poly
			(pts
				(xy -36.2585 5.2578) (xy -36.2585 0.254) (xy -37.2491 0.254) (xy -37.2491 -7.6327) (xy -39.9542 -7.6327)
				(xy -39.9542 -14.9606) (xy -38.2524 -14.9606) (xy -38.2524 -23.749) (xy -31.8008 -23.749) (xy -31.8008 -21.3106)
				(xy -31.3436 -21.3106) (xy -31.3436 -14.5542) (xy -30.7975 -14.5542) (xy -30.7975 -9.4488) (xy -31.3436 -9.4488)
				(xy -31.3436 -5.2578) (xy 31.3436 -5.2578) (xy 31.3436 -9.4488) (xy 30.7975 -9.4488) (xy 30.7975 -14.5542)
				(xy 31.3436 -14.5542) (xy 31.3436 -21.3106) (xy 31.8008 -21.3106) (xy 31.8008 -23.749) (xy 38.2524 -23.749)
				(xy 38.2524 -14.9606) (xy 39.9542 -14.9606) (xy 39.9542 -7.6327) (xy 37.2491 -7.6327) (xy 37.2491 0.254)
				(xy 36.2585 0.254) (xy 36.2585 5.2578)
			)
			(stroke
				(width 0)
				(type default)
			)
			(fill no)
			(layer "F.Fab")
		)
		(fp_text user "1"
			(at -32.745934 4.488942 0)
			(unlocked yes)
			(layer "F.SilkS")
			(effects
				(font
					(size 0.635 0.635)
					(thickness 0.1524)
				)
				(justify left)
			)
		)
		(fp_text user "204"
			(at 28.722066 -6.560058 0)
			(unlocked yes)
			(layer "F.SilkS")
			(effects
				(font
					(size 0.635 0.635)
					(thickness 0.1524)
				)
				(justify left)
			)
		)
		(pad "" np_thru_hole circle
			(at -33.399984 0)
			(size 0.254 0.254)
			(drill 1.6002)
			(layers "*.Cu" "*.Mask")
			(clearance 1.0287)
			(thermal_gap 1.0287)
		)
		(pad "" np_thru_hole circle
			(at 33.399984 0)
			(size 0.254 0.254)
			(drill 1.1176)
			(layers "*.Cu" "*.Mask")
			(clearance 0.7874)
			(thermal_gap 0.7874)
		)
		(pad "1" smd custom
			(at -31.649924 4.106672)
			(size 0.1143 0.1143)
			(layers "F.Cu" "F.Mask" "F.Paste")
			(net "DDR3_M_B_VREF_DQ1")
			(options
				(clearance outline)
				(anchor circle)
			)
			(primitives
				(gr_poly
					(pts
						(xy 0 0.9017) (xy -0.03175 0.89916) (xy -0.0635 0.889) (xy -0.09144 0.87376) (xy -0.11684 0.85344)
						(xy -0.13716 0.82804) (xy -0.1524 0.8001) (xy -0.16256 0.76835) (xy -0.1651 0.7366) (xy -0.1651 -0.13462)
						(xy -0.17272 -0.14224) (xy -0.19812 -0.1778) (xy -0.2032 -0.18796) (xy -0.20701 -0.19685) (xy -0.21209 -0.20701)
						(xy -0.2159 -0.21717) (xy -0.21844 -0.22733) (xy -0.22225 -0.23876) (xy -0.22352 -0.24892) (xy -0.22606 -0.25908)
						(xy -0.22733 -0.27051) (xy -0.22733 -0.28067) (xy -0.2286 -0.2921) (xy -0.22733 -0.30353) (xy -0.22733 -0.31369)
						(xy -0.22606 -0.32512) (xy -0.22352 -0.33528) (xy -0.22225 -0.34544) (xy -0.21844 -0.35687) (xy -0.2159 -0.36703)
						(xy -0.21209 -0.37719) (xy -0.20701 -0.38735) (xy -0.2032 -0.39624) (xy -0.19812 -0.4064) (xy -0.17272 -0.44196)
						(xy -0.1651 -0.44958) (xy -0.1651 -0.7366) (xy -0.16256 -0.76835) (xy -0.1524 -0.8001) (xy -0.13716 -0.82804)
						(xy -0.11684 -0.85344) (xy -0.09144 -0.87376) (xy -0.0635 -0.889) (xy -0.03175 -0.89916) (xy 0 -0.9017)
						(xy 0.03175 -0.89916) (xy 0.0635 -0.889) (xy 0.09144 -0.87376) (xy 0.11684 -0.85344) (xy 0.13716 -0.82804)
						(xy 0.1524 -0.8001) (xy 0.16256 -0.76835) (xy 0.1651 -0.7366) (xy 0.1651 -0.44958) (xy 0.17272 -0.44196)
						(xy 0.19812 -0.4064) (xy 0.2032 -0.39624) (xy 0.20701 -0.38735) (xy 0.21209 -0.37719) (xy 0.2159 -0.36703)
						(xy 0.21844 -0.35687) (xy 0.22225 -0.34544) (xy 0.22352 -0.33528) (xy 0.22606 -0.32512) (xy 0.22733 -0.31369)
						(xy 0.22733 -0.30353) (xy 0.2286 -0.2921) (xy 0.22733 -0.28067) (xy 0.22733 -0.27051) (xy 0.22606 -0.25908)
						(xy 0.22352 -0.24892) (xy 0.22225 -0.23876) (xy 0.21844 -0.22733) (xy 0.2159 -0.21717) (xy 0.21209 -0.20701)
						(xy 0.20701 -0.19685) (xy 0.2032 -0.18796) (xy 0.19812 -0.1778) (xy 0.17272 -0.14224) (xy 0.1651 -0.13462)
						(xy 0.1651 0.7366) (xy 0.16256 0.76835) (xy 0.1524 0.8001) (xy 0.13716 0.82804) (xy 0.11684 0.85344)
						(xy 0.09144 0.87376) (xy 0.0635 0.889) (xy 0.03175 0.89916)
					)
					(width 0)
					(fill yes)
				)
			)
		)
		(pad "2" smd custom
			(at -31.34995 -4.106672)
			(size 0.1143 0.1143)
			(layers "F.Cu" "F.Mask" "F.Paste")
			(net "GND")
			(options
				(clearance outline)
				(anchor circle)
			)
			(primitives
				(gr_poly
					(pts
						(xy 0 0.9017) (xy -0.03175 0.89916) (xy -0.0635 0.889) (xy -0.09144 0.87376) (xy -0.11684 0.85344)
						(xy -0.13716 0.82804) (xy -0.1524 0.8001) (xy -0.16256 0.76835) (xy -0.1651 0.7366) (xy -0.1651 0.44958)
						(xy -0.17272 0.44196) (xy -0.19812 0.4064) (xy -0.2032 0.39624) (xy -0.20701 0.38735) (xy -0.21209 0.37719)
						(xy -0.2159 0.36703) (xy -0.21844 0.35687) (xy -0.22225 0.34544) (xy -0.22352 0.33528) (xy -0.22606 0.32512)
						(xy -0.22733 0.31369) (xy -0.22733 0.30353) (xy -0.2286 0.2921) (xy -0.22733 0.28067) (xy -0.22733 0.27051)
						(xy -0.22606 0.25908) (xy -0.22352 0.24892) (xy -0.22225 0.23876) (xy -0.21844 0.22733) (xy -0.2159 0.21717)
						(xy -0.21209 0.20701) (xy -0.20701 0.19685) (xy -0.2032 0.18796) (xy -0.19812 0.1778) (xy -0.17272 0.14224)
						(xy -0.1651 0.13462) (xy -0.1651 -0.7366) (xy -0.16256 -0.76835) (xy -0.1524 -0.8001) (xy -0.13716 -0.82804)
						(xy -0.11684 -0.85344) (xy -0.09144 -0.87376) (xy -0.0635 -0.889) (xy -0.03175 -0.89916) (xy 0 -0.9017)
						(xy 0.03175 -0.89916) (xy 0.0635 -0.889) (xy 0.09144 -0.87376) (xy 0.11684 -0.85344) (xy 0.13716 -0.82804)
						(xy 0.1524 -0.8001) (xy 0.16256 -0.76835) (xy 0.1651 -0.7366) (xy 0.1651 0.13462) (xy 0.17272 0.14224)
						(xy 0.19812 0.1778) (xy 0.2032 0.18796) (xy 0.20701 0.19685) (xy 0.21209 0.20701) (xy 0.2159 0.21717)
						(xy 0.21844 0.22733) (xy 0.22225 0.23876) (xy 0.22352 0.24892) (xy 0.22606 0.25908) (xy 0.22733 0.27051)
						(xy 0.22733 0.28067) (xy 0.2286 0.2921) (xy 0.22733 0.30353) (xy 0.22733 0.31369) (xy 0.22606 0.32512)
						(xy 0.22352 0.33528) (xy 0.22225 0.34544) (xy 0.21844 0.35687) (xy 0.2159 0.36703) (xy 0.21209 0.37719)
						(xy 0.20701 0.38735) (xy 0.2032 0.39624) (xy 0.19812 0.4064) (xy 0.17272 0.44196) (xy 0.1651 0.44958)
						(xy 0.1651 0.7366) (xy 0.16256 0.76835) (xy 0.1524 0.8001) (xy 0.13716 0.82804) (xy 0.11684 0.85344)
						(xy 0.09144 0.87376) (xy 0.0635 0.889) (xy 0.03175 0.89916)
					)
					(width 0)
					(fill yes)
				)
			)
		)
		(pad "3" smd custom
			(at -31.049976 4.106672)
			(size 0.1143 0.1143)
			(layers "F.Cu" "F.Mask" "F.Paste")
			(net "GND")
			(options
				(clearance outline)
				(anchor circle)
			)
			(primitives
				(gr_poly
					(pts
						(xy 0 0.9017) (xy -0.03175 0.89916) (xy -0.0635 0.889) (xy -0.09144 0.87376) (xy -0.11684 0.85344)
						(xy -0.13716 0.82804) (xy -0.1524 0.8001) (xy -0.16256 0.76835) (xy -0.1651 0.7366) (xy -0.1651 0.11938)
						(xy -0.17272 0.11176) (xy -0.19812 0.0762) (xy -0.2032 0.06604) (xy -0.20701 0.05715) (xy -0.21209 0.04699)
						(xy -0.2159 0.03683) (xy -0.21844 0.02667) (xy -0.22225 0.01524) (xy -0.22352 0.00508) (xy -0.22606 -0.00508)
						(xy -0.22733 -0.01651) (xy -0.22733 -0.02667) (xy -0.2286 -0.0381) (xy -0.22733 -0.04953) (xy -0.22733 -0.05969)
						(xy -0.22606 -0.07112) (xy -0.22352 -0.08128) (xy -0.22225 -0.09144) (xy -0.21844 -0.10287) (xy -0.2159 -0.11303)
						(xy -0.21209 -0.12319) (xy -0.20701 -0.13335) (xy -0.2032 -0.14224) (xy -0.19812 -0.1524) (xy -0.17272 -0.18796)
						(xy -0.1651 -0.19558) (xy -0.1651 -0.7366) (xy -0.16256 -0.76835) (xy -0.1524 -0.8001) (xy -0.13716 -0.82804)
						(xy -0.11684 -0.85344) (xy -0.09144 -0.87376) (xy -0.0635 -0.889) (xy -0.03175 -0.89916) (xy 0 -0.9017)
						(xy 0.03175 -0.89916) (xy 0.0635 -0.889) (xy 0.09144 -0.87376) (xy 0.11684 -0.85344) (xy 0.13716 -0.82804)
						(xy 0.1524 -0.8001) (xy 0.16256 -0.76835) (xy 0.1651 -0.7366) (xy 0.1651 -0.19685) (xy 0.17272 -0.18923)
						(xy 0.17907 -0.18034) (xy 0.18669 -0.17145) (xy 0.19177 -0.16256) (xy 0.19812 -0.15367) (xy 0.20828 -0.13335)
						(xy 0.21971 -0.10287) (xy 0.22225 -0.09271) (xy 0.22479 -0.08128) (xy 0.22606 -0.07112) (xy 0.2286 -0.05969)
						(xy 0.2286 -0.01651) (xy 0.22606 -0.00508) (xy 0.22479 0.00508) (xy 0.22225 0.01651) (xy 0.21971 0.02667)
						(xy 0.20828 0.05715) (xy 0.19812 0.07747) (xy 0.19177 0.08636) (xy 0.18669 0.09525) (xy 0.17907 0.10414)
						(xy 0.17272 0.11303) (xy 0.1651 0.12065) (xy 0.1651 0.7366) (xy 0.16256 0.76835) (xy 0.1524 0.8001)
						(xy 0.13716 0.82804) (xy 0.11684 0.85344) (xy 0.09144 0.87376) (xy 0.0635 0.889) (xy 0.03175 0.89916)
					)
					(width 0)
					(fill yes)
				)
			)
		)
		(pad "4" smd custom
			(at -30.750002 -4.106672)
			(size 0.1143 0.1143)
			(layers "F.Cu" "F.Mask" "F.Paste")
			(net "M_B_DQ0")
			(options
				(clearance outline)
				(anchor circle)
			)
			(primitives
				(gr_poly
					(pts
						(xy 0 0.9017) (xy -0.03175 0.89916) (xy -0.0635 0.889) (xy -0.09144 0.87376) (xy -0.11684 0.85344)
						(xy -0.13716 0.82804) (xy -0.1524 0.8001) (xy -0.16256 0.76835) (xy -0.1651 0.7366) (xy -0.1651 0.19685)
						(xy -0.17272 0.18923) (xy -0.17907 0.18034) (xy -0.18669 0.17145) (xy -0.19177 0.16256) (xy -0.19812 0.15367)
						(xy -0.20828 0.13335) (xy -0.21971 0.10287) (xy -0.22225 0.09271) (xy -0.22479 0.08128) (xy -0.22606 0.07112)
						(xy -0.2286 0.05969) (xy -0.2286 0.01651) (xy -0.22606 0.00508) (xy -0.22479 -0.00508) (xy -0.22225 -0.01651)
						(xy -0.21971 -0.02667) (xy -0.20828 -0.05715) (xy -0.19812 -0.07747) (xy -0.19177 -0.08636) (xy -0.18669 -0.09525)
						(xy -0.17907 -0.10414) (xy -0.17272 -0.11303) (xy -0.1651 -0.12065) (xy -0.1651 -0.7366) (xy -0.16256 -0.76835)
						(xy -0.1524 -0.8001) (xy -0.13716 -0.82804) (xy -0.11684 -0.85344) (xy -0.09144 -0.87376) (xy -0.0635 -0.889)
						(xy -0.03175 -0.89916) (xy 0 -0.9017) (xy 0.03175 -0.89916) (xy 0.0635 -0.889) (xy 0.09144 -0.87376)
						(xy 0.11684 -0.85344) (xy 0.13716 -0.82804) (xy 0.1524 -0.8001) (xy 0.16256 -0.76835) (xy 0.1651 -0.7366)
						(xy 0.1651 -0.11938) (xy 0.17272 -0.11176) (xy 0.19812 -0.0762) (xy 0.2032 -0.06604) (xy 0.20701 -0.05715)
						(xy 0.21209 -0.04699) (xy 0.2159 -0.03683) (xy 0.21844 -0.02667) (xy 0.22225 -0.01524) (xy 0.22352 -0.00508)
						(xy 0.22606 0.00508) (xy 0.22733 0.01651) (xy 0.22733 0.02667) (xy 0.2286 0.0381) (xy 0.22733 0.04953)
						(xy 0.22733 0.05969) (xy 0.22606 0.07112) (xy 0.22352 0.08128) (xy 0.22225 0.09144) (xy 0.21844 0.10287)
						(xy 0.2159 0.11303) (xy 0.21209 0.12319) (xy 0.20701 0.13335) (xy 0.2032 0.14224) (xy 0.19812 0.1524)
						(xy 0.17272 0.18796) (xy 0.1651 0.19558) (xy 0.1651 0.7366) (xy 0.16256 0.76835) (xy 0.1524 0.8001)
						(xy 0.13716 0.82804) (xy 0.11684 0.85344) (xy 0.09144 0.87376) (xy 0.0635 0.889) (xy 0.03175 0.89916)
					)
					(width 0)
					(fill yes)
				)
			)
		)
		(pad "5" smd custom
			(at -30.450028 4.106672)
			(size 0.1143 0.1143)
			(layers "F.Cu" "F.Mask" "F.Paste")
			(net "M_B_DQ4")
			(options
				(clearance outline)
				(anchor circle)
			)
			(primitives
				(gr_poly
					(pts
						(xy 0 0.9017) (xy -0.03175 0.89916) (xy -0.0635 0.889) (xy -0.09144 0.87376) (xy -0.11684 0.85344)
						(xy -0.13716 0.82804) (xy -0.1524 0.8001) (xy -0.16256 0.76835) (xy -0.1651 0.7366) (xy -0.1651 -0.13462)
						(xy -0.17272 -0.14224) (xy -0.19812 -0.1778) (xy -0.2032 -0.18796) (xy -0.20701 -0.19685) (xy -0.21209 -0.20701)
						(xy -0.2159 -0.21717) (xy -0.21844 -0.22733) (xy -0.22225 -0.23876) (xy -0.22352 -0.24892) (xy -0.22606 -0.25908)
						(xy -0.22733 -0.27051) (xy -0.22733 -0.28067) (xy -0.2286 -0.2921) (xy -0.22733 -0.30353) (xy -0.22733 -0.31369)
						(xy -0.22606 -0.32512) (xy -0.22352 -0.33528) (xy -0.22225 -0.34544) (xy -0.21844 -0.35687) (xy -0.2159 -0.36703)
						(xy -0.21209 -0.37719) (xy -0.20701 -0.38735) (xy -0.2032 -0.39624) (xy -0.19812 -0.4064) (xy -0.17272 -0.44196)
						(xy -0.1651 -0.44958) (xy -0.1651 -0.7366) (xy -0.16256 -0.76835) (xy -0.1524 -0.8001) (xy -0.13716 -0.82804)
						(xy -0.11684 -0.85344) (xy -0.09144 -0.87376) (xy -0.0635 -0.889) (xy -0.03175 -0.89916) (xy 0 -0.9017)
						(xy 0.03175 -0.89916) (xy 0.0635 -0.889) (xy 0.09144 -0.87376) (xy 0.11684 -0.85344) (xy 0.13716 -0.82804)
						(xy 0.1524 -0.8001) (xy 0.16256 -0.76835) (xy 0.1651 -0.7366) (xy 0.1651 -0.44958) (xy 0.17272 -0.44196)
						(xy 0.19812 -0.4064) (xy 0.2032 -0.39624) (xy 0.20701 -0.38735) (xy 0.21209 -0.37719) (xy 0.2159 -0.36703)
						(xy 0.21844 -0.35687) (xy 0.22225 -0.34544) (xy 0.22352 -0.33528) (xy 0.22606 -0.32512) (xy 0.22733 -0.31369)
						(xy 0.22733 -0.30353) (xy 0.2286 -0.2921) (xy 0.22733 -0.28067) (xy 0.22733 -0.27051) (xy 0.22606 -0.25908)
						(xy 0.22352 -0.24892) (xy 0.22225 -0.23876) (xy 0.21844 -0.22733) (xy 0.2159 -0.21717) (xy 0.21209 -0.20701)
						(xy 0.20701 -0.19685) (xy 0.2032 -0.18796) (xy 0.19812 -0.1778) (xy 0.17272 -0.14224) (xy 0.1651 -0.13462)
						(xy 0.1651 0.7366) (xy 0.16256 0.76835) (xy 0.1524 0.8001) (xy 0.13716 0.82804) (xy 0.11684 0.85344)
						(xy 0.09144 0.87376) (xy 0.0635 0.889) (xy 0.03175 0.89916)
					)
					(width 0)
					(fill yes)
				)
			)
		)
		(pad "6" smd custom
			(at -30.150054 -4.106672)
			(size 0.1143 0.1143)
			(layers "F.Cu" "F.Mask" "F.Paste")
			(net "M_B_DQ1")
			(options
				(clearance outline)
				(anchor circle)
			)
			(primitives
				(gr_poly
					(pts
						(xy 0 0.9017) (xy -0.03175 0.89916) (xy -0.0635 0.889) (xy -0.09144 0.87376) (xy -0.11684 0.85344)
						(xy -0.13716 0.82804) (xy -0.1524 0.8001) (xy -0.16256 0.76835) (xy -0.1651 0.7366) (xy -0.1651 0.44958)
						(xy -0.17272 0.44196) (xy -0.19812 0.4064) (xy -0.2032 0.39624) (xy -0.20701 0.38735) (xy -0.21209 0.37719)
						(xy -0.2159 0.36703) (xy -0.21844 0.35687) (xy -0.22225 0.34544) (xy -0.22352 0.33528) (xy -0.22606 0.32512)
						(xy -0.22733 0.31369) (xy -0.22733 0.30353) (xy -0.2286 0.2921) (xy -0.22733 0.28067) (xy -0.22733 0.27051)
						(xy -0.22606 0.25908) (xy -0.22352 0.24892) (xy -0.22225 0.23876) (xy -0.21844 0.22733) (xy -0.2159 0.21717)
						(xy -0.21209 0.20701) (xy -0.20701 0.19685) (xy -0.2032 0.18796) (xy -0.19812 0.1778) (xy -0.17272 0.14224)
						(xy -0.1651 0.13462) (xy -0.1651 -0.7366) (xy -0.16256 -0.76835) (xy -0.1524 -0.8001) (xy -0.13716 -0.82804)
						(xy -0.11684 -0.85344) (xy -0.09144 -0.87376) (xy -0.0635 -0.889) (xy -0.03175 -0.89916) (xy 0 -0.9017)
						(xy 0.03175 -0.89916) (xy 0.0635 -0.889) (xy 0.09144 -0.87376) (xy 0.11684 -0.85344) (xy 0.13716 -0.82804)
						(xy 0.1524 -0.8001) (xy 0.16256 -0.76835) (xy 0.1651 -0.7366) (xy 0.1651 0.13462) (xy 0.17272 0.14224)
						(xy 0.19812 0.1778) (xy 0.2032 0.18796) (xy 0.20701 0.19685) (xy 0.21209 0.20701) (xy 0.2159 0.21717)
						(xy 0.21844 0.22733) (xy 0.22225 0.23876) (xy 0.22352 0.24892) (xy 0.22606 0.25908) (xy 0.22733 0.27051)
						(xy 0.22733 0.28067) (xy 0.2286 0.2921) (xy 0.22733 0.30353) (xy 0.22733 0.31369) (xy 0.22606 0.32512)
						(xy 0.22352 0.33528) (xy 0.22225 0.34544) (xy 0.21844 0.35687) (xy 0.2159 0.36703) (xy 0.21209 0.37719)
						(xy 0.20701 0.38735) (xy 0.2032 0.39624) (xy 0.19812 0.4064) (xy 0.17272 0.44196) (xy 0.1651 0.44958)
						(xy 0.1651 0.7366) (xy 0.16256 0.76835) (xy 0.1524 0.8001) (xy 0.13716 0.82804) (xy 0.11684 0.85344)
						(xy 0.09144 0.87376) (xy 0.0635 0.889) (xy 0.03175 0.89916)
					)
					(width 0)
					(fill yes)
				)
			)
		)
		(pad "7" smd custom
			(at -29.85008 4.106672)
			(size 0.1143 0.1143)
			(layers "F.Cu" "F.Mask" "F.Paste")
			(net "M_B_DQ5")
			(options
				(clearance outline)
				(anchor circle)
			)
			(primitives
				(gr_poly
					(pts
						(xy 0 0.9017) (xy -0.03175 0.89916) (xy -0.0635 0.889) (xy -0.09144 0.87376) (xy -0.11684 0.85344)
						(xy -0.13716 0.82804) (xy -0.1524 0.8001) (xy -0.16256 0.76835) (xy -0.1651 0.7366) (xy -0.1651 0.11938)
						(xy -0.17272 0.11176) (xy -0.19812 0.0762) (xy -0.2032 0.06604) (xy -0.20701 0.05715) (xy -0.21209 0.04699)
						(xy -0.2159 0.03683) (xy -0.21844 0.02667) (xy -0.22225 0.01524) (xy -0.22352 0.00508) (xy -0.22606 -0.00508)
						(xy -0.22733 -0.01651) (xy -0.22733 -0.02667) (xy -0.2286 -0.0381) (xy -0.22733 -0.04953) (xy -0.22733 -0.05969)
						(xy -0.22606 -0.07112) (xy -0.22352 -0.08128) (xy -0.22225 -0.09144) (xy -0.21844 -0.10287) (xy -0.2159 -0.11303)
						(xy -0.21209 -0.12319) (xy -0.20701 -0.13335) (xy -0.2032 -0.14224) (xy -0.19812 -0.1524) (xy -0.17272 -0.18796)
						(xy -0.1651 -0.19558) (xy -0.1651 -0.7366) (xy -0.16256 -0.76835) (xy -0.1524 -0.8001) (xy -0.13716 -0.82804)
						(xy -0.11684 -0.85344) (xy -0.09144 -0.87376) (xy -0.0635 -0.889) (xy -0.03175 -0.89916) (xy 0 -0.9017)
						(xy 0.03175 -0.89916) (xy 0.0635 -0.889) (xy 0.09144 -0.87376) (xy 0.11684 -0.85344) (xy 0.13716 -0.82804)
						(xy 0.1524 -0.8001) (xy 0.16256 -0.76835) (xy 0.1651 -0.7366) (xy 0.1651 -0.19685) (xy 0.17272 -0.18923)
						(xy 0.17907 -0.18034) (xy 0.18669 -0.17145) (xy 0.19177 -0.16256) (xy 0.19812 -0.15367) (xy 0.20828 -0.13335)
						(xy 0.21971 -0.10287) (xy 0.22225 -0.09271) (xy 0.22479 -0.08128) (xy 0.22606 -0.07112) (xy 0.2286 -0.05969)
						(xy 0.2286 -0.01651) (xy 0.22606 -0.00508) (xy 0.22479 0.00508) (xy 0.22225 0.01651) (xy 0.21971 0.02667)
						(xy 0.20828 0.05715) (xy 0.19812 0.07747) (xy 0.19177 0.08636) (xy 0.18669 0.09525) (xy 0.17907 0.10414)
						(xy 0.17272 0.11303) (xy 0.1651 0.12065) (xy 0.1651 0.7366) (xy 0.16256 0.76835) (xy 0.1524 0.8001)
						(xy 0.13716 0.82804) (xy 0.11684 0.85344) (xy 0.09144 0.87376) (xy 0.0635 0.889) (xy 0.03175 0.89916)
					)
					(width 0)
					(fill yes)
				)
			)
		)
		(pad "8" smd custom
			(at -29.550106 -4.106672)
			(size 0.1143 0.1143)
			(layers "F.Cu" "F.Mask" "F.Paste")
			(net "GND")
			(options
				(clearance outline)
				(anchor circle)
			)
			(primitives
				(gr_poly
					(pts
						(xy 0 0.9017) (xy -0.03175 0.89916) (xy -0.0635 0.889) (xy -0.09144 0.87376) (xy -0.11684 0.85344)
						(xy -0.13716 0.82804) (xy -0.1524 0.8001) (xy -0.16256 0.76835) (xy -0.1651 0.7366) (xy -0.1651 0.19685)
						(xy -0.17272 0.18923) (xy -0.17907 0.18034) (xy -0.18669 0.17145) (xy -0.19177 0.16256) (xy -0.19812 0.15367)
						(xy -0.20828 0.13335) (xy -0.21971 0.10287) (xy -0.22225 0.09271) (xy -0.22479 0.08128) (xy -0.22606 0.07112)
						(xy -0.2286 0.05969) (xy -0.2286 0.01651) (xy -0.22606 0.00508) (xy -0.22479 -0.00508) (xy -0.22225 -0.01651)
						(xy -0.21971 -0.02667) (xy -0.20828 -0.05715) (xy -0.19812 -0.07747) (xy -0.19177 -0.08636) (xy -0.18669 -0.09525)
						(xy -0.17907 -0.10414) (xy -0.17272 -0.11303) (xy -0.1651 -0.12065) (xy -0.1651 -0.7366) (xy -0.16256 -0.76835)
						(xy -0.1524 -0.8001) (xy -0.13716 -0.82804) (xy -0.11684 -0.85344) (xy -0.09144 -0.87376) (xy -0.0635 -0.889)
						(xy -0.03175 -0.89916) (xy 0 -0.9017) (xy 0.03175 -0.89916) (xy 0.0635 -0.889) (xy 0.09144 -0.87376)
						(xy 0.11684 -0.85344) (xy 0.13716 -0.82804) (xy 0.1524 -0.8001) (xy 0.16256 -0.76835) (xy 0.1651 -0.7366)
						(xy 0.1651 -0.11938) (xy 0.17272 -0.11176) (xy 0.19812 -0.0762) (xy 0.2032 -0.06604) (xy 0.20701 -0.05715)
						(xy 0.21209 -0.04699) (xy 0.2159 -0.03683) (xy 0.21844 -0.02667) (xy 0.22225 -0.01524) (xy 0.22352 -0.00508)
						(xy 0.22606 0.00508) (xy 0.22733 0.01651) (xy 0.22733 0.02667) (xy 0.2286 0.0381) (xy 0.22733 0.04953)
						(xy 0.22733 0.05969) (xy 0.22606 0.07112) (xy 0.22352 0.08128) (xy 0.22225 0.09144) (xy 0.21844 0.10287)
						(xy 0.2159 0.11303) (xy 0.21209 0.12319) (xy 0.20701 0.13335) (xy 0.2032 0.14224) (xy 0.19812 0.1524)
						(xy 0.17272 0.18796) (xy 0.1651 0.19558) (xy 0.1651 0.7366) (xy 0.16256 0.76835) (xy 0.1524 0.8001)
						(xy 0.13716 0.82804) (xy 0.11684 0.85344) (xy 0.09144 0.87376) (xy 0.0635 0.889) (xy 0.03175 0.89916)
					)
					(width 0)
					(fill yes)
				)
			)
		)
		(pad "9" smd custom
			(at -29.249878 4.106672)
			(size 0.1143 0.1143)
			(layers "F.Cu" "F.Mask" "F.Paste")
			(net "GND")
			(options
				(clearance outline)
				(anchor circle)
			)
			(primitives
				(gr_poly
					(pts
						(xy 0 0.9017) (xy -0.03175 0.89916) (xy -0.0635 0.889) (xy -0.09144 0.87376) (xy -0.11684 0.85344)
						(xy -0.13716 0.82804) (xy -0.1524 0.8001) (xy -0.16256 0.76835) (xy -0.1651 0.7366) (xy -0.1651 -0.13462)
						(xy -0.17272 -0.14224) (xy -0.19812 -0.1778) (xy -0.2032 -0.18796) (xy -0.20701 -0.19685) (xy -0.21209 -0.20701)
						(xy -0.2159 -0.21717) (xy -0.21844 -0.22733) (xy -0.22225 -0.23876) (xy -0.22352 -0.24892) (xy -0.22606 -0.25908)
						(xy -0.22733 -0.27051) (xy -0.22733 -0.28067) (xy -0.2286 -0.2921) (xy -0.22733 -0.30353) (xy -0.22733 -0.31369)
						(xy -0.22606 -0.32512) (xy -0.22352 -0.33528) (xy -0.22225 -0.34544) (xy -0.21844 -0.35687) (xy -0.2159 -0.36703)
						(xy -0.21209 -0.37719) (xy -0.20701 -0.38735) (xy -0.2032 -0.39624) (xy -0.19812 -0.4064) (xy -0.17272 -0.44196)
						(xy -0.1651 -0.44958) (xy -0.1651 -0.7366) (xy -0.16256 -0.76835) (xy -0.1524 -0.8001) (xy -0.13716 -0.82804)
						(xy -0.11684 -0.85344) (xy -0.09144 -0.87376) (xy -0.0635 -0.889) (xy -0.03175 -0.89916) (xy 0 -0.9017)
						(xy 0.03175 -0.89916) (xy 0.0635 -0.889) (xy 0.09144 -0.87376) (xy 0.11684 -0.85344) (xy 0.13716 -0.82804)
						(xy 0.1524 -0.8001) (xy 0.16256 -0.76835) (xy 0.1651 -0.7366) (xy 0.1651 -0.44958) (xy 0.17272 -0.44196)
						(xy 0.19812 -0.4064) (xy 0.2032 -0.39624) (xy 0.20701 -0.38735) (xy 0.21209 -0.37719) (xy 0.2159 -0.36703)
						(xy 0.21844 -0.35687) (xy 0.22225 -0.34544) (xy 0.22352 -0.33528) (xy 0.22606 -0.32512) (xy 0.22733 -0.31369)
						(xy 0.22733 -0.30353) (xy 0.2286 -0.2921) (xy 0.22733 -0.28067) (xy 0.22733 -0.27051) (xy 0.22606 -0.25908)
						(xy 0.22352 -0.24892) (xy 0.22225 -0.23876) (xy 0.21844 -0.22733) (xy 0.2159 -0.21717) (xy 0.21209 -0.20701)
						(xy 0.20701 -0.19685) (xy 0.2032 -0.18796) (xy 0.19812 -0.1778) (xy 0.17272 -0.14224) (xy 0.1651 -0.13462)
						(xy 0.1651 0.7366) (xy 0.16256 0.76835) (xy 0.1524 0.8001) (xy 0.13716 0.82804) (xy 0.11684 0.85344)
						(xy 0.09144 0.87376) (xy 0.0635 0.889) (xy 0.03175 0.89916)
					)
					(width 0)
					(fill yes)
				)
			)
		)
		(pad "10" smd custom
			(at -28.949904 -4.106672)
			(size 0.1143 0.1143)
			(layers "F.Cu" "F.Mask" "F.Paste")
			(net "M_B_DQS_DN0")
			(options
				(clearance outline)
				(anchor circle)
			)
			(primitives
				(gr_poly
					(pts
						(xy 0 0.9017) (xy -0.03175 0.89916) (xy -0.0635 0.889) (xy -0.09144 0.87376) (xy -0.11684 0.85344)
						(xy -0.13716 0.82804) (xy -0.1524 0.8001) (xy -0.16256 0.76835) (xy -0.1651 0.7366) (xy -0.1651 0.44958)
						(xy -0.17272 0.44196) (xy -0.19812 0.4064) (xy -0.2032 0.39624) (xy -0.20701 0.38735) (xy -0.21209 0.37719)
						(xy -0.2159 0.36703) (xy -0.21844 0.35687) (xy -0.22225 0.34544) (xy -0.22352 0.33528) (xy -0.22606 0.32512)
						(xy -0.22733 0.31369) (xy -0.22733 0.30353) (xy -0.2286 0.2921) (xy -0.22733 0.28067) (xy -0.22733 0.27051)
						(xy -0.22606 0.25908) (xy -0.22352 0.24892) (xy -0.22225 0.23876) (xy -0.21844 0.22733) (xy -0.2159 0.21717)
						(xy -0.21209 0.20701) (xy -0.20701 0.19685) (xy -0.2032 0.18796) (xy -0.19812 0.1778) (xy -0.17272 0.14224)
						(xy -0.1651 0.13462) (xy -0.1651 -0.7366) (xy -0.16256 -0.76835) (xy -0.1524 -0.8001) (xy -0.13716 -0.82804)
						(xy -0.11684 -0.85344) (xy -0.09144 -0.87376) (xy -0.0635 -0.889) (xy -0.03175 -0.89916) (xy 0 -0.9017)
						(xy 0.03175 -0.89916) (xy 0.0635 -0.889) (xy 0.09144 -0.87376) (xy 0.11684 -0.85344) (xy 0.13716 -0.82804)
						(xy 0.1524 -0.8001) (xy 0.16256 -0.76835) (xy 0.1651 -0.7366) (xy 0.1651 0.13462) (xy 0.17272 0.14224)
						(xy 0.19812 0.1778) (xy 0.2032 0.18796) (xy 0.20701 0.19685) (xy 0.21209 0.20701) (xy 0.2159 0.21717)
						(xy 0.21844 0.22733) (xy 0.22225 0.23876) (xy 0.22352 0.24892) (xy 0.22606 0.25908) (xy 0.22733 0.27051)
						(xy 0.22733 0.28067) (xy 0.2286 0.2921) (xy 0.22733 0.30353) (xy 0.22733 0.31369) (xy 0.22606 0.32512)
						(xy 0.22352 0.33528) (xy 0.22225 0.34544) (xy 0.21844 0.35687) (xy 0.2159 0.36703) (xy 0.21209 0.37719)
						(xy 0.20701 0.38735) (xy 0.2032 0.39624) (xy 0.19812 0.4064) (xy 0.17272 0.44196) (xy 0.1651 0.44958)
						(xy 0.1651 0.7366) (xy 0.16256 0.76835) (xy 0.1524 0.8001) (xy 0.13716 0.82804) (xy 0.11684 0.85344)
						(xy 0.09144 0.87376) (xy 0.0635 0.889) (xy 0.03175 0.89916)
					)
					(width 0)
					(fill yes)
				)
			)
		)
		(pad "11" smd custom
			(at -28.64993 4.106672)
			(size 0.1143 0.1143)
			(layers "F.Cu" "F.Mask" "F.Paste")
			(net "GND")
			(options
				(clearance outline)
				(anchor circle)
			)
			(primitives
				(gr_poly
					(pts
						(xy 0 0.9017) (xy -0.03175 0.89916) (xy -0.0635 0.889) (xy -0.09144 0.87376) (xy -0.11684 0.85344)
						(xy -0.13716 0.82804) (xy -0.1524 0.8001) (xy -0.16256 0.76835) (xy -0.1651 0.7366) (xy -0.1651 0.11938)
						(xy -0.17272 0.11176) (xy -0.19812 0.0762) (xy -0.2032 0.06604) (xy -0.20701 0.05715) (xy -0.21209 0.04699)
						(xy -0.2159 0.03683) (xy -0.21844 0.02667) (xy -0.22225 0.01524) (xy -0.22352 0.00508) (xy -0.22606 -0.00508)
						(xy -0.22733 -0.01651) (xy -0.22733 -0.02667) (xy -0.2286 -0.0381) (xy -0.22733 -0.04953) (xy -0.22733 -0.05969)
						(xy -0.22606 -0.07112) (xy -0.22352 -0.08128) (xy -0.22225 -0.09144) (xy -0.21844 -0.10287) (xy -0.2159 -0.11303)
						(xy -0.21209 -0.12319) (xy -0.20701 -0.13335) (xy -0.2032 -0.14224) (xy -0.19812 -0.1524) (xy -0.17272 -0.18796)
						(xy -0.1651 -0.19558) (xy -0.1651 -0.7366) (xy -0.16256 -0.76835) (xy -0.1524 -0.8001) (xy -0.13716 -0.82804)
						(xy -0.11684 -0.85344) (xy -0.09144 -0.87376) (xy -0.0635 -0.889) (xy -0.03175 -0.89916) (xy 0 -0.9017)
						(xy 0.03175 -0.89916) (xy 0.0635 -0.889) (xy 0.09144 -0.87376) (xy 0.11684 -0.85344) (xy 0.13716 -0.82804)
						(xy 0.1524 -0.8001) (xy 0.16256 -0.76835) (xy 0.1651 -0.7366) (xy 0.1651 -0.19685) (xy 0.17272 -0.18923)
						(xy 0.17907 -0.18034) (xy 0.18669 -0.17145) (xy 0.19177 -0.16256) (xy 0.19812 -0.15367) (xy 0.20828 -0.13335)
						(xy 0.21971 -0.10287) (xy 0.22225 -0.09271) (xy 0.22479 -0.08128) (xy 0.22606 -0.07112) (xy 0.2286 -0.05969)
						(xy 0.2286 -0.01651) (xy 0.22606 -0.00508) (xy 0.22479 0.00508) (xy 0.22225 0.01651) (xy 0.21971 0.02667)
						(xy 0.20828 0.05715) (xy 0.19812 0.07747) (xy 0.19177 0.08636) (xy 0.18669 0.09525) (xy 0.17907 0.10414)
						(xy 0.17272 0.11303) (xy 0.1651 0.12065) (xy 0.1651 0.7366) (xy 0.16256 0.76835) (xy 0.1524 0.8001)
						(xy 0.13716 0.82804) (xy 0.11684 0.85344) (xy 0.09144 0.87376) (xy 0.0635 0.889) (xy 0.03175 0.89916)
					)
					(width 0)
					(fill yes)
				)
			)
		)
		(pad "12" smd custom
			(at -28.349956 -4.106672)
			(size 0.1143 0.1143)
			(layers "F.Cu" "F.Mask" "F.Paste")
			(net "M_B_DQS_DP0")
			(options
				(clearance outline)
				(anchor circle)
			)
			(primitives
				(gr_poly
					(pts
						(xy 0 0.9017) (xy -0.03175 0.89916) (xy -0.0635 0.889) (xy -0.09144 0.87376) (xy -0.11684 0.85344)
						(xy -0.13716 0.82804) (xy -0.1524 0.8001) (xy -0.16256 0.76835) (xy -0.1651 0.7366) (xy -0.1651 0.19685)
						(xy -0.17272 0.18923) (xy -0.17907 0.18034) (xy -0.18669 0.17145) (xy -0.19177 0.16256) (xy -0.19812 0.15367)
						(xy -0.20828 0.13335) (xy -0.21971 0.10287) (xy -0.22225 0.09271) (xy -0.22479 0.08128) (xy -0.22606 0.07112)
						(xy -0.2286 0.05969) (xy -0.2286 0.01651) (xy -0.22606 0.00508) (xy -0.22479 -0.00508) (xy -0.22225 -0.01651)
						(xy -0.21971 -0.02667) (xy -0.20828 -0.05715) (xy -0.19812 -0.07747) (xy -0.19177 -0.08636) (xy -0.18669 -0.09525)
						(xy -0.17907 -0.10414) (xy -0.17272 -0.11303) (xy -0.1651 -0.12065) (xy -0.1651 -0.7366) (xy -0.16256 -0.76835)
						(xy -0.1524 -0.8001) (xy -0.13716 -0.82804) (xy -0.11684 -0.85344) (xy -0.09144 -0.87376) (xy -0.0635 -0.889)
						(xy -0.03175 -0.89916) (xy 0 -0.9017) (xy 0.03175 -0.89916) (xy 0.0635 -0.889) (xy 0.09144 -0.87376)
						(xy 0.11684 -0.85344) (xy 0.13716 -0.82804) (xy 0.1524 -0.8001) (xy 0.16256 -0.76835) (xy 0.1651 -0.7366)
						(xy 0.1651 -0.11938) (xy 0.17272 -0.11176) (xy 0.19812 -0.0762) (xy 0.2032 -0.06604) (xy 0.20701 -0.05715)
						(xy 0.21209 -0.04699) (xy 0.2159 -0.03683) (xy 0.21844 -0.02667) (xy 0.22225 -0.01524) (xy 0.22352 -0.00508)
						(xy 0.22606 0.00508) (xy 0.22733 0.01651) (xy 0.22733 0.02667) (xy 0.2286 0.0381) (xy 0.22733 0.04953)
						(xy 0.22733 0.05969) (xy 0.22606 0.07112) (xy 0.22352 0.08128) (xy 0.22225 0.09144) (xy 0.21844 0.10287)
						(xy 0.2159 0.11303) (xy 0.21209 0.12319) (xy 0.20701 0.13335) (xy 0.2032 0.14224) (xy 0.19812 0.1524)
						(xy 0.17272 0.18796) (xy 0.1651 0.19558) (xy 0.1651 0.7366) (xy 0.16256 0.76835) (xy 0.1524 0.8001)
						(xy 0.13716 0.82804) (xy 0.11684 0.85344) (xy 0.09144 0.87376) (xy 0.0635 0.889) (xy 0.03175 0.89916)
					)
					(width 0)
					(fill yes)
				)
			)
		)
		(pad "13" smd custom
			(at -28.049982 4.106672)
			(size 0.1143 0.1143)
			(layers "F.Cu" "F.Mask" "F.Paste")
			(net "M_B_DQ6")
			(options
				(clearance outline)
				(anchor circle)
			)
			(primitives
				(gr_poly
					(pts
						(xy 0 0.9017) (xy -0.03175 0.89916) (xy -0.0635 0.889) (xy -0.09144 0.87376) (xy -0.11684 0.85344)
						(xy -0.13716 0.82804) (xy -0.1524 0.8001) (xy -0.16256 0.76835) (xy -0.1651 0.7366) (xy -0.1651 -0.13462)
						(xy -0.17272 -0.14224) (xy -0.19812 -0.1778) (xy -0.2032 -0.18796) (xy -0.20701 -0.19685) (xy -0.21209 -0.20701)
						(xy -0.2159 -0.21717) (xy -0.21844 -0.22733) (xy -0.22225 -0.23876) (xy -0.22352 -0.24892) (xy -0.22606 -0.25908)
						(xy -0.22733 -0.27051) (xy -0.22733 -0.28067) (xy -0.2286 -0.2921) (xy -0.22733 -0.30353) (xy -0.22733 -0.31369)
						(xy -0.22606 -0.32512) (xy -0.22352 -0.33528) (xy -0.22225 -0.34544) (xy -0.21844 -0.35687) (xy -0.2159 -0.36703)
						(xy -0.21209 -0.37719) (xy -0.20701 -0.38735) (xy -0.2032 -0.39624) (xy -0.19812 -0.4064) (xy -0.17272 -0.44196)
						(xy -0.1651 -0.44958) (xy -0.1651 -0.7366) (xy -0.16256 -0.76835) (xy -0.1524 -0.8001) (xy -0.13716 -0.82804)
						(xy -0.11684 -0.85344) (xy -0.09144 -0.87376) (xy -0.0635 -0.889) (xy -0.03175 -0.89916) (xy 0 -0.9017)
						(xy 0.03175 -0.89916) (xy 0.0635 -0.889) (xy 0.09144 -0.87376) (xy 0.11684 -0.85344) (xy 0.13716 -0.82804)
						(xy 0.1524 -0.8001) (xy 0.16256 -0.76835) (xy 0.1651 -0.7366) (xy 0.1651 -0.44958) (xy 0.17272 -0.44196)
						(xy 0.19812 -0.4064) (xy 0.2032 -0.39624) (xy 0.20701 -0.38735) (xy 0.21209 -0.37719) (xy 0.2159 -0.36703)
						(xy 0.21844 -0.35687) (xy 0.22225 -0.34544) (xy 0.22352 -0.33528) (xy 0.22606 -0.32512) (xy 0.22733 -0.31369)
						(xy 0.22733 -0.30353) (xy 0.2286 -0.2921) (xy 0.22733 -0.28067) (xy 0.22733 -0.27051) (xy 0.22606 -0.25908)
						(xy 0.22352 -0.24892) (xy 0.22225 -0.23876) (xy 0.21844 -0.22733) (xy 0.2159 -0.21717) (xy 0.21209 -0.20701)
						(xy 0.20701 -0.19685) (xy 0.2032 -0.18796) (xy 0.19812 -0.1778) (xy 0.17272 -0.14224) (xy 0.1651 -0.13462)
						(xy 0.1651 0.7366) (xy 0.16256 0.76835) (xy 0.1524 0.8001) (xy 0.13716 0.82804) (xy 0.11684 0.85344)
						(xy 0.09144 0.87376) (xy 0.0635 0.889) (xy 0.03175 0.89916)
					)
					(width 0)
					(fill yes)
				)
			)
		)
		(pad "14" smd custom
			(at -27.750008 -4.106672)
			(size 0.1143 0.1143)
			(layers "F.Cu" "F.Mask" "F.Paste")
			(net "GND")
			(options
				(clearance outline)
				(anchor circle)
			)
			(primitives
				(gr_poly
					(pts
						(xy 0 0.9017) (xy -0.03175 0.89916) (xy -0.0635 0.889) (xy -0.09144 0.87376) (xy -0.11684 0.85344)
						(xy -0.13716 0.82804) (xy -0.1524 0.8001) (xy -0.16256 0.76835) (xy -0.1651 0.7366) (xy -0.1651 0.44958)
						(xy -0.17272 0.44196) (xy -0.19812 0.4064) (xy -0.2032 0.39624) (xy -0.20701 0.38735) (xy -0.21209 0.37719)
						(xy -0.2159 0.36703) (xy -0.21844 0.35687) (xy -0.22225 0.34544) (xy -0.22352 0.33528) (xy -0.22606 0.32512)
						(xy -0.22733 0.31369) (xy -0.22733 0.30353) (xy -0.2286 0.2921) (xy -0.22733 0.28067) (xy -0.22733 0.27051)
						(xy -0.22606 0.25908) (xy -0.22352 0.24892) (xy -0.22225 0.23876) (xy -0.21844 0.22733) (xy -0.2159 0.21717)
						(xy -0.21209 0.20701) (xy -0.20701 0.19685) (xy -0.2032 0.18796) (xy -0.19812 0.1778) (xy -0.17272 0.14224)
						(xy -0.1651 0.13462) (xy -0.1651 -0.7366) (xy -0.16256 -0.76835) (xy -0.1524 -0.8001) (xy -0.13716 -0.82804)
						(xy -0.11684 -0.85344) (xy -0.09144 -0.87376) (xy -0.0635 -0.889) (xy -0.03175 -0.89916) (xy 0 -0.9017)
						(xy 0.03175 -0.89916) (xy 0.0635 -0.889) (xy 0.09144 -0.87376) (xy 0.11684 -0.85344) (xy 0.13716 -0.82804)
						(xy 0.1524 -0.8001) (xy 0.16256 -0.76835) (xy 0.1651 -0.7366) (xy 0.1651 0.13462) (xy 0.17272 0.14224)
						(xy 0.19812 0.1778) (xy 0.2032 0.18796) (xy 0.20701 0.19685) (xy 0.21209 0.20701) (xy 0.2159 0.21717)
						(xy 0.21844 0.22733) (xy 0.22225 0.23876) (xy 0.22352 0.24892) (xy 0.22606 0.25908) (xy 0.22733 0.27051)
						(xy 0.22733 0.28067) (xy 0.2286 0.2921) (xy 0.22733 0.30353) (xy 0.22733 0.31369) (xy 0.22606 0.32512)
						(xy 0.22352 0.33528) (xy 0.22225 0.34544) (xy 0.21844 0.35687) (xy 0.2159 0.36703) (xy 0.21209 0.37719)
						(xy 0.20701 0.38735) (xy 0.2032 0.39624) (xy 0.19812 0.4064) (xy 0.17272 0.44196) (xy 0.1651 0.44958)
						(xy 0.1651 0.7366) (xy 0.16256 0.76835) (xy 0.1524 0.8001) (xy 0.13716 0.82804) (xy 0.11684 0.85344)
						(xy 0.09144 0.87376) (xy 0.0635 0.889) (xy 0.03175 0.89916)
					)
					(width 0)
					(fill yes)
				)
			)
		)
		(pad "15" smd custom
			(at -27.450034 4.106672)
			(size 0.1143 0.1143)
			(layers "F.Cu" "F.Mask" "F.Paste")
			(net "M_B_DQ7")
			(options
				(clearance outline)
				(anchor circle)
			)
			(primitives
				(gr_poly
					(pts
						(xy 0 0.9017) (xy -0.03175 0.89916) (xy -0.0635 0.889) (xy -0.09144 0.87376) (xy -0.11684 0.85344)
						(xy -0.13716 0.82804) (xy -0.1524 0.8001) (xy -0.16256 0.76835) (xy -0.1651 0.7366) (xy -0.1651 0.11938)
						(xy -0.17272 0.11176) (xy -0.19812 0.0762) (xy -0.2032 0.06604) (xy -0.20701 0.05715) (xy -0.21209 0.04699)
						(xy -0.2159 0.03683) (xy -0.21844 0.02667) (xy -0.22225 0.01524) (xy -0.22352 0.00508) (xy -0.22606 -0.00508)
						(xy -0.22733 -0.01651) (xy -0.22733 -0.02667) (xy -0.2286 -0.0381) (xy -0.22733 -0.04953) (xy -0.22733 -0.05969)
						(xy -0.22606 -0.07112) (xy -0.22352 -0.08128) (xy -0.22225 -0.09144) (xy -0.21844 -0.10287) (xy -0.2159 -0.11303)
						(xy -0.21209 -0.12319) (xy -0.20701 -0.13335) (xy -0.2032 -0.14224) (xy -0.19812 -0.1524) (xy -0.17272 -0.18796)
						(xy -0.1651 -0.19558) (xy -0.1651 -0.7366) (xy -0.16256 -0.76835) (xy -0.1524 -0.8001) (xy -0.13716 -0.82804)
						(xy -0.11684 -0.85344) (xy -0.09144 -0.87376) (xy -0.0635 -0.889) (xy -0.03175 -0.89916) (xy 0 -0.9017)
						(xy 0.03175 -0.89916) (xy 0.0635 -0.889) (xy 0.09144 -0.87376) (xy 0.11684 -0.85344) (xy 0.13716 -0.82804)
						(xy 0.1524 -0.8001) (xy 0.16256 -0.76835) (xy 0.1651 -0.7366) (xy 0.1651 -0.19685) (xy 0.17272 -0.18923)
						(xy 0.17907 -0.18034) (xy 0.18669 -0.17145) (xy 0.19177 -0.16256) (xy 0.19812 -0.15367) (xy 0.20828 -0.13335)
						(xy 0.21971 -0.10287) (xy 0.22225 -0.09271) (xy 0.22479 -0.08128) (xy 0.22606 -0.07112) (xy 0.2286 -0.05969)
						(xy 0.2286 -0.01651) (xy 0.22606 -0.00508) (xy 0.22479 0.00508) (xy 0.22225 0.01651) (xy 0.21971 0.02667)
						(xy 0.20828 0.05715) (xy 0.19812 0.07747) (xy 0.19177 0.08636) (xy 0.18669 0.09525) (xy 0.17907 0.10414)
						(xy 0.17272 0.11303) (xy 0.1651 0.12065) (xy 0.1651 0.7366) (xy 0.16256 0.76835) (xy 0.1524 0.8001)
						(xy 0.13716 0.82804) (xy 0.11684 0.85344) (xy 0.09144 0.87376) (xy 0.0635 0.889) (xy 0.03175 0.89916)
					)
					(width 0)
					(fill yes)
				)
			)
		)
		(pad "16" smd custom
			(at -27.15006 -4.106672)
			(size 0.1143 0.1143)
			(layers "F.Cu" "F.Mask" "F.Paste")
			(net "M_B_DQ2")
			(options
				(clearance outline)
				(anchor circle)
			)
			(primitives
				(gr_poly
					(pts
						(xy 0 0.9017) (xy -0.03175 0.89916) (xy -0.0635 0.889) (xy -0.09144 0.87376) (xy -0.11684 0.85344)
						(xy -0.13716 0.82804) (xy -0.1524 0.8001) (xy -0.16256 0.76835) (xy -0.1651 0.7366) (xy -0.1651 0.19685)
						(xy -0.17272 0.18923) (xy -0.17907 0.18034) (xy -0.18669 0.17145) (xy -0.19177 0.16256) (xy -0.19812 0.15367)
						(xy -0.20828 0.13335) (xy -0.21971 0.10287) (xy -0.22225 0.09271) (xy -0.22479 0.08128) (xy -0.22606 0.07112)
						(xy -0.2286 0.05969) (xy -0.2286 0.01651) (xy -0.22606 0.00508) (xy -0.22479 -0.00508) (xy -0.22225 -0.01651)
						(xy -0.21971 -0.02667) (xy -0.20828 -0.05715) (xy -0.19812 -0.07747) (xy -0.19177 -0.08636) (xy -0.18669 -0.09525)
						(xy -0.17907 -0.10414) (xy -0.17272 -0.11303) (xy -0.1651 -0.12065) (xy -0.1651 -0.7366) (xy -0.16256 -0.76835)
						(xy -0.1524 -0.8001) (xy -0.13716 -0.82804) (xy -0.11684 -0.85344) (xy -0.09144 -0.87376) (xy -0.0635 -0.889)
						(xy -0.03175 -0.89916) (xy 0 -0.9017) (xy 0.03175 -0.89916) (xy 0.0635 -0.889) (xy 0.09144 -0.87376)
						(xy 0.11684 -0.85344) (xy 0.13716 -0.82804) (xy 0.1524 -0.8001) (xy 0.16256 -0.76835) (xy 0.1651 -0.7366)
						(xy 0.1651 -0.11938) (xy 0.17272 -0.11176) (xy 0.19812 -0.0762) (xy 0.2032 -0.06604) (xy 0.20701 -0.05715)
						(xy 0.21209 -0.04699) (xy 0.2159 -0.03683) (xy 0.21844 -0.02667) (xy 0.22225 -0.01524) (xy 0.22352 -0.00508)
						(xy 0.22606 0.00508) (xy 0.22733 0.01651) (xy 0.22733 0.02667) (xy 0.2286 0.0381) (xy 0.22733 0.04953)
						(xy 0.22733 0.05969) (xy 0.22606 0.07112) (xy 0.22352 0.08128) (xy 0.22225 0.09144) (xy 0.21844 0.10287)
						(xy 0.2159 0.11303) (xy 0.21209 0.12319) (xy 0.20701 0.13335) (xy 0.2032 0.14224) (xy 0.19812 0.1524)
						(xy 0.17272 0.18796) (xy 0.1651 0.19558) (xy 0.1651 0.7366) (xy 0.16256 0.76835) (xy 0.1524 0.8001)
						(xy 0.13716 0.82804) (xy 0.11684 0.85344) (xy 0.09144 0.87376) (xy 0.0635 0.889) (xy 0.03175 0.89916)
					)
					(width 0)
					(fill yes)
				)
			)
		)
		(pad "17" smd custom
			(at -26.850086 4.106672)
			(size 0.1143 0.1143)
			(layers "F.Cu" "F.Mask" "F.Paste")
			(net "GND")
			(options
				(clearance outline)
				(anchor circle)
			)
			(primitives
				(gr_poly
					(pts
						(xy 0 0.9017) (xy -0.03175 0.89916) (xy -0.0635 0.889) (xy -0.09144 0.87376) (xy -0.11684 0.85344)
						(xy -0.13716 0.82804) (xy -0.1524 0.8001) (xy -0.16256 0.76835) (xy -0.1651 0.7366) (xy -0.1651 -0.13462)
						(xy -0.17272 -0.14224) (xy -0.19812 -0.1778) (xy -0.2032 -0.18796) (xy -0.20701 -0.19685) (xy -0.21209 -0.20701)
						(xy -0.2159 -0.21717) (xy -0.21844 -0.22733) (xy -0.22225 -0.23876) (xy -0.22352 -0.24892) (xy -0.22606 -0.25908)
						(xy -0.22733 -0.27051) (xy -0.22733 -0.28067) (xy -0.2286 -0.2921) (xy -0.22733 -0.30353) (xy -0.22733 -0.31369)
						(xy -0.22606 -0.32512) (xy -0.22352 -0.33528) (xy -0.22225 -0.34544) (xy -0.21844 -0.35687) (xy -0.2159 -0.36703)
						(xy -0.21209 -0.37719) (xy -0.20701 -0.38735) (xy -0.2032 -0.39624) (xy -0.19812 -0.4064) (xy -0.17272 -0.44196)
						(xy -0.1651 -0.44958) (xy -0.1651 -0.7366) (xy -0.16256 -0.76835) (xy -0.1524 -0.8001) (xy -0.13716 -0.82804)
						(xy -0.11684 -0.85344) (xy -0.09144 -0.87376) (xy -0.0635 -0.889) (xy -0.03175 -0.89916) (xy 0 -0.9017)
						(xy 0.03175 -0.89916) (xy 0.0635 -0.889) (xy 0.09144 -0.87376) (xy 0.11684 -0.85344) (xy 0.13716 -0.82804)
						(xy 0.1524 -0.8001) (xy 0.16256 -0.76835) (xy 0.1651 -0.7366) (xy 0.1651 -0.44958) (xy 0.17272 -0.44196)
						(xy 0.19812 -0.4064) (xy 0.2032 -0.39624) (xy 0.20701 -0.38735) (xy 0.21209 -0.37719) (xy 0.2159 -0.36703)
						(xy 0.21844 -0.35687) (xy 0.22225 -0.34544) (xy 0.22352 -0.33528) (xy 0.22606 -0.32512) (xy 0.22733 -0.31369)
						(xy 0.22733 -0.30353) (xy 0.2286 -0.2921) (xy 0.22733 -0.28067) (xy 0.22733 -0.27051) (xy 0.22606 -0.25908)
						(xy 0.22352 -0.24892) (xy 0.22225 -0.23876) (xy 0.21844 -0.22733) (xy 0.2159 -0.21717) (xy 0.21209 -0.20701)
						(xy 0.20701 -0.19685) (xy 0.2032 -0.18796) (xy 0.19812 -0.1778) (xy 0.17272 -0.14224) (xy 0.1651 -0.13462)
						(xy 0.1651 0.7366) (xy 0.16256 0.76835) (xy 0.1524 0.8001) (xy 0.13716 0.82804) (xy 0.11684 0.85344)
						(xy 0.09144 0.87376) (xy 0.0635 0.889) (xy 0.03175 0.89916)
					)
					(width 0)
					(fill yes)
				)
			)
		)
		(pad "18" smd custom
			(at -26.550112 -4.106672)
			(size 0.1143 0.1143)
			(layers "F.Cu" "F.Mask" "F.Paste")
			(net "M_B_DQ3")
			(options
				(clearance outline)
				(anchor circle)
			)
			(primitives
				(gr_poly
					(pts
						(xy 0 0.9017) (xy -0.03175 0.89916) (xy -0.0635 0.889) (xy -0.09144 0.87376) (xy -0.11684 0.85344)
						(xy -0.13716 0.82804) (xy -0.1524 0.8001) (xy -0.16256 0.76835) (xy -0.1651 0.7366) (xy -0.1651 0.44958)
						(xy -0.17272 0.44196) (xy -0.19812 0.4064) (xy -0.2032 0.39624) (xy -0.20701 0.38735) (xy -0.21209 0.37719)
						(xy -0.2159 0.36703) (xy -0.21844 0.35687) (xy -0.22225 0.34544) (xy -0.22352 0.33528) (xy -0.22606 0.32512)
						(xy -0.22733 0.31369) (xy -0.22733 0.30353) (xy -0.2286 0.2921) (xy -0.22733 0.28067) (xy -0.22733 0.27051)
						(xy -0.22606 0.25908) (xy -0.22352 0.24892) (xy -0.22225 0.23876) (xy -0.21844 0.22733) (xy -0.2159 0.21717)
						(xy -0.21209 0.20701) (xy -0.20701 0.19685) (xy -0.2032 0.18796) (xy -0.19812 0.1778) (xy -0.17272 0.14224)
						(xy -0.1651 0.13462) (xy -0.1651 -0.7366) (xy -0.16256 -0.76835) (xy -0.1524 -0.8001) (xy -0.13716 -0.82804)
						(xy -0.11684 -0.85344) (xy -0.09144 -0.87376) (xy -0.0635 -0.889) (xy -0.03175 -0.89916) (xy 0 -0.9017)
						(xy 0.03175 -0.89916) (xy 0.0635 -0.889) (xy 0.09144 -0.87376) (xy 0.11684 -0.85344) (xy 0.13716 -0.82804)
						(xy 0.1524 -0.8001) (xy 0.16256 -0.76835) (xy 0.1651 -0.7366) (xy 0.1651 0.13462) (xy 0.17272 0.14224)
						(xy 0.19812 0.1778) (xy 0.2032 0.18796) (xy 0.20701 0.19685) (xy 0.21209 0.20701) (xy 0.2159 0.21717)
						(xy 0.21844 0.22733) (xy 0.22225 0.23876) (xy 0.22352 0.24892) (xy 0.22606 0.25908) (xy 0.22733 0.27051)
						(xy 0.22733 0.28067) (xy 0.2286 0.2921) (xy 0.22733 0.30353) (xy 0.22733 0.31369) (xy 0.22606 0.32512)
						(xy 0.22352 0.33528) (xy 0.22225 0.34544) (xy 0.21844 0.35687) (xy 0.2159 0.36703) (xy 0.21209 0.37719)
						(xy 0.20701 0.38735) (xy 0.2032 0.39624) (xy 0.19812 0.4064) (xy 0.17272 0.44196) (xy 0.1651 0.44958)
						(xy 0.1651 0.7366) (xy 0.16256 0.76835) (xy 0.1524 0.8001) (xy 0.13716 0.82804) (xy 0.11684 0.85344)
						(xy 0.09144 0.87376) (xy 0.0635 0.889) (xy 0.03175 0.89916)
					)
					(width 0)
					(fill yes)
				)
			)
		)
		(pad "19" smd custom
			(at -26.249884 4.106672)
			(size 0.1143 0.1143)
			(layers "F.Cu" "F.Mask" "F.Paste")
			(net "M_B_DQ12")
			(options
				(clearance outline)
				(anchor circle)
			)
			(primitives
				(gr_poly
					(pts
						(xy 0 0.9017) (xy -0.03175 0.89916) (xy -0.0635 0.889) (xy -0.09144 0.87376) (xy -0.11684 0.85344)
						(xy -0.13716 0.82804) (xy -0.1524 0.8001) (xy -0.16256 0.76835) (xy -0.1651 0.7366) (xy -0.1651 0.11938)
						(xy -0.17272 0.11176) (xy -0.19812 0.0762) (xy -0.2032 0.06604) (xy -0.20701 0.05715) (xy -0.21209 0.04699)
						(xy -0.2159 0.03683) (xy -0.21844 0.02667) (xy -0.22225 0.01524) (xy -0.22352 0.00508) (xy -0.22606 -0.00508)
						(xy -0.22733 -0.01651) (xy -0.22733 -0.02667) (xy -0.2286 -0.0381) (xy -0.22733 -0.04953) (xy -0.22733 -0.05969)
						(xy -0.22606 -0.07112) (xy -0.22352 -0.08128) (xy -0.22225 -0.09144) (xy -0.21844 -0.10287) (xy -0.2159 -0.11303)
						(xy -0.21209 -0.12319) (xy -0.20701 -0.13335) (xy -0.2032 -0.14224) (xy -0.19812 -0.1524) (xy -0.17272 -0.18796)
						(xy -0.1651 -0.19558) (xy -0.1651 -0.7366) (xy -0.16256 -0.76835) (xy -0.1524 -0.8001) (xy -0.13716 -0.82804)
						(xy -0.11684 -0.85344) (xy -0.09144 -0.87376) (xy -0.0635 -0.889) (xy -0.03175 -0.89916) (xy 0 -0.9017)
						(xy 0.03175 -0.89916) (xy 0.0635 -0.889) (xy 0.09144 -0.87376) (xy 0.11684 -0.85344) (xy 0.13716 -0.82804)
						(xy 0.1524 -0.8001) (xy 0.16256 -0.76835) (xy 0.1651 -0.7366) (xy 0.1651 -0.19685) (xy 0.17272 -0.18923)
						(xy 0.17907 -0.18034) (xy 0.18669 -0.17145) (xy 0.19177 -0.16256) (xy 0.19812 -0.15367) (xy 0.20828 -0.13335)
						(xy 0.21971 -0.10287) (xy 0.22225 -0.09271) (xy 0.22479 -0.08128) (xy 0.22606 -0.07112) (xy 0.2286 -0.05969)
						(xy 0.2286 -0.01651) (xy 0.22606 -0.00508) (xy 0.22479 0.00508) (xy 0.22225 0.01651) (xy 0.21971 0.02667)
						(xy 0.20828 0.05715) (xy 0.19812 0.07747) (xy 0.19177 0.08636) (xy 0.18669 0.09525) (xy 0.17907 0.10414)
						(xy 0.17272 0.11303) (xy 0.1651 0.12065) (xy 0.1651 0.7366) (xy 0.16256 0.76835) (xy 0.1524 0.8001)
						(xy 0.13716 0.82804) (xy 0.11684 0.85344) (xy 0.09144 0.87376) (xy 0.0635 0.889) (xy 0.03175 0.89916)
					)
					(width 0)
					(fill yes)
				)
			)
		)
		(pad "20" smd custom
			(at -25.94991 -4.106672)
			(size 0.1143 0.1143)
			(layers "F.Cu" "F.Mask" "F.Paste")
			(net "GND")
			(options
				(clearance outline)
				(anchor circle)
			)
			(primitives
				(gr_poly
					(pts
						(xy 0 0.9017) (xy -0.03175 0.89916) (xy -0.0635 0.889) (xy -0.09144 0.87376) (xy -0.11684 0.85344)
						(xy -0.13716 0.82804) (xy -0.1524 0.8001) (xy -0.16256 0.76835) (xy -0.1651 0.7366) (xy -0.1651 0.19685)
						(xy -0.17272 0.18923) (xy -0.17907 0.18034) (xy -0.18669 0.17145) (xy -0.19177 0.16256) (xy -0.19812 0.15367)
						(xy -0.20828 0.13335) (xy -0.21971 0.10287) (xy -0.22225 0.09271) (xy -0.22479 0.08128) (xy -0.22606 0.07112)
						(xy -0.2286 0.05969) (xy -0.2286 0.01651) (xy -0.22606 0.00508) (xy -0.22479 -0.00508) (xy -0.22225 -0.01651)
						(xy -0.21971 -0.02667) (xy -0.20828 -0.05715) (xy -0.19812 -0.07747) (xy -0.19177 -0.08636) (xy -0.18669 -0.09525)
						(xy -0.17907 -0.10414) (xy -0.17272 -0.11303) (xy -0.1651 -0.12065) (xy -0.1651 -0.7366) (xy -0.16256 -0.76835)
						(xy -0.1524 -0.8001) (xy -0.13716 -0.82804) (xy -0.11684 -0.85344) (xy -0.09144 -0.87376) (xy -0.0635 -0.889)
						(xy -0.03175 -0.89916) (xy 0 -0.9017) (xy 0.03175 -0.89916) (xy 0.0635 -0.889) (xy 0.09144 -0.87376)
						(xy 0.11684 -0.85344) (xy 0.13716 -0.82804) (xy 0.1524 -0.8001) (xy 0.16256 -0.76835) (xy 0.1651 -0.7366)
						(xy 0.1651 -0.11938) (xy 0.17272 -0.11176) (xy 0.19812 -0.0762) (xy 0.2032 -0.06604) (xy 0.20701 -0.05715)
						(xy 0.21209 -0.04699) (xy 0.2159 -0.03683) (xy 0.21844 -0.02667) (xy 0.22225 -0.01524) (xy 0.22352 -0.00508)
						(xy 0.22606 0.00508) (xy 0.22733 0.01651) (xy 0.22733 0.02667) (xy 0.2286 0.0381) (xy 0.22733 0.04953)
						(xy 0.22733 0.05969) (xy 0.22606 0.07112) (xy 0.22352 0.08128) (xy 0.22225 0.09144) (xy 0.21844 0.10287)
						(xy 0.2159 0.11303) (xy 0.21209 0.12319) (xy 0.20701 0.13335) (xy 0.2032 0.14224) (xy 0.19812 0.1524)
						(xy 0.17272 0.18796) (xy 0.1651 0.19558) (xy 0.1651 0.7366) (xy 0.16256 0.76835) (xy 0.1524 0.8001)
						(xy 0.13716 0.82804) (xy 0.11684 0.85344) (xy 0.09144 0.87376) (xy 0.0635 0.889) (xy 0.03175 0.89916)
					)
					(width 0)
					(fill yes)
				)
			)
		)
		(pad "21" smd custom
			(at -25.649936 4.106672)
			(size 0.1143 0.1143)
			(layers "F.Cu" "F.Mask" "F.Paste")
			(net "M_B_DQ13")
			(options
				(clearance outline)
				(anchor circle)
			)
			(primitives
				(gr_poly
					(pts
						(xy 0 0.9017) (xy -0.03175 0.89916) (xy -0.0635 0.889) (xy -0.09144 0.87376) (xy -0.11684 0.85344)
						(xy -0.13716 0.82804) (xy -0.1524 0.8001) (xy -0.16256 0.76835) (xy -0.1651 0.7366) (xy -0.1651 -0.13462)
						(xy -0.17272 -0.14224) (xy -0.19812 -0.1778) (xy -0.2032 -0.18796) (xy -0.20701 -0.19685) (xy -0.21209 -0.20701)
						(xy -0.2159 -0.21717) (xy -0.21844 -0.22733) (xy -0.22225 -0.23876) (xy -0.22352 -0.24892) (xy -0.22606 -0.25908)
						(xy -0.22733 -0.27051) (xy -0.22733 -0.28067) (xy -0.2286 -0.2921) (xy -0.22733 -0.30353) (xy -0.22733 -0.31369)
						(xy -0.22606 -0.32512) (xy -0.22352 -0.33528) (xy -0.22225 -0.34544) (xy -0.21844 -0.35687) (xy -0.2159 -0.36703)
						(xy -0.21209 -0.37719) (xy -0.20701 -0.38735) (xy -0.2032 -0.39624) (xy -0.19812 -0.4064) (xy -0.17272 -0.44196)
						(xy -0.1651 -0.44958) (xy -0.1651 -0.7366) (xy -0.16256 -0.76835) (xy -0.1524 -0.8001) (xy -0.13716 -0.82804)
						(xy -0.11684 -0.85344) (xy -0.09144 -0.87376) (xy -0.0635 -0.889) (xy -0.03175 -0.89916) (xy 0 -0.9017)
						(xy 0.03175 -0.89916) (xy 0.0635 -0.889) (xy 0.09144 -0.87376) (xy 0.11684 -0.85344) (xy 0.13716 -0.82804)
						(xy 0.1524 -0.8001) (xy 0.16256 -0.76835) (xy 0.1651 -0.7366) (xy 0.1651 -0.44958) (xy 0.17272 -0.44196)
						(xy 0.19812 -0.4064) (xy 0.2032 -0.39624) (xy 0.20701 -0.38735) (xy 0.21209 -0.37719) (xy 0.2159 -0.36703)
						(xy 0.21844 -0.35687) (xy 0.22225 -0.34544) (xy 0.22352 -0.33528) (xy 0.22606 -0.32512) (xy 0.22733 -0.31369)
						(xy 0.22733 -0.30353) (xy 0.2286 -0.2921) (xy 0.22733 -0.28067) (xy 0.22733 -0.27051) (xy 0.22606 -0.25908)
						(xy 0.22352 -0.24892) (xy 0.22225 -0.23876) (xy 0.21844 -0.22733) (xy 0.2159 -0.21717) (xy 0.21209 -0.20701)
						(xy 0.20701 -0.19685) (xy 0.2032 -0.18796) (xy 0.19812 -0.1778) (xy 0.17272 -0.14224) (xy 0.1651 -0.13462)
						(xy 0.1651 0.7366) (xy 0.16256 0.76835) (xy 0.1524 0.8001) (xy 0.13716 0.82804) (xy 0.11684 0.85344)
						(xy 0.09144 0.87376) (xy 0.0635 0.889) (xy 0.03175 0.89916)
					)
					(width 0)
					(fill yes)
				)
			)
		)
		(pad "22" smd custom
			(at -25.349962 -4.106672)
			(size 0.1143 0.1143)
			(layers "F.Cu" "F.Mask" "F.Paste")
			(net "M_B_DQ8")
			(options
				(clearance outline)
				(anchor circle)
			)
			(primitives
				(gr_poly
					(pts
						(xy 0 0.9017) (xy -0.03175 0.89916) (xy -0.0635 0.889) (xy -0.09144 0.87376) (xy -0.11684 0.85344)
						(xy -0.13716 0.82804) (xy -0.1524 0.8001) (xy -0.16256 0.76835) (xy -0.1651 0.7366) (xy -0.1651 0.44958)
						(xy -0.17272 0.44196) (xy -0.19812 0.4064) (xy -0.2032 0.39624) (xy -0.20701 0.38735) (xy -0.21209 0.37719)
						(xy -0.2159 0.36703) (xy -0.21844 0.35687) (xy -0.22225 0.34544) (xy -0.22352 0.33528) (xy -0.22606 0.32512)
						(xy -0.22733 0.31369) (xy -0.22733 0.30353) (xy -0.2286 0.2921) (xy -0.22733 0.28067) (xy -0.22733 0.27051)
						(xy -0.22606 0.25908) (xy -0.22352 0.24892) (xy -0.22225 0.23876) (xy -0.21844 0.22733) (xy -0.2159 0.21717)
						(xy -0.21209 0.20701) (xy -0.20701 0.19685) (xy -0.2032 0.18796) (xy -0.19812 0.1778) (xy -0.17272 0.14224)
						(xy -0.1651 0.13462) (xy -0.1651 -0.7366) (xy -0.16256 -0.76835) (xy -0.1524 -0.8001) (xy -0.13716 -0.82804)
						(xy -0.11684 -0.85344) (xy -0.09144 -0.87376) (xy -0.0635 -0.889) (xy -0.03175 -0.89916) (xy 0 -0.9017)
						(xy 0.03175 -0.89916) (xy 0.0635 -0.889) (xy 0.09144 -0.87376) (xy 0.11684 -0.85344) (xy 0.13716 -0.82804)
						(xy 0.1524 -0.8001) (xy 0.16256 -0.76835) (xy 0.1651 -0.7366) (xy 0.1651 0.13462) (xy 0.17272 0.14224)
						(xy 0.19812 0.1778) (xy 0.2032 0.18796) (xy 0.20701 0.19685) (xy 0.21209 0.20701) (xy 0.2159 0.21717)
						(xy 0.21844 0.22733) (xy 0.22225 0.23876) (xy 0.22352 0.24892) (xy 0.22606 0.25908) (xy 0.22733 0.27051)
						(xy 0.22733 0.28067) (xy 0.2286 0.2921) (xy 0.22733 0.30353) (xy 0.22733 0.31369) (xy 0.22606 0.32512)
						(xy 0.22352 0.33528) (xy 0.22225 0.34544) (xy 0.21844 0.35687) (xy 0.2159 0.36703) (xy 0.21209 0.37719)
						(xy 0.20701 0.38735) (xy 0.2032 0.39624) (xy 0.19812 0.4064) (xy 0.17272 0.44196) (xy 0.1651 0.44958)
						(xy 0.1651 0.7366) (xy 0.16256 0.76835) (xy 0.1524 0.8001) (xy 0.13716 0.82804) (xy 0.11684 0.85344)
						(xy 0.09144 0.87376) (xy 0.0635 0.889) (xy 0.03175 0.89916)
					)
					(width 0)
					(fill yes)
				)
			)
		)
		(pad "23" smd custom
			(at -25.049988 4.106672)
			(size 0.1143 0.1143)
			(layers "F.Cu" "F.Mask" "F.Paste")
			(net "GND")
			(options
				(clearance outline)
				(anchor circle)
			)
			(primitives
				(gr_poly
					(pts
						(xy 0 0.9017) (xy -0.03175 0.89916) (xy -0.0635 0.889) (xy -0.09144 0.87376) (xy -0.11684 0.85344)
						(xy -0.13716 0.82804) (xy -0.1524 0.8001) (xy -0.16256 0.76835) (xy -0.1651 0.7366) (xy -0.1651 0.11938)
						(xy -0.17272 0.11176) (xy -0.19812 0.0762) (xy -0.2032 0.06604) (xy -0.20701 0.05715) (xy -0.21209 0.04699)
						(xy -0.2159 0.03683) (xy -0.21844 0.02667) (xy -0.22225 0.01524) (xy -0.22352 0.00508) (xy -0.22606 -0.00508)
						(xy -0.22733 -0.01651) (xy -0.22733 -0.02667) (xy -0.2286 -0.0381) (xy -0.22733 -0.04953) (xy -0.22733 -0.05969)
						(xy -0.22606 -0.07112) (xy -0.22352 -0.08128) (xy -0.22225 -0.09144) (xy -0.21844 -0.10287) (xy -0.2159 -0.11303)
						(xy -0.21209 -0.12319) (xy -0.20701 -0.13335) (xy -0.2032 -0.14224) (xy -0.19812 -0.1524) (xy -0.17272 -0.18796)
						(xy -0.1651 -0.19558) (xy -0.1651 -0.7366) (xy -0.16256 -0.76835) (xy -0.1524 -0.8001) (xy -0.13716 -0.82804)
						(xy -0.11684 -0.85344) (xy -0.09144 -0.87376) (xy -0.0635 -0.889) (xy -0.03175 -0.89916) (xy 0 -0.9017)
						(xy 0.03175 -0.89916) (xy 0.0635 -0.889) (xy 0.09144 -0.87376) (xy 0.11684 -0.85344) (xy 0.13716 -0.82804)
						(xy 0.1524 -0.8001) (xy 0.16256 -0.76835) (xy 0.1651 -0.7366) (xy 0.1651 -0.19685) (xy 0.17272 -0.18923)
						(xy 0.17907 -0.18034) (xy 0.18669 -0.17145) (xy 0.19177 -0.16256) (xy 0.19812 -0.15367) (xy 0.20828 -0.13335)
						(xy 0.21971 -0.10287) (xy 0.22225 -0.09271) (xy 0.22479 -0.08128) (xy 0.22606 -0.07112) (xy 0.2286 -0.05969)
						(xy 0.2286 -0.01651) (xy 0.22606 -0.00508) (xy 0.22479 0.00508) (xy 0.22225 0.01651) (xy 0.21971 0.02667)
						(xy 0.20828 0.05715) (xy 0.19812 0.07747) (xy 0.19177 0.08636) (xy 0.18669 0.09525) (xy 0.17907 0.10414)
						(xy 0.17272 0.11303) (xy 0.1651 0.12065) (xy 0.1651 0.7366) (xy 0.16256 0.76835) (xy 0.1524 0.8001)
						(xy 0.13716 0.82804) (xy 0.11684 0.85344) (xy 0.09144 0.87376) (xy 0.0635 0.889) (xy 0.03175 0.89916)
					)
					(width 0)
					(fill yes)
				)
			)
		)
		(pad "24" smd custom
			(at -24.750014 -4.106672)
			(size 0.1143 0.1143)
			(layers "F.Cu" "F.Mask" "F.Paste")
			(net "M_B_DQ9")
			(options
				(clearance outline)
				(anchor circle)
			)
			(primitives
				(gr_poly
					(pts
						(xy 0 0.9017) (xy -0.03175 0.89916) (xy -0.0635 0.889) (xy -0.09144 0.87376) (xy -0.11684 0.85344)
						(xy -0.13716 0.82804) (xy -0.1524 0.8001) (xy -0.16256 0.76835) (xy -0.1651 0.7366) (xy -0.1651 0.19685)
						(xy -0.17272 0.18923) (xy -0.17907 0.18034) (xy -0.18669 0.17145) (xy -0.19177 0.16256) (xy -0.19812 0.15367)
						(xy -0.20828 0.13335) (xy -0.21971 0.10287) (xy -0.22225 0.09271) (xy -0.22479 0.08128) (xy -0.22606 0.07112)
						(xy -0.2286 0.05969) (xy -0.2286 0.01651) (xy -0.22606 0.00508) (xy -0.22479 -0.00508) (xy -0.22225 -0.01651)
						(xy -0.21971 -0.02667) (xy -0.20828 -0.05715) (xy -0.19812 -0.07747) (xy -0.19177 -0.08636) (xy -0.18669 -0.09525)
						(xy -0.17907 -0.10414) (xy -0.17272 -0.11303) (xy -0.1651 -0.12065) (xy -0.1651 -0.7366) (xy -0.16256 -0.76835)
						(xy -0.1524 -0.8001) (xy -0.13716 -0.82804) (xy -0.11684 -0.85344) (xy -0.09144 -0.87376) (xy -0.0635 -0.889)
						(xy -0.03175 -0.89916) (xy 0 -0.9017) (xy 0.03175 -0.89916) (xy 0.0635 -0.889) (xy 0.09144 -0.87376)
						(xy 0.11684 -0.85344) (xy 0.13716 -0.82804) (xy 0.1524 -0.8001) (xy 0.16256 -0.76835) (xy 0.1651 -0.7366)
						(xy 0.1651 -0.11938) (xy 0.17272 -0.11176) (xy 0.19812 -0.0762) (xy 0.2032 -0.06604) (xy 0.20701 -0.05715)
						(xy 0.21209 -0.04699) (xy 0.2159 -0.03683) (xy 0.21844 -0.02667) (xy 0.22225 -0.01524) (xy 0.22352 -0.00508)
						(xy 0.22606 0.00508) (xy 0.22733 0.01651) (xy 0.22733 0.02667) (xy 0.2286 0.0381) (xy 0.22733 0.04953)
						(xy 0.22733 0.05969) (xy 0.22606 0.07112) (xy 0.22352 0.08128) (xy 0.22225 0.09144) (xy 0.21844 0.10287)
						(xy 0.2159 0.11303) (xy 0.21209 0.12319) (xy 0.20701 0.13335) (xy 0.2032 0.14224) (xy 0.19812 0.1524)
						(xy 0.17272 0.18796) (xy 0.1651 0.19558) (xy 0.1651 0.7366) (xy 0.16256 0.76835) (xy 0.1524 0.8001)
						(xy 0.13716 0.82804) (xy 0.11684 0.85344) (xy 0.09144 0.87376) (xy 0.0635 0.889) (xy 0.03175 0.89916)
					)
					(width 0)
					(fill yes)
				)
			)
		)
		(pad "25" smd custom
			(at -24.45004 4.106672)
			(size 0.1143 0.1143)
			(layers "F.Cu" "F.Mask" "F.Paste")
			(net "M_B_DQS_DN1")
			(options
				(clearance outline)
				(anchor circle)
			)
			(primitives
				(gr_poly
					(pts
						(xy 0 0.9017) (xy -0.03175 0.89916) (xy -0.0635 0.889) (xy -0.09144 0.87376) (xy -0.11684 0.85344)
						(xy -0.13716 0.82804) (xy -0.1524 0.8001) (xy -0.16256 0.76835) (xy -0.1651 0.7366) (xy -0.1651 -0.13462)
						(xy -0.17272 -0.14224) (xy -0.19812 -0.1778) (xy -0.2032 -0.18796) (xy -0.20701 -0.19685) (xy -0.21209 -0.20701)
						(xy -0.2159 -0.21717) (xy -0.21844 -0.22733) (xy -0.22225 -0.23876) (xy -0.22352 -0.24892) (xy -0.22606 -0.25908)
						(xy -0.22733 -0.27051) (xy -0.22733 -0.28067) (xy -0.2286 -0.2921) (xy -0.22733 -0.30353) (xy -0.22733 -0.31369)
						(xy -0.22606 -0.32512) (xy -0.22352 -0.33528) (xy -0.22225 -0.34544) (xy -0.21844 -0.35687) (xy -0.2159 -0.36703)
						(xy -0.21209 -0.37719) (xy -0.20701 -0.38735) (xy -0.2032 -0.39624) (xy -0.19812 -0.4064) (xy -0.17272 -0.44196)
						(xy -0.1651 -0.44958) (xy -0.1651 -0.7366) (xy -0.16256 -0.76835) (xy -0.1524 -0.8001) (xy -0.13716 -0.82804)
						(xy -0.11684 -0.85344) (xy -0.09144 -0.87376) (xy -0.0635 -0.889) (xy -0.03175 -0.89916) (xy 0 -0.9017)
						(xy 0.03175 -0.89916) (xy 0.0635 -0.889) (xy 0.09144 -0.87376) (xy 0.11684 -0.85344) (xy 0.13716 -0.82804)
						(xy 0.1524 -0.8001) (xy 0.16256 -0.76835) (xy 0.1651 -0.7366) (xy 0.1651 -0.44958) (xy 0.17272 -0.44196)
						(xy 0.19812 -0.4064) (xy 0.2032 -0.39624) (xy 0.20701 -0.38735) (xy 0.21209 -0.37719) (xy 0.2159 -0.36703)
						(xy 0.21844 -0.35687) (xy 0.22225 -0.34544) (xy 0.22352 -0.33528) (xy 0.22606 -0.32512) (xy 0.22733 -0.31369)
						(xy 0.22733 -0.30353) (xy 0.2286 -0.2921) (xy 0.22733 -0.28067) (xy 0.22733 -0.27051) (xy 0.22606 -0.25908)
						(xy 0.22352 -0.24892) (xy 0.22225 -0.23876) (xy 0.21844 -0.22733) (xy 0.2159 -0.21717) (xy 0.21209 -0.20701)
						(xy 0.20701 -0.19685) (xy 0.2032 -0.18796) (xy 0.19812 -0.1778) (xy 0.17272 -0.14224) (xy 0.1651 -0.13462)
						(xy 0.1651 0.7366) (xy 0.16256 0.76835) (xy 0.1524 0.8001) (xy 0.13716 0.82804) (xy 0.11684 0.85344)
						(xy 0.09144 0.87376) (xy 0.0635 0.889) (xy 0.03175 0.89916)
					)
					(width 0)
					(fill yes)
				)
			)
		)
		(pad "26" smd custom
			(at -24.150066 -4.106672)
			(size 0.1143 0.1143)
			(layers "F.Cu" "F.Mask" "F.Paste")
			(net "GND")
			(options
				(clearance outline)
				(anchor circle)
			)
			(primitives
				(gr_poly
					(pts
						(xy 0 0.9017) (xy -0.03175 0.89916) (xy -0.0635 0.889) (xy -0.09144 0.87376) (xy -0.11684 0.85344)
						(xy -0.13716 0.82804) (xy -0.1524 0.8001) (xy -0.16256 0.76835) (xy -0.1651 0.7366) (xy -0.1651 0.44958)
						(xy -0.17272 0.44196) (xy -0.19812 0.4064) (xy -0.2032 0.39624) (xy -0.20701 0.38735) (xy -0.21209 0.37719)
						(xy -0.2159 0.36703) (xy -0.21844 0.35687) (xy -0.22225 0.34544) (xy -0.22352 0.33528) (xy -0.22606 0.32512)
						(xy -0.22733 0.31369) (xy -0.22733 0.30353) (xy -0.2286 0.2921) (xy -0.22733 0.28067) (xy -0.22733 0.27051)
						(xy -0.22606 0.25908) (xy -0.22352 0.24892) (xy -0.22225 0.23876) (xy -0.21844 0.22733) (xy -0.2159 0.21717)
						(xy -0.21209 0.20701) (xy -0.20701 0.19685) (xy -0.2032 0.18796) (xy -0.19812 0.1778) (xy -0.17272 0.14224)
						(xy -0.1651 0.13462) (xy -0.1651 -0.7366) (xy -0.16256 -0.76835) (xy -0.1524 -0.8001) (xy -0.13716 -0.82804)
						(xy -0.11684 -0.85344) (xy -0.09144 -0.87376) (xy -0.0635 -0.889) (xy -0.03175 -0.89916) (xy 0 -0.9017)
						(xy 0.03175 -0.89916) (xy 0.0635 -0.889) (xy 0.09144 -0.87376) (xy 0.11684 -0.85344) (xy 0.13716 -0.82804)
						(xy 0.1524 -0.8001) (xy 0.16256 -0.76835) (xy 0.1651 -0.7366) (xy 0.1651 0.13462) (xy 0.17272 0.14224)
						(xy 0.19812 0.1778) (xy 0.2032 0.18796) (xy 0.20701 0.19685) (xy 0.21209 0.20701) (xy 0.2159 0.21717)
						(xy 0.21844 0.22733) (xy 0.22225 0.23876) (xy 0.22352 0.24892) (xy 0.22606 0.25908) (xy 0.22733 0.27051)
						(xy 0.22733 0.28067) (xy 0.2286 0.2921) (xy 0.22733 0.30353) (xy 0.22733 0.31369) (xy 0.22606 0.32512)
						(xy 0.22352 0.33528) (xy 0.22225 0.34544) (xy 0.21844 0.35687) (xy 0.2159 0.36703) (xy 0.21209 0.37719)
						(xy 0.20701 0.38735) (xy 0.2032 0.39624) (xy 0.19812 0.4064) (xy 0.17272 0.44196) (xy 0.1651 0.44958)
						(xy 0.1651 0.7366) (xy 0.16256 0.76835) (xy 0.1524 0.8001) (xy 0.13716 0.82804) (xy 0.11684 0.85344)
						(xy 0.09144 0.87376) (xy 0.0635 0.889) (xy 0.03175 0.89916)
					)
					(width 0)
					(fill yes)
				)
			)
		)
		(pad "27" smd custom
			(at -23.850092 4.106672)
			(size 0.1143 0.1143)
			(layers "F.Cu" "F.Mask" "F.Paste")
			(net "M_B_DQS_DP1")
			(options
				(clearance outline)
				(anchor circle)
			)
			(primitives
				(gr_poly
					(pts
						(xy 0 0.9017) (xy -0.03175 0.89916) (xy -0.0635 0.889) (xy -0.09144 0.87376) (xy -0.11684 0.85344)
						(xy -0.13716 0.82804) (xy -0.1524 0.8001) (xy -0.16256 0.76835) (xy -0.1651 0.7366) (xy -0.1651 0.11938)
						(xy -0.17272 0.11176) (xy -0.19812 0.0762) (xy -0.2032 0.06604) (xy -0.20701 0.05715) (xy -0.21209 0.04699)
						(xy -0.2159 0.03683) (xy -0.21844 0.02667) (xy -0.22225 0.01524) (xy -0.22352 0.00508) (xy -0.22606 -0.00508)
						(xy -0.22733 -0.01651) (xy -0.22733 -0.02667) (xy -0.2286 -0.0381) (xy -0.22733 -0.04953) (xy -0.22733 -0.05969)
						(xy -0.22606 -0.07112) (xy -0.22352 -0.08128) (xy -0.22225 -0.09144) (xy -0.21844 -0.10287) (xy -0.2159 -0.11303)
						(xy -0.21209 -0.12319) (xy -0.20701 -0.13335) (xy -0.2032 -0.14224) (xy -0.19812 -0.1524) (xy -0.17272 -0.18796)
						(xy -0.1651 -0.19558) (xy -0.1651 -0.7366) (xy -0.16256 -0.76835) (xy -0.1524 -0.8001) (xy -0.13716 -0.82804)
						(xy -0.11684 -0.85344) (xy -0.09144 -0.87376) (xy -0.0635 -0.889) (xy -0.03175 -0.89916) (xy 0 -0.9017)
						(xy 0.03175 -0.89916) (xy 0.0635 -0.889) (xy 0.09144 -0.87376) (xy 0.11684 -0.85344) (xy 0.13716 -0.82804)
						(xy 0.1524 -0.8001) (xy 0.16256 -0.76835) (xy 0.1651 -0.7366) (xy 0.1651 -0.19685) (xy 0.17272 -0.18923)
						(xy 0.17907 -0.18034) (xy 0.18669 -0.17145) (xy 0.19177 -0.16256) (xy 0.19812 -0.15367) (xy 0.20828 -0.13335)
						(xy 0.21971 -0.10287) (xy 0.22225 -0.09271) (xy 0.22479 -0.08128) (xy 0.22606 -0.07112) (xy 0.2286 -0.05969)
						(xy 0.2286 -0.01651) (xy 0.22606 -0.00508) (xy 0.22479 0.00508) (xy 0.22225 0.01651) (xy 0.21971 0.02667)
						(xy 0.20828 0.05715) (xy 0.19812 0.07747) (xy 0.19177 0.08636) (xy 0.18669 0.09525) (xy 0.17907 0.10414)
						(xy 0.17272 0.11303) (xy 0.1651 0.12065) (xy 0.1651 0.7366) (xy 0.16256 0.76835) (xy 0.1524 0.8001)
						(xy 0.13716 0.82804) (xy 0.11684 0.85344) (xy 0.09144 0.87376) (xy 0.0635 0.889) (xy 0.03175 0.89916)
					)
					(width 0)
					(fill yes)
				)
			)
		)
		(pad "28" smd custom
			(at -23.550118 -4.106672)
			(size 0.1143 0.1143)
			(layers "F.Cu" "F.Mask" "F.Paste")
			(net "GND")
			(options
				(clearance outline)
				(anchor circle)
			)
			(primitives
				(gr_poly
					(pts
						(xy 0 0.9017) (xy -0.03175 0.89916) (xy -0.0635 0.889) (xy -0.09144 0.87376) (xy -0.11684 0.85344)
						(xy -0.13716 0.82804) (xy -0.1524 0.8001) (xy -0.16256 0.76835) (xy -0.1651 0.7366) (xy -0.1651 0.19685)
						(xy -0.17272 0.18923) (xy -0.17907 0.18034) (xy -0.18669 0.17145) (xy -0.19177 0.16256) (xy -0.19812 0.15367)
						(xy -0.20828 0.13335) (xy -0.21971 0.10287) (xy -0.22225 0.09271) (xy -0.22479 0.08128) (xy -0.22606 0.07112)
						(xy -0.2286 0.05969) (xy -0.2286 0.01651) (xy -0.22606 0.00508) (xy -0.22479 -0.00508) (xy -0.22225 -0.01651)
						(xy -0.21971 -0.02667) (xy -0.20828 -0.05715) (xy -0.19812 -0.07747) (xy -0.19177 -0.08636) (xy -0.18669 -0.09525)
						(xy -0.17907 -0.10414) (xy -0.17272 -0.11303) (xy -0.1651 -0.12065) (xy -0.1651 -0.7366) (xy -0.16256 -0.76835)
						(xy -0.1524 -0.8001) (xy -0.13716 -0.82804) (xy -0.11684 -0.85344) (xy -0.09144 -0.87376) (xy -0.0635 -0.889)
						(xy -0.03175 -0.89916) (xy 0 -0.9017) (xy 0.03175 -0.89916) (xy 0.0635 -0.889) (xy 0.09144 -0.87376)
						(xy 0.11684 -0.85344) (xy 0.13716 -0.82804) (xy 0.1524 -0.8001) (xy 0.16256 -0.76835) (xy 0.1651 -0.7366)
						(xy 0.1651 -0.11938) (xy 0.17272 -0.11176) (xy 0.19812 -0.0762) (xy 0.2032 -0.06604) (xy 0.20701 -0.05715)
						(xy 0.21209 -0.04699) (xy 0.2159 -0.03683) (xy 0.21844 -0.02667) (xy 0.22225 -0.01524) (xy 0.22352 -0.00508)
						(xy 0.22606 0.00508) (xy 0.22733 0.01651) (xy 0.22733 0.02667) (xy 0.2286 0.0381) (xy 0.22733 0.04953)
						(xy 0.22733 0.05969) (xy 0.22606 0.07112) (xy 0.22352 0.08128) (xy 0.22225 0.09144) (xy 0.21844 0.10287)
						(xy 0.2159 0.11303) (xy 0.21209 0.12319) (xy 0.20701 0.13335) (xy 0.2032 0.14224) (xy 0.19812 0.1524)
						(xy 0.17272 0.18796) (xy 0.1651 0.19558) (xy 0.1651 0.7366) (xy 0.16256 0.76835) (xy 0.1524 0.8001)
						(xy 0.13716 0.82804) (xy 0.11684 0.85344) (xy 0.09144 0.87376) (xy 0.0635 0.889) (xy 0.03175 0.89916)
					)
					(width 0)
					(fill yes)
				)
			)
		)
		(pad "29" smd custom
			(at -23.24989 4.106672)
			(size 0.1143 0.1143)
			(layers "F.Cu" "F.Mask" "F.Paste")
			(net "GND")
			(options
				(clearance outline)
				(anchor circle)
			)
			(primitives
				(gr_poly
					(pts
						(xy 0 0.9017) (xy -0.03175 0.89916) (xy -0.0635 0.889) (xy -0.09144 0.87376) (xy -0.11684 0.85344)
						(xy -0.13716 0.82804) (xy -0.1524 0.8001) (xy -0.16256 0.76835) (xy -0.1651 0.7366) (xy -0.1651 -0.13462)
						(xy -0.17272 -0.14224) (xy -0.19812 -0.1778) (xy -0.2032 -0.18796) (xy -0.20701 -0.19685) (xy -0.21209 -0.20701)
						(xy -0.2159 -0.21717) (xy -0.21844 -0.22733) (xy -0.22225 -0.23876) (xy -0.22352 -0.24892) (xy -0.22606 -0.25908)
						(xy -0.22733 -0.27051) (xy -0.22733 -0.28067) (xy -0.2286 -0.2921) (xy -0.22733 -0.30353) (xy -0.22733 -0.31369)
						(xy -0.22606 -0.32512) (xy -0.22352 -0.33528) (xy -0.22225 -0.34544) (xy -0.21844 -0.35687) (xy -0.2159 -0.36703)
						(xy -0.21209 -0.37719) (xy -0.20701 -0.38735) (xy -0.2032 -0.39624) (xy -0.19812 -0.4064) (xy -0.17272 -0.44196)
						(xy -0.1651 -0.44958) (xy -0.1651 -0.7366) (xy -0.16256 -0.76835) (xy -0.1524 -0.8001) (xy -0.13716 -0.82804)
						(xy -0.11684 -0.85344) (xy -0.09144 -0.87376) (xy -0.0635 -0.889) (xy -0.03175 -0.89916) (xy 0 -0.9017)
						(xy 0.03175 -0.89916) (xy 0.0635 -0.889) (xy 0.09144 -0.87376) (xy 0.11684 -0.85344) (xy 0.13716 -0.82804)
						(xy 0.1524 -0.8001) (xy 0.16256 -0.76835) (xy 0.1651 -0.7366) (xy 0.1651 -0.44958) (xy 0.17272 -0.44196)
						(xy 0.19812 -0.4064) (xy 0.2032 -0.39624) (xy 0.20701 -0.38735) (xy 0.21209 -0.37719) (xy 0.2159 -0.36703)
						(xy 0.21844 -0.35687) (xy 0.22225 -0.34544) (xy 0.22352 -0.33528) (xy 0.22606 -0.32512) (xy 0.22733 -0.31369)
						(xy 0.22733 -0.30353) (xy 0.2286 -0.2921) (xy 0.22733 -0.28067) (xy 0.22733 -0.27051) (xy 0.22606 -0.25908)
						(xy 0.22352 -0.24892) (xy 0.22225 -0.23876) (xy 0.21844 -0.22733) (xy 0.2159 -0.21717) (xy 0.21209 -0.20701)
						(xy 0.20701 -0.19685) (xy 0.2032 -0.18796) (xy 0.19812 -0.1778) (xy 0.17272 -0.14224) (xy 0.1651 -0.13462)
						(xy 0.1651 0.7366) (xy 0.16256 0.76835) (xy 0.1524 0.8001) (xy 0.13716 0.82804) (xy 0.11684 0.85344)
						(xy 0.09144 0.87376) (xy 0.0635 0.889) (xy 0.03175 0.89916)
					)
					(width 0)
					(fill yes)
				)
			)
		)
		(pad "30" smd custom
			(at -22.949916 -4.106672)
			(size 0.1143 0.1143)
			(layers "F.Cu" "F.Mask" "F.Paste")
			(net "M_B_RESET#")
			(options
				(clearance outline)
				(anchor circle)
			)
			(primitives
				(gr_poly
					(pts
						(xy 0 0.9017) (xy -0.03175 0.89916) (xy -0.0635 0.889) (xy -0.09144 0.87376) (xy -0.11684 0.85344)
						(xy -0.13716 0.82804) (xy -0.1524 0.8001) (xy -0.16256 0.76835) (xy -0.1651 0.7366) (xy -0.1651 0.44958)
						(xy -0.17272 0.44196) (xy -0.19812 0.4064) (xy -0.2032 0.39624) (xy -0.20701 0.38735) (xy -0.21209 0.37719)
						(xy -0.2159 0.36703) (xy -0.21844 0.35687) (xy -0.22225 0.34544) (xy -0.22352 0.33528) (xy -0.22606 0.32512)
						(xy -0.22733 0.31369) (xy -0.22733 0.30353) (xy -0.2286 0.2921) (xy -0.22733 0.28067) (xy -0.22733 0.27051)
						(xy -0.22606 0.25908) (xy -0.22352 0.24892) (xy -0.22225 0.23876) (xy -0.21844 0.22733) (xy -0.2159 0.21717)
						(xy -0.21209 0.20701) (xy -0.20701 0.19685) (xy -0.2032 0.18796) (xy -0.19812 0.1778) (xy -0.17272 0.14224)
						(xy -0.1651 0.13462) (xy -0.1651 -0.7366) (xy -0.16256 -0.76835) (xy -0.1524 -0.8001) (xy -0.13716 -0.82804)
						(xy -0.11684 -0.85344) (xy -0.09144 -0.87376) (xy -0.0635 -0.889) (xy -0.03175 -0.89916) (xy 0 -0.9017)
						(xy 0.03175 -0.89916) (xy 0.0635 -0.889) (xy 0.09144 -0.87376) (xy 0.11684 -0.85344) (xy 0.13716 -0.82804)
						(xy 0.1524 -0.8001) (xy 0.16256 -0.76835) (xy 0.1651 -0.7366) (xy 0.1651 0.13462) (xy 0.17272 0.14224)
						(xy 0.19812 0.1778) (xy 0.2032 0.18796) (xy 0.20701 0.19685) (xy 0.21209 0.20701) (xy 0.2159 0.21717)
						(xy 0.21844 0.22733) (xy 0.22225 0.23876) (xy 0.22352 0.24892) (xy 0.22606 0.25908) (xy 0.22733 0.27051)
						(xy 0.22733 0.28067) (xy 0.2286 0.2921) (xy 0.22733 0.30353) (xy 0.22733 0.31369) (xy 0.22606 0.32512)
						(xy 0.22352 0.33528) (xy 0.22225 0.34544) (xy 0.21844 0.35687) (xy 0.2159 0.36703) (xy 0.21209 0.37719)
						(xy 0.20701 0.38735) (xy 0.2032 0.39624) (xy 0.19812 0.4064) (xy 0.17272 0.44196) (xy 0.1651 0.44958)
						(xy 0.1651 0.7366) (xy 0.16256 0.76835) (xy 0.1524 0.8001) (xy 0.13716 0.82804) (xy 0.11684 0.85344)
						(xy 0.09144 0.87376) (xy 0.0635 0.889) (xy 0.03175 0.89916)
					)
					(width 0)
					(fill yes)
				)
			)
		)
		(pad "31" smd custom
			(at -22.649942 4.106672)
			(size 0.1143 0.1143)
			(layers "F.Cu" "F.Mask" "F.Paste")
			(net "M_B_DQ14")
			(options
				(clearance outline)
				(anchor circle)
			)
			(primitives
				(gr_poly
					(pts
						(xy 0 0.9017) (xy -0.03175 0.89916) (xy -0.0635 0.889) (xy -0.09144 0.87376) (xy -0.11684 0.85344)
						(xy -0.13716 0.82804) (xy -0.1524 0.8001) (xy -0.16256 0.76835) (xy -0.1651 0.7366) (xy -0.1651 0.11938)
						(xy -0.17272 0.11176) (xy -0.19812 0.0762) (xy -0.2032 0.06604) (xy -0.20701 0.05715) (xy -0.21209 0.04699)
						(xy -0.2159 0.03683) (xy -0.21844 0.02667) (xy -0.22225 0.01524) (xy -0.22352 0.00508) (xy -0.22606 -0.00508)
						(xy -0.22733 -0.01651) (xy -0.22733 -0.02667) (xy -0.2286 -0.0381) (xy -0.22733 -0.04953) (xy -0.22733 -0.05969)
						(xy -0.22606 -0.07112) (xy -0.22352 -0.08128) (xy -0.22225 -0.09144) (xy -0.21844 -0.10287) (xy -0.2159 -0.11303)
						(xy -0.21209 -0.12319) (xy -0.20701 -0.13335) (xy -0.2032 -0.14224) (xy -0.19812 -0.1524) (xy -0.17272 -0.18796)
						(xy -0.1651 -0.19558) (xy -0.1651 -0.7366) (xy -0.16256 -0.76835) (xy -0.1524 -0.8001) (xy -0.13716 -0.82804)
						(xy -0.11684 -0.85344) (xy -0.09144 -0.87376) (xy -0.0635 -0.889) (xy -0.03175 -0.89916) (xy 0 -0.9017)
						(xy 0.03175 -0.89916) (xy 0.0635 -0.889) (xy 0.09144 -0.87376) (xy 0.11684 -0.85344) (xy 0.13716 -0.82804)
						(xy 0.1524 -0.8001) (xy 0.16256 -0.76835) (xy 0.1651 -0.7366) (xy 0.1651 -0.19685) (xy 0.17272 -0.18923)
						(xy 0.17907 -0.18034) (xy 0.18669 -0.17145) (xy 0.19177 -0.16256) (xy 0.19812 -0.15367) (xy 0.20828 -0.13335)
						(xy 0.21971 -0.10287) (xy 0.22225 -0.09271) (xy 0.22479 -0.08128) (xy 0.22606 -0.07112) (xy 0.2286 -0.05969)
						(xy 0.2286 -0.01651) (xy 0.22606 -0.00508) (xy 0.22479 0.00508) (xy 0.22225 0.01651) (xy 0.21971 0.02667)
						(xy 0.20828 0.05715) (xy 0.19812 0.07747) (xy 0.19177 0.08636) (xy 0.18669 0.09525) (xy 0.17907 0.10414)
						(xy 0.17272 0.11303) (xy 0.1651 0.12065) (xy 0.1651 0.7366) (xy 0.16256 0.76835) (xy 0.1524 0.8001)
						(xy 0.13716 0.82804) (xy 0.11684 0.85344) (xy 0.09144 0.87376) (xy 0.0635 0.889) (xy 0.03175 0.89916)
					)
					(width 0)
					(fill yes)
				)
			)
		)
		(pad "32" smd custom
			(at -22.349968 -4.106672)
			(size 0.1143 0.1143)
			(layers "F.Cu" "F.Mask" "F.Paste")
			(net "GND")
			(options
				(clearance outline)
				(anchor circle)
			)
			(primitives
				(gr_poly
					(pts
						(xy 0 0.9017) (xy -0.03175 0.89916) (xy -0.0635 0.889) (xy -0.09144 0.87376) (xy -0.11684 0.85344)
						(xy -0.13716 0.82804) (xy -0.1524 0.8001) (xy -0.16256 0.76835) (xy -0.1651 0.7366) (xy -0.1651 0.19685)
						(xy -0.17272 0.18923) (xy -0.17907 0.18034) (xy -0.18669 0.17145) (xy -0.19177 0.16256) (xy -0.19812 0.15367)
						(xy -0.20828 0.13335) (xy -0.21971 0.10287) (xy -0.22225 0.09271) (xy -0.22479 0.08128) (xy -0.22606 0.07112)
						(xy -0.2286 0.05969) (xy -0.2286 0.01651) (xy -0.22606 0.00508) (xy -0.22479 -0.00508) (xy -0.22225 -0.01651)
						(xy -0.21971 -0.02667) (xy -0.20828 -0.05715) (xy -0.19812 -0.07747) (xy -0.19177 -0.08636) (xy -0.18669 -0.09525)
						(xy -0.17907 -0.10414) (xy -0.17272 -0.11303) (xy -0.1651 -0.12065) (xy -0.1651 -0.7366) (xy -0.16256 -0.76835)
						(xy -0.1524 -0.8001) (xy -0.13716 -0.82804) (xy -0.11684 -0.85344) (xy -0.09144 -0.87376) (xy -0.0635 -0.889)
						(xy -0.03175 -0.89916) (xy 0 -0.9017) (xy 0.03175 -0.89916) (xy 0.0635 -0.889) (xy 0.09144 -0.87376)
						(xy 0.11684 -0.85344) (xy 0.13716 -0.82804) (xy 0.1524 -0.8001) (xy 0.16256 -0.76835) (xy 0.1651 -0.7366)
						(xy 0.1651 -0.11938) (xy 0.17272 -0.11176) (xy 0.19812 -0.0762) (xy 0.2032 -0.06604) (xy 0.20701 -0.05715)
						(xy 0.21209 -0.04699) (xy 0.2159 -0.03683) (xy 0.21844 -0.02667) (xy 0.22225 -0.01524) (xy 0.22352 -0.00508)
						(xy 0.22606 0.00508) (xy 0.22733 0.01651) (xy 0.22733 0.02667) (xy 0.2286 0.0381) (xy 0.22733 0.04953)
						(xy 0.22733 0.05969) (xy 0.22606 0.07112) (xy 0.22352 0.08128) (xy 0.22225 0.09144) (xy 0.21844 0.10287)
						(xy 0.2159 0.11303) (xy 0.21209 0.12319) (xy 0.20701 0.13335) (xy 0.2032 0.14224) (xy 0.19812 0.1524)
						(xy 0.17272 0.18796) (xy 0.1651 0.19558) (xy 0.1651 0.7366) (xy 0.16256 0.76835) (xy 0.1524 0.8001)
						(xy 0.13716 0.82804) (xy 0.11684 0.85344) (xy 0.09144 0.87376) (xy 0.0635 0.889) (xy 0.03175 0.89916)
					)
					(width 0)
					(fill yes)
				)
			)
		)
		(pad "33" smd custom
			(at -22.049994 4.106672)
			(size 0.1143 0.1143)
			(layers "F.Cu" "F.Mask" "F.Paste")
			(net "M_B_DQ15")
			(options
				(clearance outline)
				(anchor circle)
			)
			(primitives
				(gr_poly
					(pts
						(xy 0 0.9017) (xy -0.03175 0.89916) (xy -0.0635 0.889) (xy -0.09144 0.87376) (xy -0.11684 0.85344)
						(xy -0.13716 0.82804) (xy -0.1524 0.8001) (xy -0.16256 0.76835) (xy -0.1651 0.7366) (xy -0.1651 -0.13462)
						(xy -0.17272 -0.14224) (xy -0.19812 -0.1778) (xy -0.2032 -0.18796) (xy -0.20701 -0.19685) (xy -0.21209 -0.20701)
						(xy -0.2159 -0.21717) (xy -0.21844 -0.22733) (xy -0.22225 -0.23876) (xy -0.22352 -0.24892) (xy -0.22606 -0.25908)
						(xy -0.22733 -0.27051) (xy -0.22733 -0.28067) (xy -0.2286 -0.2921) (xy -0.22733 -0.30353) (xy -0.22733 -0.31369)
						(xy -0.22606 -0.32512) (xy -0.22352 -0.33528) (xy -0.22225 -0.34544) (xy -0.21844 -0.35687) (xy -0.2159 -0.36703)
						(xy -0.21209 -0.37719) (xy -0.20701 -0.38735) (xy -0.2032 -0.39624) (xy -0.19812 -0.4064) (xy -0.17272 -0.44196)
						(xy -0.1651 -0.44958) (xy -0.1651 -0.7366) (xy -0.16256 -0.76835) (xy -0.1524 -0.8001) (xy -0.13716 -0.82804)
						(xy -0.11684 -0.85344) (xy -0.09144 -0.87376) (xy -0.0635 -0.889) (xy -0.03175 -0.89916) (xy 0 -0.9017)
						(xy 0.03175 -0.89916) (xy 0.0635 -0.889) (xy 0.09144 -0.87376) (xy 0.11684 -0.85344) (xy 0.13716 -0.82804)
						(xy 0.1524 -0.8001) (xy 0.16256 -0.76835) (xy 0.1651 -0.7366) (xy 0.1651 -0.44958) (xy 0.17272 -0.44196)
						(xy 0.19812 -0.4064) (xy 0.2032 -0.39624) (xy 0.20701 -0.38735) (xy 0.21209 -0.37719) (xy 0.2159 -0.36703)
						(xy 0.21844 -0.35687) (xy 0.22225 -0.34544) (xy 0.22352 -0.33528) (xy 0.22606 -0.32512) (xy 0.22733 -0.31369)
						(xy 0.22733 -0.30353) (xy 0.2286 -0.2921) (xy 0.22733 -0.28067) (xy 0.22733 -0.27051) (xy 0.22606 -0.25908)
						(xy 0.22352 -0.24892) (xy 0.22225 -0.23876) (xy 0.21844 -0.22733) (xy 0.2159 -0.21717) (xy 0.21209 -0.20701)
						(xy 0.20701 -0.19685) (xy 0.2032 -0.18796) (xy 0.19812 -0.1778) (xy 0.17272 -0.14224) (xy 0.1651 -0.13462)
						(xy 0.1651 0.7366) (xy 0.16256 0.76835) (xy 0.1524 0.8001) (xy 0.13716 0.82804) (xy 0.11684 0.85344)
						(xy 0.09144 0.87376) (xy 0.0635 0.889) (xy 0.03175 0.89916)
					)
					(width 0)
					(fill yes)
				)
			)
		)
		(pad "34" smd custom
			(at -21.75002 -4.106672)
			(size 0.1143 0.1143)
			(layers "F.Cu" "F.Mask" "F.Paste")
			(net "M_B_DQ10")
			(options
				(clearance outline)
				(anchor circle)
			)
			(primitives
				(gr_poly
					(pts
						(xy 0 0.9017) (xy -0.03175 0.89916) (xy -0.0635 0.889) (xy -0.09144 0.87376) (xy -0.11684 0.85344)
						(xy -0.13716 0.82804) (xy -0.1524 0.8001) (xy -0.16256 0.76835) (xy -0.1651 0.7366) (xy -0.1651 0.44958)
						(xy -0.17272 0.44196) (xy -0.19812 0.4064) (xy -0.2032 0.39624) (xy -0.20701 0.38735) (xy -0.21209 0.37719)
						(xy -0.2159 0.36703) (xy -0.21844 0.35687) (xy -0.22225 0.34544) (xy -0.22352 0.33528) (xy -0.22606 0.32512)
						(xy -0.22733 0.31369) (xy -0.22733 0.30353) (xy -0.2286 0.2921) (xy -0.22733 0.28067) (xy -0.22733 0.27051)
						(xy -0.22606 0.25908) (xy -0.22352 0.24892) (xy -0.22225 0.23876) (xy -0.21844 0.22733) (xy -0.2159 0.21717)
						(xy -0.21209 0.20701) (xy -0.20701 0.19685) (xy -0.2032 0.18796) (xy -0.19812 0.1778) (xy -0.17272 0.14224)
						(xy -0.1651 0.13462) (xy -0.1651 -0.7366) (xy -0.16256 -0.76835) (xy -0.1524 -0.8001) (xy -0.13716 -0.82804)
						(xy -0.11684 -0.85344) (xy -0.09144 -0.87376) (xy -0.0635 -0.889) (xy -0.03175 -0.89916) (xy 0 -0.9017)
						(xy 0.03175 -0.89916) (xy 0.0635 -0.889) (xy 0.09144 -0.87376) (xy 0.11684 -0.85344) (xy 0.13716 -0.82804)
						(xy 0.1524 -0.8001) (xy 0.16256 -0.76835) (xy 0.1651 -0.7366) (xy 0.1651 0.13462) (xy 0.17272 0.14224)
						(xy 0.19812 0.1778) (xy 0.2032 0.18796) (xy 0.20701 0.19685) (xy 0.21209 0.20701) (xy 0.2159 0.21717)
						(xy 0.21844 0.22733) (xy 0.22225 0.23876) (xy 0.22352 0.24892) (xy 0.22606 0.25908) (xy 0.22733 0.27051)
						(xy 0.22733 0.28067) (xy 0.2286 0.2921) (xy 0.22733 0.30353) (xy 0.22733 0.31369) (xy 0.22606 0.32512)
						(xy 0.22352 0.33528) (xy 0.22225 0.34544) (xy 0.21844 0.35687) (xy 0.2159 0.36703) (xy 0.21209 0.37719)
						(xy 0.20701 0.38735) (xy 0.2032 0.39624) (xy 0.19812 0.4064) (xy 0.17272 0.44196) (xy 0.1651 0.44958)
						(xy 0.1651 0.7366) (xy 0.16256 0.76835) (xy 0.1524 0.8001) (xy 0.13716 0.82804) (xy 0.11684 0.85344)
						(xy 0.09144 0.87376) (xy 0.0635 0.889) (xy 0.03175 0.89916)
					)
					(width 0)
					(fill yes)
				)
			)
		)
		(pad "35" smd custom
			(at -21.450046 4.106672)
			(size 0.1143 0.1143)
			(layers "F.Cu" "F.Mask" "F.Paste")
			(net "GND")
			(options
				(clearance outline)
				(anchor circle)
			)
			(primitives
				(gr_poly
					(pts
						(xy 0 0.9017) (xy -0.03175 0.89916) (xy -0.0635 0.889) (xy -0.09144 0.87376) (xy -0.11684 0.85344)
						(xy -0.13716 0.82804) (xy -0.1524 0.8001) (xy -0.16256 0.76835) (xy -0.1651 0.7366) (xy -0.1651 0.11938)
						(xy -0.17272 0.11176) (xy -0.19812 0.0762) (xy -0.2032 0.06604) (xy -0.20701 0.05715) (xy -0.21209 0.04699)
						(xy -0.2159 0.03683) (xy -0.21844 0.02667) (xy -0.22225 0.01524) (xy -0.22352 0.00508) (xy -0.22606 -0.00508)
						(xy -0.22733 -0.01651) (xy -0.22733 -0.02667) (xy -0.2286 -0.0381) (xy -0.22733 -0.04953) (xy -0.22733 -0.05969)
						(xy -0.22606 -0.07112) (xy -0.22352 -0.08128) (xy -0.22225 -0.09144) (xy -0.21844 -0.10287) (xy -0.2159 -0.11303)
						(xy -0.21209 -0.12319) (xy -0.20701 -0.13335) (xy -0.2032 -0.14224) (xy -0.19812 -0.1524) (xy -0.17272 -0.18796)
						(xy -0.1651 -0.19558) (xy -0.1651 -0.7366) (xy -0.16256 -0.76835) (xy -0.1524 -0.8001) (xy -0.13716 -0.82804)
						(xy -0.11684 -0.85344) (xy -0.09144 -0.87376) (xy -0.0635 -0.889) (xy -0.03175 -0.89916) (xy 0 -0.9017)
						(xy 0.03175 -0.89916) (xy 0.0635 -0.889) (xy 0.09144 -0.87376) (xy 0.11684 -0.85344) (xy 0.13716 -0.82804)
						(xy 0.1524 -0.8001) (xy 0.16256 -0.76835) (xy 0.1651 -0.7366) (xy 0.1651 -0.19685) (xy 0.17272 -0.18923)
						(xy 0.17907 -0.18034) (xy 0.18669 -0.17145) (xy 0.19177 -0.16256) (xy 0.19812 -0.15367) (xy 0.20828 -0.13335)
						(xy 0.21971 -0.10287) (xy 0.22225 -0.09271) (xy 0.22479 -0.08128) (xy 0.22606 -0.07112) (xy 0.2286 -0.05969)
						(xy 0.2286 -0.01651) (xy 0.22606 -0.00508) (xy 0.22479 0.00508) (xy 0.22225 0.01651) (xy 0.21971 0.02667)
						(xy 0.20828 0.05715) (xy 0.19812 0.07747) (xy 0.19177 0.08636) (xy 0.18669 0.09525) (xy 0.17907 0.10414)
						(xy 0.17272 0.11303) (xy 0.1651 0.12065) (xy 0.1651 0.7366) (xy 0.16256 0.76835) (xy 0.1524 0.8001)
						(xy 0.13716 0.82804) (xy 0.11684 0.85344) (xy 0.09144 0.87376) (xy 0.0635 0.889) (xy 0.03175 0.89916)
					)
					(width 0)
					(fill yes)
				)
			)
		)
		(pad "36" smd custom
			(at -21.150072 -4.106672)
			(size 0.1143 0.1143)
			(layers "F.Cu" "F.Mask" "F.Paste")
			(net "M_B_DQ11")
			(options
				(clearance outline)
				(anchor circle)
			)
			(primitives
				(gr_poly
					(pts
						(xy 0 0.9017) (xy -0.03175 0.89916) (xy -0.0635 0.889) (xy -0.09144 0.87376) (xy -0.11684 0.85344)
						(xy -0.13716 0.82804) (xy -0.1524 0.8001) (xy -0.16256 0.76835) (xy -0.1651 0.7366) (xy -0.1651 0.19685)
						(xy -0.17272 0.18923) (xy -0.17907 0.18034) (xy -0.18669 0.17145) (xy -0.19177 0.16256) (xy -0.19812 0.15367)
						(xy -0.20828 0.13335) (xy -0.21971 0.10287) (xy -0.22225 0.09271) (xy -0.22479 0.08128) (xy -0.22606 0.07112)
						(xy -0.2286 0.05969) (xy -0.2286 0.01651) (xy -0.22606 0.00508) (xy -0.22479 -0.00508) (xy -0.22225 -0.01651)
						(xy -0.21971 -0.02667) (xy -0.20828 -0.05715) (xy -0.19812 -0.07747) (xy -0.19177 -0.08636) (xy -0.18669 -0.09525)
						(xy -0.17907 -0.10414) (xy -0.17272 -0.11303) (xy -0.1651 -0.12065) (xy -0.1651 -0.7366) (xy -0.16256 -0.76835)
						(xy -0.1524 -0.8001) (xy -0.13716 -0.82804) (xy -0.11684 -0.85344) (xy -0.09144 -0.87376) (xy -0.0635 -0.889)
						(xy -0.03175 -0.89916) (xy 0 -0.9017) (xy 0.03175 -0.89916) (xy 0.0635 -0.889) (xy 0.09144 -0.87376)
						(xy 0.11684 -0.85344) (xy 0.13716 -0.82804) (xy 0.1524 -0.8001) (xy 0.16256 -0.76835) (xy 0.1651 -0.7366)
						(xy 0.1651 -0.11938) (xy 0.17272 -0.11176) (xy 0.19812 -0.0762) (xy 0.2032 -0.06604) (xy 0.20701 -0.05715)
						(xy 0.21209 -0.04699) (xy 0.2159 -0.03683) (xy 0.21844 -0.02667) (xy 0.22225 -0.01524) (xy 0.22352 -0.00508)
						(xy 0.22606 0.00508) (xy 0.22733 0.01651) (xy 0.22733 0.02667) (xy 0.2286 0.0381) (xy 0.22733 0.04953)
						(xy 0.22733 0.05969) (xy 0.22606 0.07112) (xy 0.22352 0.08128) (xy 0.22225 0.09144) (xy 0.21844 0.10287)
						(xy 0.2159 0.11303) (xy 0.21209 0.12319) (xy 0.20701 0.13335) (xy 0.2032 0.14224) (xy 0.19812 0.1524)
						(xy 0.17272 0.18796) (xy 0.1651 0.19558) (xy 0.1651 0.7366) (xy 0.16256 0.76835) (xy 0.1524 0.8001)
						(xy 0.13716 0.82804) (xy 0.11684 0.85344) (xy 0.09144 0.87376) (xy 0.0635 0.889) (xy 0.03175 0.89916)
					)
					(width 0)
					(fill yes)
				)
			)
		)
		(pad "37" smd custom
			(at -20.850098 4.106672)
			(size 0.1143 0.1143)
			(layers "F.Cu" "F.Mask" "F.Paste")
			(net "M_B_DQ20")
			(options
				(clearance outline)
				(anchor circle)
			)
			(primitives
				(gr_poly
					(pts
						(xy 0 0.9017) (xy -0.03175 0.89916) (xy -0.0635 0.889) (xy -0.09144 0.87376) (xy -0.11684 0.85344)
						(xy -0.13716 0.82804) (xy -0.1524 0.8001) (xy -0.16256 0.76835) (xy -0.1651 0.7366) (xy -0.1651 -0.13462)
						(xy -0.17272 -0.14224) (xy -0.19812 -0.1778) (xy -0.2032 -0.18796) (xy -0.20701 -0.19685) (xy -0.21209 -0.20701)
						(xy -0.2159 -0.21717) (xy -0.21844 -0.22733) (xy -0.22225 -0.23876) (xy -0.22352 -0.24892) (xy -0.22606 -0.25908)
						(xy -0.22733 -0.27051) (xy -0.22733 -0.28067) (xy -0.2286 -0.2921) (xy -0.22733 -0.30353) (xy -0.22733 -0.31369)
						(xy -0.22606 -0.32512) (xy -0.22352 -0.33528) (xy -0.22225 -0.34544) (xy -0.21844 -0.35687) (xy -0.2159 -0.36703)
						(xy -0.21209 -0.37719) (xy -0.20701 -0.38735) (xy -0.2032 -0.39624) (xy -0.19812 -0.4064) (xy -0.17272 -0.44196)
						(xy -0.1651 -0.44958) (xy -0.1651 -0.7366) (xy -0.16256 -0.76835) (xy -0.1524 -0.8001) (xy -0.13716 -0.82804)
						(xy -0.11684 -0.85344) (xy -0.09144 -0.87376) (xy -0.0635 -0.889) (xy -0.03175 -0.89916) (xy 0 -0.9017)
						(xy 0.03175 -0.89916) (xy 0.0635 -0.889) (xy 0.09144 -0.87376) (xy 0.11684 -0.85344) (xy 0.13716 -0.82804)
						(xy 0.1524 -0.8001) (xy 0.16256 -0.76835) (xy 0.1651 -0.7366) (xy 0.1651 -0.44958) (xy 0.17272 -0.44196)
						(xy 0.19812 -0.4064) (xy 0.2032 -0.39624) (xy 0.20701 -0.38735) (xy 0.21209 -0.37719) (xy 0.2159 -0.36703)
						(xy 0.21844 -0.35687) (xy 0.22225 -0.34544) (xy 0.22352 -0.33528) (xy 0.22606 -0.32512) (xy 0.22733 -0.31369)
						(xy 0.22733 -0.30353) (xy 0.2286 -0.2921) (xy 0.22733 -0.28067) (xy 0.22733 -0.27051) (xy 0.22606 -0.25908)
						(xy 0.22352 -0.24892) (xy 0.22225 -0.23876) (xy 0.21844 -0.22733) (xy 0.2159 -0.21717) (xy 0.21209 -0.20701)
						(xy 0.20701 -0.19685) (xy 0.2032 -0.18796) (xy 0.19812 -0.1778) (xy 0.17272 -0.14224) (xy 0.1651 -0.13462)
						(xy 0.1651 0.7366) (xy 0.16256 0.76835) (xy 0.1524 0.8001) (xy 0.13716 0.82804) (xy 0.11684 0.85344)
						(xy 0.09144 0.87376) (xy 0.0635 0.889) (xy 0.03175 0.89916)
					)
					(width 0)
					(fill yes)
				)
			)
		)
		(pad "38" smd custom
			(at -20.550124 -4.106672)
			(size 0.1143 0.1143)
			(layers "F.Cu" "F.Mask" "F.Paste")
			(net "GND")
			(options
				(clearance outline)
				(anchor circle)
			)
			(primitives
				(gr_poly
					(pts
						(xy 0 0.9017) (xy -0.03175 0.89916) (xy -0.0635 0.889) (xy -0.09144 0.87376) (xy -0.11684 0.85344)
						(xy -0.13716 0.82804) (xy -0.1524 0.8001) (xy -0.16256 0.76835) (xy -0.1651 0.7366) (xy -0.1651 0.44958)
						(xy -0.17272 0.44196) (xy -0.19812 0.4064) (xy -0.2032 0.39624) (xy -0.20701 0.38735) (xy -0.21209 0.37719)
						(xy -0.2159 0.36703) (xy -0.21844 0.35687) (xy -0.22225 0.34544) (xy -0.22352 0.33528) (xy -0.22606 0.32512)
						(xy -0.22733 0.31369) (xy -0.22733 0.30353) (xy -0.2286 0.2921) (xy -0.22733 0.28067) (xy -0.22733 0.27051)
						(xy -0.22606 0.25908) (xy -0.22352 0.24892) (xy -0.22225 0.23876) (xy -0.21844 0.22733) (xy -0.2159 0.21717)
						(xy -0.21209 0.20701) (xy -0.20701 0.19685) (xy -0.2032 0.18796) (xy -0.19812 0.1778) (xy -0.17272 0.14224)
						(xy -0.1651 0.13462) (xy -0.1651 -0.7366) (xy -0.16256 -0.76835) (xy -0.1524 -0.8001) (xy -0.13716 -0.82804)
						(xy -0.11684 -0.85344) (xy -0.09144 -0.87376) (xy -0.0635 -0.889) (xy -0.03175 -0.89916) (xy 0 -0.9017)
						(xy 0.03175 -0.89916) (xy 0.0635 -0.889) (xy 0.09144 -0.87376) (xy 0.11684 -0.85344) (xy 0.13716 -0.82804)
						(xy 0.1524 -0.8001) (xy 0.16256 -0.76835) (xy 0.1651 -0.7366) (xy 0.1651 0.13462) (xy 0.17272 0.14224)
						(xy 0.19812 0.1778) (xy 0.2032 0.18796) (xy 0.20701 0.19685) (xy 0.21209 0.20701) (xy 0.2159 0.21717)
						(xy 0.21844 0.22733) (xy 0.22225 0.23876) (xy 0.22352 0.24892) (xy 0.22606 0.25908) (xy 0.22733 0.27051)
						(xy 0.22733 0.28067) (xy 0.2286 0.2921) (xy 0.22733 0.30353) (xy 0.22733 0.31369) (xy 0.22606 0.32512)
						(xy 0.22352 0.33528) (xy 0.22225 0.34544) (xy 0.21844 0.35687) (xy 0.2159 0.36703) (xy 0.21209 0.37719)
						(xy 0.20701 0.38735) (xy 0.2032 0.39624) (xy 0.19812 0.4064) (xy 0.17272 0.44196) (xy 0.1651 0.44958)
						(xy 0.1651 0.7366) (xy 0.16256 0.76835) (xy 0.1524 0.8001) (xy 0.13716 0.82804) (xy 0.11684 0.85344)
						(xy 0.09144 0.87376) (xy 0.0635 0.889) (xy 0.03175 0.89916)
					)
					(width 0)
					(fill yes)
				)
			)
		)
		(pad "39" smd custom
			(at -20.249896 4.106672)
			(size 0.1143 0.1143)
			(layers "F.Cu" "F.Mask" "F.Paste")
			(net "M_B_DQ21")
			(options
				(clearance outline)
				(anchor circle)
			)
			(primitives
				(gr_poly
					(pts
						(xy 0 0.9017) (xy -0.03175 0.89916) (xy -0.0635 0.889) (xy -0.09144 0.87376) (xy -0.11684 0.85344)
						(xy -0.13716 0.82804) (xy -0.1524 0.8001) (xy -0.16256 0.76835) (xy -0.1651 0.7366) (xy -0.1651 0.11938)
						(xy -0.17272 0.11176) (xy -0.19812 0.0762) (xy -0.2032 0.06604) (xy -0.20701 0.05715) (xy -0.21209 0.04699)
						(xy -0.2159 0.03683) (xy -0.21844 0.02667) (xy -0.22225 0.01524) (xy -0.22352 0.00508) (xy -0.22606 -0.00508)
						(xy -0.22733 -0.01651) (xy -0.22733 -0.02667) (xy -0.2286 -0.0381) (xy -0.22733 -0.04953) (xy -0.22733 -0.05969)
						(xy -0.22606 -0.07112) (xy -0.22352 -0.08128) (xy -0.22225 -0.09144) (xy -0.21844 -0.10287) (xy -0.2159 -0.11303)
						(xy -0.21209 -0.12319) (xy -0.20701 -0.13335) (xy -0.2032 -0.14224) (xy -0.19812 -0.1524) (xy -0.17272 -0.18796)
						(xy -0.1651 -0.19558) (xy -0.1651 -0.7366) (xy -0.16256 -0.76835) (xy -0.1524 -0.8001) (xy -0.13716 -0.82804)
						(xy -0.11684 -0.85344) (xy -0.09144 -0.87376) (xy -0.0635 -0.889) (xy -0.03175 -0.89916) (xy 0 -0.9017)
						(xy 0.03175 -0.89916) (xy 0.0635 -0.889) (xy 0.09144 -0.87376) (xy 0.11684 -0.85344) (xy 0.13716 -0.82804)
						(xy 0.1524 -0.8001) (xy 0.16256 -0.76835) (xy 0.1651 -0.7366) (xy 0.1651 -0.19685) (xy 0.17272 -0.18923)
						(xy 0.17907 -0.18034) (xy 0.18669 -0.17145) (xy 0.19177 -0.16256) (xy 0.19812 -0.15367) (xy 0.20828 -0.13335)
						(xy 0.21971 -0.10287) (xy 0.22225 -0.09271) (xy 0.22479 -0.08128) (xy 0.22606 -0.07112) (xy 0.2286 -0.05969)
						(xy 0.2286 -0.01651) (xy 0.22606 -0.00508) (xy 0.22479 0.00508) (xy 0.22225 0.01651) (xy 0.21971 0.02667)
						(xy 0.20828 0.05715) (xy 0.19812 0.07747) (xy 0.19177 0.08636) (xy 0.18669 0.09525) (xy 0.17907 0.10414)
						(xy 0.17272 0.11303) (xy 0.1651 0.12065) (xy 0.1651 0.7366) (xy 0.16256 0.76835) (xy 0.1524 0.8001)
						(xy 0.13716 0.82804) (xy 0.11684 0.85344) (xy 0.09144 0.87376) (xy 0.0635 0.889) (xy 0.03175 0.89916)
					)
					(width 0)
					(fill yes)
				)
			)
		)
		(pad "40" smd custom
			(at -19.949922 -4.106672)
			(size 0.1143 0.1143)
			(layers "F.Cu" "F.Mask" "F.Paste")
			(net "M_B_DQ16")
			(options
				(clearance outline)
				(anchor circle)
			)
			(primitives
				(gr_poly
					(pts
						(xy 0 0.9017) (xy -0.03175 0.89916) (xy -0.0635 0.889) (xy -0.09144 0.87376) (xy -0.11684 0.85344)
						(xy -0.13716 0.82804) (xy -0.1524 0.8001) (xy -0.16256 0.76835) (xy -0.1651 0.7366) (xy -0.1651 0.19685)
						(xy -0.17272 0.18923) (xy -0.17907 0.18034) (xy -0.18669 0.17145) (xy -0.19177 0.16256) (xy -0.19812 0.15367)
						(xy -0.20828 0.13335) (xy -0.21971 0.10287) (xy -0.22225 0.09271) (xy -0.22479 0.08128) (xy -0.22606 0.07112)
						(xy -0.2286 0.05969) (xy -0.2286 0.01651) (xy -0.22606 0.00508) (xy -0.22479 -0.00508) (xy -0.22225 -0.01651)
						(xy -0.21971 -0.02667) (xy -0.20828 -0.05715) (xy -0.19812 -0.07747) (xy -0.19177 -0.08636) (xy -0.18669 -0.09525)
						(xy -0.17907 -0.10414) (xy -0.17272 -0.11303) (xy -0.1651 -0.12065) (xy -0.1651 -0.7366) (xy -0.16256 -0.76835)
						(xy -0.1524 -0.8001) (xy -0.13716 -0.82804) (xy -0.11684 -0.85344) (xy -0.09144 -0.87376) (xy -0.0635 -0.889)
						(xy -0.03175 -0.89916) (xy 0 -0.9017) (xy 0.03175 -0.89916) (xy 0.0635 -0.889) (xy 0.09144 -0.87376)
						(xy 0.11684 -0.85344) (xy 0.13716 -0.82804) (xy 0.1524 -0.8001) (xy 0.16256 -0.76835) (xy 0.1651 -0.7366)
						(xy 0.1651 -0.11938) (xy 0.17272 -0.11176) (xy 0.19812 -0.0762) (xy 0.2032 -0.06604) (xy 0.20701 -0.05715)
						(xy 0.21209 -0.04699) (xy 0.2159 -0.03683) (xy 0.21844 -0.02667) (xy 0.22225 -0.01524) (xy 0.22352 -0.00508)
						(xy 0.22606 0.00508) (xy 0.22733 0.01651) (xy 0.22733 0.02667) (xy 0.2286 0.0381) (xy 0.22733 0.04953)
						(xy 0.22733 0.05969) (xy 0.22606 0.07112) (xy 0.22352 0.08128) (xy 0.22225 0.09144) (xy 0.21844 0.10287)
						(xy 0.2159 0.11303) (xy 0.21209 0.12319) (xy 0.20701 0.13335) (xy 0.2032 0.14224) (xy 0.19812 0.1524)
						(xy 0.17272 0.18796) (xy 0.1651 0.19558) (xy 0.1651 0.7366) (xy 0.16256 0.76835) (xy 0.1524 0.8001)
						(xy 0.13716 0.82804) (xy 0.11684 0.85344) (xy 0.09144 0.87376) (xy 0.0635 0.889) (xy 0.03175 0.89916)
					)
					(width 0)
					(fill yes)
				)
			)
		)
		(pad "41" smd custom
			(at -19.649948 4.106672)
			(size 0.1143 0.1143)
			(layers "F.Cu" "F.Mask" "F.Paste")
			(net "GND")
			(options
				(clearance outline)
				(anchor circle)
			)
			(primitives
				(gr_poly
					(pts
						(xy 0 0.9017) (xy -0.03175 0.89916) (xy -0.0635 0.889) (xy -0.09144 0.87376) (xy -0.11684 0.85344)
						(xy -0.13716 0.82804) (xy -0.1524 0.8001) (xy -0.16256 0.76835) (xy -0.1651 0.7366) (xy -0.1651 -0.13462)
						(xy -0.17272 -0.14224) (xy -0.19812 -0.1778) (xy -0.2032 -0.18796) (xy -0.20701 -0.19685) (xy -0.21209 -0.20701)
						(xy -0.2159 -0.21717) (xy -0.21844 -0.22733) (xy -0.22225 -0.23876) (xy -0.22352 -0.24892) (xy -0.22606 -0.25908)
						(xy -0.22733 -0.27051) (xy -0.22733 -0.28067) (xy -0.2286 -0.2921) (xy -0.22733 -0.30353) (xy -0.22733 -0.31369)
						(xy -0.22606 -0.32512) (xy -0.22352 -0.33528) (xy -0.22225 -0.34544) (xy -0.21844 -0.35687) (xy -0.2159 -0.36703)
						(xy -0.21209 -0.37719) (xy -0.20701 -0.38735) (xy -0.2032 -0.39624) (xy -0.19812 -0.4064) (xy -0.17272 -0.44196)
						(xy -0.1651 -0.44958) (xy -0.1651 -0.7366) (xy -0.16256 -0.76835) (xy -0.1524 -0.8001) (xy -0.13716 -0.82804)
						(xy -0.11684 -0.85344) (xy -0.09144 -0.87376) (xy -0.0635 -0.889) (xy -0.03175 -0.89916) (xy 0 -0.9017)
						(xy 0.03175 -0.89916) (xy 0.0635 -0.889) (xy 0.09144 -0.87376) (xy 0.11684 -0.85344) (xy 0.13716 -0.82804)
						(xy 0.1524 -0.8001) (xy 0.16256 -0.76835) (xy 0.1651 -0.7366) (xy 0.1651 -0.44958) (xy 0.17272 -0.44196)
						(xy 0.19812 -0.4064) (xy 0.2032 -0.39624) (xy 0.20701 -0.38735) (xy 0.21209 -0.37719) (xy 0.2159 -0.36703)
						(xy 0.21844 -0.35687) (xy 0.22225 -0.34544) (xy 0.22352 -0.33528) (xy 0.22606 -0.32512) (xy 0.22733 -0.31369)
						(xy 0.22733 -0.30353) (xy 0.2286 -0.2921) (xy 0.22733 -0.28067) (xy 0.22733 -0.27051) (xy 0.22606 -0.25908)
						(xy 0.22352 -0.24892) (xy 0.22225 -0.23876) (xy 0.21844 -0.22733) (xy 0.2159 -0.21717) (xy 0.21209 -0.20701)
						(xy 0.20701 -0.19685) (xy 0.2032 -0.18796) (xy 0.19812 -0.1778) (xy 0.17272 -0.14224) (xy 0.1651 -0.13462)
						(xy 0.1651 0.7366) (xy 0.16256 0.76835) (xy 0.1524 0.8001) (xy 0.13716 0.82804) (xy 0.11684 0.85344)
						(xy 0.09144 0.87376) (xy 0.0635 0.889) (xy 0.03175 0.89916)
					)
					(width 0)
					(fill yes)
				)
			)
		)
		(pad "42" smd custom
			(at -19.349974 -4.106672)
			(size 0.1143 0.1143)
			(layers "F.Cu" "F.Mask" "F.Paste")
			(net "M_B_DQ17")
			(options
				(clearance outline)
				(anchor circle)
			)
			(primitives
				(gr_poly
					(pts
						(xy 0 0.9017) (xy -0.03175 0.89916) (xy -0.0635 0.889) (xy -0.09144 0.87376) (xy -0.11684 0.85344)
						(xy -0.13716 0.82804) (xy -0.1524 0.8001) (xy -0.16256 0.76835) (xy -0.1651 0.7366) (xy -0.1651 0.44958)
						(xy -0.17272 0.44196) (xy -0.19812 0.4064) (xy -0.2032 0.39624) (xy -0.20701 0.38735) (xy -0.21209 0.37719)
						(xy -0.2159 0.36703) (xy -0.21844 0.35687) (xy -0.22225 0.34544) (xy -0.22352 0.33528) (xy -0.22606 0.32512)
						(xy -0.22733 0.31369) (xy -0.22733 0.30353) (xy -0.2286 0.2921) (xy -0.22733 0.28067) (xy -0.22733 0.27051)
						(xy -0.22606 0.25908) (xy -0.22352 0.24892) (xy -0.22225 0.23876) (xy -0.21844 0.22733) (xy -0.2159 0.21717)
						(xy -0.21209 0.20701) (xy -0.20701 0.19685) (xy -0.2032 0.18796) (xy -0.19812 0.1778) (xy -0.17272 0.14224)
						(xy -0.1651 0.13462) (xy -0.1651 -0.7366) (xy -0.16256 -0.76835) (xy -0.1524 -0.8001) (xy -0.13716 -0.82804)
						(xy -0.11684 -0.85344) (xy -0.09144 -0.87376) (xy -0.0635 -0.889) (xy -0.03175 -0.89916) (xy 0 -0.9017)
						(xy 0.03175 -0.89916) (xy 0.0635 -0.889) (xy 0.09144 -0.87376) (xy 0.11684 -0.85344) (xy 0.13716 -0.82804)
						(xy 0.1524 -0.8001) (xy 0.16256 -0.76835) (xy 0.1651 -0.7366) (xy 0.1651 0.13462) (xy 0.17272 0.14224)
						(xy 0.19812 0.1778) (xy 0.2032 0.18796) (xy 0.20701 0.19685) (xy 0.21209 0.20701) (xy 0.2159 0.21717)
						(xy 0.21844 0.22733) (xy 0.22225 0.23876) (xy 0.22352 0.24892) (xy 0.22606 0.25908) (xy 0.22733 0.27051)
						(xy 0.22733 0.28067) (xy 0.2286 0.2921) (xy 0.22733 0.30353) (xy 0.22733 0.31369) (xy 0.22606 0.32512)
						(xy 0.22352 0.33528) (xy 0.22225 0.34544) (xy 0.21844 0.35687) (xy 0.2159 0.36703) (xy 0.21209 0.37719)
						(xy 0.20701 0.38735) (xy 0.2032 0.39624) (xy 0.19812 0.4064) (xy 0.17272 0.44196) (xy 0.1651 0.44958)
						(xy 0.1651 0.7366) (xy 0.16256 0.76835) (xy 0.1524 0.8001) (xy 0.13716 0.82804) (xy 0.11684 0.85344)
						(xy 0.09144 0.87376) (xy 0.0635 0.889) (xy 0.03175 0.89916)
					)
					(width 0)
					(fill yes)
				)
			)
		)
		(pad "43" smd custom
			(at -19.05 4.106672)
			(size 0.1143 0.1143)
			(layers "F.Cu" "F.Mask" "F.Paste")
			(net "M_B_DQS_DN2")
			(options
				(clearance outline)
				(anchor circle)
			)
			(primitives
				(gr_poly
					(pts
						(xy 0 0.9017) (xy -0.03175 0.89916) (xy -0.0635 0.889) (xy -0.09144 0.87376) (xy -0.11684 0.85344)
						(xy -0.13716 0.82804) (xy -0.1524 0.8001) (xy -0.16256 0.76835) (xy -0.1651 0.7366) (xy -0.1651 0.11938)
						(xy -0.17272 0.11176) (xy -0.19812 0.0762) (xy -0.2032 0.06604) (xy -0.20701 0.05715) (xy -0.21209 0.04699)
						(xy -0.2159 0.03683) (xy -0.21844 0.02667) (xy -0.22225 0.01524) (xy -0.22352 0.00508) (xy -0.22606 -0.00508)
						(xy -0.22733 -0.01651) (xy -0.22733 -0.02667) (xy -0.2286 -0.0381) (xy -0.22733 -0.04953) (xy -0.22733 -0.05969)
						(xy -0.22606 -0.07112) (xy -0.22352 -0.08128) (xy -0.22225 -0.09144) (xy -0.21844 -0.10287) (xy -0.2159 -0.11303)
						(xy -0.21209 -0.12319) (xy -0.20701 -0.13335) (xy -0.2032 -0.14224) (xy -0.19812 -0.1524) (xy -0.17272 -0.18796)
						(xy -0.1651 -0.19558) (xy -0.1651 -0.7366) (xy -0.16256 -0.76835) (xy -0.1524 -0.8001) (xy -0.13716 -0.82804)
						(xy -0.11684 -0.85344) (xy -0.09144 -0.87376) (xy -0.0635 -0.889) (xy -0.03175 -0.89916) (xy 0 -0.9017)
						(xy 0.03175 -0.89916) (xy 0.0635 -0.889) (xy 0.09144 -0.87376) (xy 0.11684 -0.85344) (xy 0.13716 -0.82804)
						(xy 0.1524 -0.8001) (xy 0.16256 -0.76835) (xy 0.1651 -0.7366) (xy 0.1651 -0.19685) (xy 0.17272 -0.18923)
						(xy 0.17907 -0.18034) (xy 0.18669 -0.17145) (xy 0.19177 -0.16256) (xy 0.19812 -0.15367) (xy 0.20828 -0.13335)
						(xy 0.21971 -0.10287) (xy 0.22225 -0.09271) (xy 0.22479 -0.08128) (xy 0.22606 -0.07112) (xy 0.2286 -0.05969)
						(xy 0.2286 -0.01651) (xy 0.22606 -0.00508) (xy 0.22479 0.00508) (xy 0.22225 0.01651) (xy 0.21971 0.02667)
						(xy 0.20828 0.05715) (xy 0.19812 0.07747) (xy 0.19177 0.08636) (xy 0.18669 0.09525) (xy 0.17907 0.10414)
						(xy 0.17272 0.11303) (xy 0.1651 0.12065) (xy 0.1651 0.7366) (xy 0.16256 0.76835) (xy 0.1524 0.8001)
						(xy 0.13716 0.82804) (xy 0.11684 0.85344) (xy 0.09144 0.87376) (xy 0.0635 0.889) (xy 0.03175 0.89916)
					)
					(width 0)
					(fill yes)
				)
			)
		)
		(pad "44" smd custom
			(at -18.750026 -4.106672)
			(size 0.1143 0.1143)
			(layers "F.Cu" "F.Mask" "F.Paste")
			(net "GND")
			(options
				(clearance outline)
				(anchor circle)
			)
			(primitives
				(gr_poly
					(pts
						(xy 0 0.9017) (xy -0.03175 0.89916) (xy -0.0635 0.889) (xy -0.09144 0.87376) (xy -0.11684 0.85344)
						(xy -0.13716 0.82804) (xy -0.1524 0.8001) (xy -0.16256 0.76835) (xy -0.1651 0.7366) (xy -0.1651 0.19685)
						(xy -0.17272 0.18923) (xy -0.17907 0.18034) (xy -0.18669 0.17145) (xy -0.19177 0.16256) (xy -0.19812 0.15367)
						(xy -0.20828 0.13335) (xy -0.21971 0.10287) (xy -0.22225 0.09271) (xy -0.22479 0.08128) (xy -0.22606 0.07112)
						(xy -0.2286 0.05969) (xy -0.2286 0.01651) (xy -0.22606 0.00508) (xy -0.22479 -0.00508) (xy -0.22225 -0.01651)
						(xy -0.21971 -0.02667) (xy -0.20828 -0.05715) (xy -0.19812 -0.07747) (xy -0.19177 -0.08636) (xy -0.18669 -0.09525)
						(xy -0.17907 -0.10414) (xy -0.17272 -0.11303) (xy -0.1651 -0.12065) (xy -0.1651 -0.7366) (xy -0.16256 -0.76835)
						(xy -0.1524 -0.8001) (xy -0.13716 -0.82804) (xy -0.11684 -0.85344) (xy -0.09144 -0.87376) (xy -0.0635 -0.889)
						(xy -0.03175 -0.89916) (xy 0 -0.9017) (xy 0.03175 -0.89916) (xy 0.0635 -0.889) (xy 0.09144 -0.87376)
						(xy 0.11684 -0.85344) (xy 0.13716 -0.82804) (xy 0.1524 -0.8001) (xy 0.16256 -0.76835) (xy 0.1651 -0.7366)
						(xy 0.1651 -0.11938) (xy 0.17272 -0.11176) (xy 0.19812 -0.0762) (xy 0.2032 -0.06604) (xy 0.20701 -0.05715)
						(xy 0.21209 -0.04699) (xy 0.2159 -0.03683) (xy 0.21844 -0.02667) (xy 0.22225 -0.01524) (xy 0.22352 -0.00508)
						(xy 0.22606 0.00508) (xy 0.22733 0.01651) (xy 0.22733 0.02667) (xy 0.2286 0.0381) (xy 0.22733 0.04953)
						(xy 0.22733 0.05969) (xy 0.22606 0.07112) (xy 0.22352 0.08128) (xy 0.22225 0.09144) (xy 0.21844 0.10287)
						(xy 0.2159 0.11303) (xy 0.21209 0.12319) (xy 0.20701 0.13335) (xy 0.2032 0.14224) (xy 0.19812 0.1524)
						(xy 0.17272 0.18796) (xy 0.1651 0.19558) (xy 0.1651 0.7366) (xy 0.16256 0.76835) (xy 0.1524 0.8001)
						(xy 0.13716 0.82804) (xy 0.11684 0.85344) (xy 0.09144 0.87376) (xy 0.0635 0.889) (xy 0.03175 0.89916)
					)
					(width 0)
					(fill yes)
				)
			)
		)
		(pad "45" smd custom
			(at -18.450052 4.106672)
			(size 0.1143 0.1143)
			(layers "F.Cu" "F.Mask" "F.Paste")
			(net "M_B_DQS_DP2")
			(options
				(clearance outline)
				(anchor circle)
			)
			(primitives
				(gr_poly
					(pts
						(xy 0 0.9017) (xy -0.03175 0.89916) (xy -0.0635 0.889) (xy -0.09144 0.87376) (xy -0.11684 0.85344)
						(xy -0.13716 0.82804) (xy -0.1524 0.8001) (xy -0.16256 0.76835) (xy -0.1651 0.7366) (xy -0.1651 -0.13462)
						(xy -0.17272 -0.14224) (xy -0.19812 -0.1778) (xy -0.2032 -0.18796) (xy -0.20701 -0.19685) (xy -0.21209 -0.20701)
						(xy -0.2159 -0.21717) (xy -0.21844 -0.22733) (xy -0.22225 -0.23876) (xy -0.22352 -0.24892) (xy -0.22606 -0.25908)
						(xy -0.22733 -0.27051) (xy -0.22733 -0.28067) (xy -0.2286 -0.2921) (xy -0.22733 -0.30353) (xy -0.22733 -0.31369)
						(xy -0.22606 -0.32512) (xy -0.22352 -0.33528) (xy -0.22225 -0.34544) (xy -0.21844 -0.35687) (xy -0.2159 -0.36703)
						(xy -0.21209 -0.37719) (xy -0.20701 -0.38735) (xy -0.2032 -0.39624) (xy -0.19812 -0.4064) (xy -0.17272 -0.44196)
						(xy -0.1651 -0.44958) (xy -0.1651 -0.7366) (xy -0.16256 -0.76835) (xy -0.1524 -0.8001) (xy -0.13716 -0.82804)
						(xy -0.11684 -0.85344) (xy -0.09144 -0.87376) (xy -0.0635 -0.889) (xy -0.03175 -0.89916) (xy 0 -0.9017)
						(xy 0.03175 -0.89916) (xy 0.0635 -0.889) (xy 0.09144 -0.87376) (xy 0.11684 -0.85344) (xy 0.13716 -0.82804)
						(xy 0.1524 -0.8001) (xy 0.16256 -0.76835) (xy 0.1651 -0.7366) (xy 0.1651 -0.44958) (xy 0.17272 -0.44196)
						(xy 0.19812 -0.4064) (xy 0.2032 -0.39624) (xy 0.20701 -0.38735) (xy 0.21209 -0.37719) (xy 0.2159 -0.36703)
						(xy 0.21844 -0.35687) (xy 0.22225 -0.34544) (xy 0.22352 -0.33528) (xy 0.22606 -0.32512) (xy 0.22733 -0.31369)
						(xy 0.22733 -0.30353) (xy 0.2286 -0.2921) (xy 0.22733 -0.28067) (xy 0.22733 -0.27051) (xy 0.22606 -0.25908)
						(xy 0.22352 -0.24892) (xy 0.22225 -0.23876) (xy 0.21844 -0.22733) (xy 0.2159 -0.21717) (xy 0.21209 -0.20701)
						(xy 0.20701 -0.19685) (xy 0.2032 -0.18796) (xy 0.19812 -0.1778) (xy 0.17272 -0.14224) (xy 0.1651 -0.13462)
						(xy 0.1651 0.7366) (xy 0.16256 0.76835) (xy 0.1524 0.8001) (xy 0.13716 0.82804) (xy 0.11684 0.85344)
						(xy 0.09144 0.87376) (xy 0.0635 0.889) (xy 0.03175 0.89916)
					)
					(width 0)
					(fill yes)
				)
			)
		)
		(pad "46" smd custom
			(at -18.150078 -4.106672)
			(size 0.1143 0.1143)
			(layers "F.Cu" "F.Mask" "F.Paste")
			(net "GND")
			(options
				(clearance outline)
				(anchor circle)
			)
			(primitives
				(gr_poly
					(pts
						(xy 0 0.9017) (xy -0.03175 0.89916) (xy -0.0635 0.889) (xy -0.09144 0.87376) (xy -0.11684 0.85344)
						(xy -0.13716 0.82804) (xy -0.1524 0.8001) (xy -0.16256 0.76835) (xy -0.1651 0.7366) (xy -0.1651 0.44958)
						(xy -0.17272 0.44196) (xy -0.19812 0.4064) (xy -0.2032 0.39624) (xy -0.20701 0.38735) (xy -0.21209 0.37719)
						(xy -0.2159 0.36703) (xy -0.21844 0.35687) (xy -0.22225 0.34544) (xy -0.22352 0.33528) (xy -0.22606 0.32512)
						(xy -0.22733 0.31369) (xy -0.22733 0.30353) (xy -0.2286 0.2921) (xy -0.22733 0.28067) (xy -0.22733 0.27051)
						(xy -0.22606 0.25908) (xy -0.22352 0.24892) (xy -0.22225 0.23876) (xy -0.21844 0.22733) (xy -0.2159 0.21717)
						(xy -0.21209 0.20701) (xy -0.20701 0.19685) (xy -0.2032 0.18796) (xy -0.19812 0.1778) (xy -0.17272 0.14224)
						(xy -0.1651 0.13462) (xy -0.1651 -0.7366) (xy -0.16256 -0.76835) (xy -0.1524 -0.8001) (xy -0.13716 -0.82804)
						(xy -0.11684 -0.85344) (xy -0.09144 -0.87376) (xy -0.0635 -0.889) (xy -0.03175 -0.89916) (xy 0 -0.9017)
						(xy 0.03175 -0.89916) (xy 0.0635 -0.889) (xy 0.09144 -0.87376) (xy 0.11684 -0.85344) (xy 0.13716 -0.82804)
						(xy 0.1524 -0.8001) (xy 0.16256 -0.76835) (xy 0.1651 -0.7366) (xy 0.1651 0.13462) (xy 0.17272 0.14224)
						(xy 0.19812 0.1778) (xy 0.2032 0.18796) (xy 0.20701 0.19685) (xy 0.21209 0.20701) (xy 0.2159 0.21717)
						(xy 0.21844 0.22733) (xy 0.22225 0.23876) (xy 0.22352 0.24892) (xy 0.22606 0.25908) (xy 0.22733 0.27051)
						(xy 0.22733 0.28067) (xy 0.2286 0.2921) (xy 0.22733 0.30353) (xy 0.22733 0.31369) (xy 0.22606 0.32512)
						(xy 0.22352 0.33528) (xy 0.22225 0.34544) (xy 0.21844 0.35687) (xy 0.2159 0.36703) (xy 0.21209 0.37719)
						(xy 0.20701 0.38735) (xy 0.2032 0.39624) (xy 0.19812 0.4064) (xy 0.17272 0.44196) (xy 0.1651 0.44958)
						(xy 0.1651 0.7366) (xy 0.16256 0.76835) (xy 0.1524 0.8001) (xy 0.13716 0.82804) (xy 0.11684 0.85344)
						(xy 0.09144 0.87376) (xy 0.0635 0.889) (xy 0.03175 0.89916)
					)
					(width 0)
					(fill yes)
				)
			)
		)
		(pad "47" smd custom
			(at -17.850104 4.106672)
			(size 0.1143 0.1143)
			(layers "F.Cu" "F.Mask" "F.Paste")
			(net "GND")
			(options
				(clearance outline)
				(anchor circle)
			)
			(primitives
				(gr_poly
					(pts
						(xy 0 0.9017) (xy -0.03175 0.89916) (xy -0.0635 0.889) (xy -0.09144 0.87376) (xy -0.11684 0.85344)
						(xy -0.13716 0.82804) (xy -0.1524 0.8001) (xy -0.16256 0.76835) (xy -0.1651 0.7366) (xy -0.1651 0.11938)
						(xy -0.17272 0.11176) (xy -0.19812 0.0762) (xy -0.2032 0.06604) (xy -0.20701 0.05715) (xy -0.21209 0.04699)
						(xy -0.2159 0.03683) (xy -0.21844 0.02667) (xy -0.22225 0.01524) (xy -0.22352 0.00508) (xy -0.22606 -0.00508)
						(xy -0.22733 -0.01651) (xy -0.22733 -0.02667) (xy -0.2286 -0.0381) (xy -0.22733 -0.04953) (xy -0.22733 -0.05969)
						(xy -0.22606 -0.07112) (xy -0.22352 -0.08128) (xy -0.22225 -0.09144) (xy -0.21844 -0.10287) (xy -0.2159 -0.11303)
						(xy -0.21209 -0.12319) (xy -0.20701 -0.13335) (xy -0.2032 -0.14224) (xy -0.19812 -0.1524) (xy -0.17272 -0.18796)
						(xy -0.1651 -0.19558) (xy -0.1651 -0.7366) (xy -0.16256 -0.76835) (xy -0.1524 -0.8001) (xy -0.13716 -0.82804)
						(xy -0.11684 -0.85344) (xy -0.09144 -0.87376) (xy -0.0635 -0.889) (xy -0.03175 -0.89916) (xy 0 -0.9017)
						(xy 0.03175 -0.89916) (xy 0.0635 -0.889) (xy 0.09144 -0.87376) (xy 0.11684 -0.85344) (xy 0.13716 -0.82804)
						(xy 0.1524 -0.8001) (xy 0.16256 -0.76835) (xy 0.1651 -0.7366) (xy 0.1651 -0.19685) (xy 0.17272 -0.18923)
						(xy 0.17907 -0.18034) (xy 0.18669 -0.17145) (xy 0.19177 -0.16256) (xy 0.19812 -0.15367) (xy 0.20828 -0.13335)
						(xy 0.21971 -0.10287) (xy 0.22225 -0.09271) (xy 0.22479 -0.08128) (xy 0.22606 -0.07112) (xy 0.2286 -0.05969)
						(xy 0.2286 -0.01651) (xy 0.22606 -0.00508) (xy 0.22479 0.00508) (xy 0.22225 0.01651) (xy 0.21971 0.02667)
						(xy 0.20828 0.05715) (xy 0.19812 0.07747) (xy 0.19177 0.08636) (xy 0.18669 0.09525) (xy 0.17907 0.10414)
						(xy 0.17272 0.11303) (xy 0.1651 0.12065) (xy 0.1651 0.7366) (xy 0.16256 0.76835) (xy 0.1524 0.8001)
						(xy 0.13716 0.82804) (xy 0.11684 0.85344) (xy 0.09144 0.87376) (xy 0.0635 0.889) (xy 0.03175 0.89916)
					)
					(width 0)
					(fill yes)
				)
			)
		)
		(pad "48" smd custom
			(at -17.549876 -4.106672)
			(size 0.1143 0.1143)
			(layers "F.Cu" "F.Mask" "F.Paste")
			(net "M_B_DQ18")
			(options
				(clearance outline)
				(anchor circle)
			)
			(primitives
				(gr_poly
					(pts
						(xy 0 0.9017) (xy -0.03175 0.89916) (xy -0.0635 0.889) (xy -0.09144 0.87376) (xy -0.11684 0.85344)
						(xy -0.13716 0.82804) (xy -0.1524 0.8001) (xy -0.16256 0.76835) (xy -0.1651 0.7366) (xy -0.1651 0.19685)
						(xy -0.17272 0.18923) (xy -0.17907 0.18034) (xy -0.18669 0.17145) (xy -0.19177 0.16256) (xy -0.19812 0.15367)
						(xy -0.20828 0.13335) (xy -0.21971 0.10287) (xy -0.22225 0.09271) (xy -0.22479 0.08128) (xy -0.22606 0.07112)
						(xy -0.2286 0.05969) (xy -0.2286 0.01651) (xy -0.22606 0.00508) (xy -0.22479 -0.00508) (xy -0.22225 -0.01651)
						(xy -0.21971 -0.02667) (xy -0.20828 -0.05715) (xy -0.19812 -0.07747) (xy -0.19177 -0.08636) (xy -0.18669 -0.09525)
						(xy -0.17907 -0.10414) (xy -0.17272 -0.11303) (xy -0.1651 -0.12065) (xy -0.1651 -0.7366) (xy -0.16256 -0.76835)
						(xy -0.1524 -0.8001) (xy -0.13716 -0.82804) (xy -0.11684 -0.85344) (xy -0.09144 -0.87376) (xy -0.0635 -0.889)
						(xy -0.03175 -0.89916) (xy 0 -0.9017) (xy 0.03175 -0.89916) (xy 0.0635 -0.889) (xy 0.09144 -0.87376)
						(xy 0.11684 -0.85344) (xy 0.13716 -0.82804) (xy 0.1524 -0.8001) (xy 0.16256 -0.76835) (xy 0.1651 -0.7366)
						(xy 0.1651 -0.11938) (xy 0.17272 -0.11176) (xy 0.19812 -0.0762) (xy 0.2032 -0.06604) (xy 0.20701 -0.05715)
						(xy 0.21209 -0.04699) (xy 0.2159 -0.03683) (xy 0.21844 -0.02667) (xy 0.22225 -0.01524) (xy 0.22352 -0.00508)
						(xy 0.22606 0.00508) (xy 0.22733 0.01651) (xy 0.22733 0.02667) (xy 0.2286 0.0381) (xy 0.22733 0.04953)
						(xy 0.22733 0.05969) (xy 0.22606 0.07112) (xy 0.22352 0.08128) (xy 0.22225 0.09144) (xy 0.21844 0.10287)
						(xy 0.2159 0.11303) (xy 0.21209 0.12319) (xy 0.20701 0.13335) (xy 0.2032 0.14224) (xy 0.19812 0.1524)
						(xy 0.17272 0.18796) (xy 0.1651 0.19558) (xy 0.1651 0.7366) (xy 0.16256 0.76835) (xy 0.1524 0.8001)
						(xy 0.13716 0.82804) (xy 0.11684 0.85344) (xy 0.09144 0.87376) (xy 0.0635 0.889) (xy 0.03175 0.89916)
					)
					(width 0)
					(fill yes)
				)
			)
		)
		(pad "49" smd custom
			(at -17.249902 4.106672)
			(size 0.1143 0.1143)
			(layers "F.Cu" "F.Mask" "F.Paste")
			(net "M_B_DQ22")
			(options
				(clearance outline)
				(anchor circle)
			)
			(primitives
				(gr_poly
					(pts
						(xy 0 0.9017) (xy -0.03175 0.89916) (xy -0.0635 0.889) (xy -0.09144 0.87376) (xy -0.11684 0.85344)
						(xy -0.13716 0.82804) (xy -0.1524 0.8001) (xy -0.16256 0.76835) (xy -0.1651 0.7366) (xy -0.1651 -0.13462)
						(xy -0.17272 -0.14224) (xy -0.19812 -0.1778) (xy -0.2032 -0.18796) (xy -0.20701 -0.19685) (xy -0.21209 -0.20701)
						(xy -0.2159 -0.21717) (xy -0.21844 -0.22733) (xy -0.22225 -0.23876) (xy -0.22352 -0.24892) (xy -0.22606 -0.25908)
						(xy -0.22733 -0.27051) (xy -0.22733 -0.28067) (xy -0.2286 -0.2921) (xy -0.22733 -0.30353) (xy -0.22733 -0.31369)
						(xy -0.22606 -0.32512) (xy -0.22352 -0.33528) (xy -0.22225 -0.34544) (xy -0.21844 -0.35687) (xy -0.2159 -0.36703)
						(xy -0.21209 -0.37719) (xy -0.20701 -0.38735) (xy -0.2032 -0.39624) (xy -0.19812 -0.4064) (xy -0.17272 -0.44196)
						(xy -0.1651 -0.44958) (xy -0.1651 -0.7366) (xy -0.16256 -0.76835) (xy -0.1524 -0.8001) (xy -0.13716 -0.82804)
						(xy -0.11684 -0.85344) (xy -0.09144 -0.87376) (xy -0.0635 -0.889) (xy -0.03175 -0.89916) (xy 0 -0.9017)
						(xy 0.03175 -0.89916) (xy 0.0635 -0.889) (xy 0.09144 -0.87376) (xy 0.11684 -0.85344) (xy 0.13716 -0.82804)
						(xy 0.1524 -0.8001) (xy 0.16256 -0.76835) (xy 0.1651 -0.7366) (xy 0.1651 -0.44958) (xy 0.17272 -0.44196)
						(xy 0.19812 -0.4064) (xy 0.2032 -0.39624) (xy 0.20701 -0.38735) (xy 0.21209 -0.37719) (xy 0.2159 -0.36703)
						(xy 0.21844 -0.35687) (xy 0.22225 -0.34544) (xy 0.22352 -0.33528) (xy 0.22606 -0.32512) (xy 0.22733 -0.31369)
						(xy 0.22733 -0.30353) (xy 0.2286 -0.2921) (xy 0.22733 -0.28067) (xy 0.22733 -0.27051) (xy 0.22606 -0.25908)
						(xy 0.22352 -0.24892) (xy 0.22225 -0.23876) (xy 0.21844 -0.22733) (xy 0.2159 -0.21717) (xy 0.21209 -0.20701)
						(xy 0.20701 -0.19685) (xy 0.2032 -0.18796) (xy 0.19812 -0.1778) (xy 0.17272 -0.14224) (xy 0.1651 -0.13462)
						(xy 0.1651 0.7366) (xy 0.16256 0.76835) (xy 0.1524 0.8001) (xy 0.13716 0.82804) (xy 0.11684 0.85344)
						(xy 0.09144 0.87376) (xy 0.0635 0.889) (xy 0.03175 0.89916)
					)
					(width 0)
					(fill yes)
				)
			)
		)
		(pad "50" smd custom
			(at -16.949928 -4.106672)
			(size 0.1143 0.1143)
			(layers "F.Cu" "F.Mask" "F.Paste")
			(net "M_B_DQ19")
			(options
				(clearance outline)
				(anchor circle)
			)
			(primitives
				(gr_poly
					(pts
						(xy 0 0.9017) (xy -0.03175 0.89916) (xy -0.0635 0.889) (xy -0.09144 0.87376) (xy -0.11684 0.85344)
						(xy -0.13716 0.82804) (xy -0.1524 0.8001) (xy -0.16256 0.76835) (xy -0.1651 0.7366) (xy -0.1651 0.44958)
						(xy -0.17272 0.44196) (xy -0.19812 0.4064) (xy -0.2032 0.39624) (xy -0.20701 0.38735) (xy -0.21209 0.37719)
						(xy -0.2159 0.36703) (xy -0.21844 0.35687) (xy -0.22225 0.34544) (xy -0.22352 0.33528) (xy -0.22606 0.32512)
						(xy -0.22733 0.31369) (xy -0.22733 0.30353) (xy -0.2286 0.2921) (xy -0.22733 0.28067) (xy -0.22733 0.27051)
						(xy -0.22606 0.25908) (xy -0.22352 0.24892) (xy -0.22225 0.23876) (xy -0.21844 0.22733) (xy -0.2159 0.21717)
						(xy -0.21209 0.20701) (xy -0.20701 0.19685) (xy -0.2032 0.18796) (xy -0.19812 0.1778) (xy -0.17272 0.14224)
						(xy -0.1651 0.13462) (xy -0.1651 -0.7366) (xy -0.16256 -0.76835) (xy -0.1524 -0.8001) (xy -0.13716 -0.82804)
						(xy -0.11684 -0.85344) (xy -0.09144 -0.87376) (xy -0.0635 -0.889) (xy -0.03175 -0.89916) (xy 0 -0.9017)
						(xy 0.03175 -0.89916) (xy 0.0635 -0.889) (xy 0.09144 -0.87376) (xy 0.11684 -0.85344) (xy 0.13716 -0.82804)
						(xy 0.1524 -0.8001) (xy 0.16256 -0.76835) (xy 0.1651 -0.7366) (xy 0.1651 0.13462) (xy 0.17272 0.14224)
						(xy 0.19812 0.1778) (xy 0.2032 0.18796) (xy 0.20701 0.19685) (xy 0.21209 0.20701) (xy 0.2159 0.21717)
						(xy 0.21844 0.22733) (xy 0.22225 0.23876) (xy 0.22352 0.24892) (xy 0.22606 0.25908) (xy 0.22733 0.27051)
						(xy 0.22733 0.28067) (xy 0.2286 0.2921) (xy 0.22733 0.30353) (xy 0.22733 0.31369) (xy 0.22606 0.32512)
						(xy 0.22352 0.33528) (xy 0.22225 0.34544) (xy 0.21844 0.35687) (xy 0.2159 0.36703) (xy 0.21209 0.37719)
						(xy 0.20701 0.38735) (xy 0.2032 0.39624) (xy 0.19812 0.4064) (xy 0.17272 0.44196) (xy 0.1651 0.44958)
						(xy 0.1651 0.7366) (xy 0.16256 0.76835) (xy 0.1524 0.8001) (xy 0.13716 0.82804) (xy 0.11684 0.85344)
						(xy 0.09144 0.87376) (xy 0.0635 0.889) (xy 0.03175 0.89916)
					)
					(width 0)
					(fill yes)
				)
			)
		)
		(pad "51" smd custom
			(at -16.649954 4.106672)
			(size 0.1143 0.1143)
			(layers "F.Cu" "F.Mask" "F.Paste")
			(net "M_B_DQ23")
			(options
				(clearance outline)
				(anchor circle)
			)
			(primitives
				(gr_poly
					(pts
						(xy 0 0.9017) (xy -0.03175 0.89916) (xy -0.0635 0.889) (xy -0.09144 0.87376) (xy -0.11684 0.85344)
						(xy -0.13716 0.82804) (xy -0.1524 0.8001) (xy -0.16256 0.76835) (xy -0.1651 0.7366) (xy -0.1651 0.11938)
						(xy -0.17272 0.11176) (xy -0.19812 0.0762) (xy -0.2032 0.06604) (xy -0.20701 0.05715) (xy -0.21209 0.04699)
						(xy -0.2159 0.03683) (xy -0.21844 0.02667) (xy -0.22225 0.01524) (xy -0.22352 0.00508) (xy -0.22606 -0.00508)
						(xy -0.22733 -0.01651) (xy -0.22733 -0.02667) (xy -0.2286 -0.0381) (xy -0.22733 -0.04953) (xy -0.22733 -0.05969)
						(xy -0.22606 -0.07112) (xy -0.22352 -0.08128) (xy -0.22225 -0.09144) (xy -0.21844 -0.10287) (xy -0.2159 -0.11303)
						(xy -0.21209 -0.12319) (xy -0.20701 -0.13335) (xy -0.2032 -0.14224) (xy -0.19812 -0.1524) (xy -0.17272 -0.18796)
						(xy -0.1651 -0.19558) (xy -0.1651 -0.7366) (xy -0.16256 -0.76835) (xy -0.1524 -0.8001) (xy -0.13716 -0.82804)
						(xy -0.11684 -0.85344) (xy -0.09144 -0.87376) (xy -0.0635 -0.889) (xy -0.03175 -0.89916) (xy 0 -0.9017)
						(xy 0.03175 -0.89916) (xy 0.0635 -0.889) (xy 0.09144 -0.87376) (xy 0.11684 -0.85344) (xy 0.13716 -0.82804)
						(xy 0.1524 -0.8001) (xy 0.16256 -0.76835) (xy 0.1651 -0.7366) (xy 0.1651 -0.19685) (xy 0.17272 -0.18923)
						(xy 0.17907 -0.18034) (xy 0.18669 -0.17145) (xy 0.19177 -0.16256) (xy 0.19812 -0.15367) (xy 0.20828 -0.13335)
						(xy 0.21971 -0.10287) (xy 0.22225 -0.09271) (xy 0.22479 -0.08128) (xy 0.22606 -0.07112) (xy 0.2286 -0.05969)
						(xy 0.2286 -0.01651) (xy 0.22606 -0.00508) (xy 0.22479 0.00508) (xy 0.22225 0.01651) (xy 0.21971 0.02667)
						(xy 0.20828 0.05715) (xy 0.19812 0.07747) (xy 0.19177 0.08636) (xy 0.18669 0.09525) (xy 0.17907 0.10414)
						(xy 0.17272 0.11303) (xy 0.1651 0.12065) (xy 0.1651 0.7366) (xy 0.16256 0.76835) (xy 0.1524 0.8001)
						(xy 0.13716 0.82804) (xy 0.11684 0.85344) (xy 0.09144 0.87376) (xy 0.0635 0.889) (xy 0.03175 0.89916)
					)
					(width 0)
					(fill yes)
				)
			)
		)
		(pad "52" smd custom
			(at -16.34998 -4.106672)
			(size 0.1143 0.1143)
			(layers "F.Cu" "F.Mask" "F.Paste")
			(net "GND")
			(options
				(clearance outline)
				(anchor circle)
			)
			(primitives
				(gr_poly
					(pts
						(xy 0 0.9017) (xy -0.03175 0.89916) (xy -0.0635 0.889) (xy -0.09144 0.87376) (xy -0.11684 0.85344)
						(xy -0.13716 0.82804) (xy -0.1524 0.8001) (xy -0.16256 0.76835) (xy -0.1651 0.7366) (xy -0.1651 0.19685)
						(xy -0.17272 0.18923) (xy -0.17907 0.18034) (xy -0.18669 0.17145) (xy -0.19177 0.16256) (xy -0.19812 0.15367)
						(xy -0.20828 0.13335) (xy -0.21971 0.10287) (xy -0.22225 0.09271) (xy -0.22479 0.08128) (xy -0.22606 0.07112)
						(xy -0.2286 0.05969) (xy -0.2286 0.01651) (xy -0.22606 0.00508) (xy -0.22479 -0.00508) (xy -0.22225 -0.01651)
						(xy -0.21971 -0.02667) (xy -0.20828 -0.05715) (xy -0.19812 -0.07747) (xy -0.19177 -0.08636) (xy -0.18669 -0.09525)
						(xy -0.17907 -0.10414) (xy -0.17272 -0.11303) (xy -0.1651 -0.12065) (xy -0.1651 -0.7366) (xy -0.16256 -0.76835)
						(xy -0.1524 -0.8001) (xy -0.13716 -0.82804) (xy -0.11684 -0.85344) (xy -0.09144 -0.87376) (xy -0.0635 -0.889)
						(xy -0.03175 -0.89916) (xy 0 -0.9017) (xy 0.03175 -0.89916) (xy 0.0635 -0.889) (xy 0.09144 -0.87376)
						(xy 0.11684 -0.85344) (xy 0.13716 -0.82804) (xy 0.1524 -0.8001) (xy 0.16256 -0.76835) (xy 0.1651 -0.7366)
						(xy 0.1651 -0.11938) (xy 0.17272 -0.11176) (xy 0.19812 -0.0762) (xy 0.2032 -0.06604) (xy 0.20701 -0.05715)
						(xy 0.21209 -0.04699) (xy 0.2159 -0.03683) (xy 0.21844 -0.02667) (xy 0.22225 -0.01524) (xy 0.22352 -0.00508)
						(xy 0.22606 0.00508) (xy 0.22733 0.01651) (xy 0.22733 0.02667) (xy 0.2286 0.0381) (xy 0.22733 0.04953)
						(xy 0.22733 0.05969) (xy 0.22606 0.07112) (xy 0.22352 0.08128) (xy 0.22225 0.09144) (xy 0.21844 0.10287)
						(xy 0.2159 0.11303) (xy 0.21209 0.12319) (xy 0.20701 0.13335) (xy 0.2032 0.14224) (xy 0.19812 0.1524)
						(xy 0.17272 0.18796) (xy 0.1651 0.19558) (xy 0.1651 0.7366) (xy 0.16256 0.76835) (xy 0.1524 0.8001)
						(xy 0.13716 0.82804) (xy 0.11684 0.85344) (xy 0.09144 0.87376) (xy 0.0635 0.889) (xy 0.03175 0.89916)
					)
					(width 0)
					(fill yes)
				)
			)
		)
		(pad "53" smd custom
			(at -16.050006 4.106672)
			(size 0.1143 0.1143)
			(layers "F.Cu" "F.Mask" "F.Paste")
			(net "GND")
			(options
				(clearance outline)
				(anchor circle)
			)
			(primitives
				(gr_poly
					(pts
						(xy 0 0.9017) (xy -0.03175 0.89916) (xy -0.0635 0.889) (xy -0.09144 0.87376) (xy -0.11684 0.85344)
						(xy -0.13716 0.82804) (xy -0.1524 0.8001) (xy -0.16256 0.76835) (xy -0.1651 0.7366) (xy -0.1651 -0.13462)
						(xy -0.17272 -0.14224) (xy -0.19812 -0.1778) (xy -0.2032 -0.18796) (xy -0.20701 -0.19685) (xy -0.21209 -0.20701)
						(xy -0.2159 -0.21717) (xy -0.21844 -0.22733) (xy -0.22225 -0.23876) (xy -0.22352 -0.24892) (xy -0.22606 -0.25908)
						(xy -0.22733 -0.27051) (xy -0.22733 -0.28067) (xy -0.2286 -0.2921) (xy -0.22733 -0.30353) (xy -0.22733 -0.31369)
						(xy -0.22606 -0.32512) (xy -0.22352 -0.33528) (xy -0.22225 -0.34544) (xy -0.21844 -0.35687) (xy -0.2159 -0.36703)
						(xy -0.21209 -0.37719) (xy -0.20701 -0.38735) (xy -0.2032 -0.39624) (xy -0.19812 -0.4064) (xy -0.17272 -0.44196)
						(xy -0.1651 -0.44958) (xy -0.1651 -0.7366) (xy -0.16256 -0.76835) (xy -0.1524 -0.8001) (xy -0.13716 -0.82804)
						(xy -0.11684 -0.85344) (xy -0.09144 -0.87376) (xy -0.0635 -0.889) (xy -0.03175 -0.89916) (xy 0 -0.9017)
						(xy 0.03175 -0.89916) (xy 0.0635 -0.889) (xy 0.09144 -0.87376) (xy 0.11684 -0.85344) (xy 0.13716 -0.82804)
						(xy 0.1524 -0.8001) (xy 0.16256 -0.76835) (xy 0.1651 -0.7366) (xy 0.1651 -0.44958) (xy 0.17272 -0.44196)
						(xy 0.19812 -0.4064) (xy 0.2032 -0.39624) (xy 0.20701 -0.38735) (xy 0.21209 -0.37719) (xy 0.2159 -0.36703)
						(xy 0.21844 -0.35687) (xy 0.22225 -0.34544) (xy 0.22352 -0.33528) (xy 0.22606 -0.32512) (xy 0.22733 -0.31369)
						(xy 0.22733 -0.30353) (xy 0.2286 -0.2921) (xy 0.22733 -0.28067) (xy 0.22733 -0.27051) (xy 0.22606 -0.25908)
						(xy 0.22352 -0.24892) (xy 0.22225 -0.23876) (xy 0.21844 -0.22733) (xy 0.2159 -0.21717) (xy 0.21209 -0.20701)
						(xy 0.20701 -0.19685) (xy 0.2032 -0.18796) (xy 0.19812 -0.1778) (xy 0.17272 -0.14224) (xy 0.1651 -0.13462)
						(xy 0.1651 0.7366) (xy 0.16256 0.76835) (xy 0.1524 0.8001) (xy 0.13716 0.82804) (xy 0.11684 0.85344)
						(xy 0.09144 0.87376) (xy 0.0635 0.889) (xy 0.03175 0.89916)
					)
					(width 0)
					(fill yes)
				)
			)
		)
		(pad "54" smd custom
			(at -15.750032 -4.106672)
			(size 0.1143 0.1143)
			(layers "F.Cu" "F.Mask" "F.Paste")
			(net "M_B_DQ24")
			(options
				(clearance outline)
				(anchor circle)
			)
			(primitives
				(gr_poly
					(pts
						(xy 0 0.9017) (xy -0.03175 0.89916) (xy -0.0635 0.889) (xy -0.09144 0.87376) (xy -0.11684 0.85344)
						(xy -0.13716 0.82804) (xy -0.1524 0.8001) (xy -0.16256 0.76835) (xy -0.1651 0.7366) (xy -0.1651 0.44958)
						(xy -0.17272 0.44196) (xy -0.19812 0.4064) (xy -0.2032 0.39624) (xy -0.20701 0.38735) (xy -0.21209 0.37719)
						(xy -0.2159 0.36703) (xy -0.21844 0.35687) (xy -0.22225 0.34544) (xy -0.22352 0.33528) (xy -0.22606 0.32512)
						(xy -0.22733 0.31369) (xy -0.22733 0.30353) (xy -0.2286 0.2921) (xy -0.22733 0.28067) (xy -0.22733 0.27051)
						(xy -0.22606 0.25908) (xy -0.22352 0.24892) (xy -0.22225 0.23876) (xy -0.21844 0.22733) (xy -0.2159 0.21717)
						(xy -0.21209 0.20701) (xy -0.20701 0.19685) (xy -0.2032 0.18796) (xy -0.19812 0.1778) (xy -0.17272 0.14224)
						(xy -0.1651 0.13462) (xy -0.1651 -0.7366) (xy -0.16256 -0.76835) (xy -0.1524 -0.8001) (xy -0.13716 -0.82804)
						(xy -0.11684 -0.85344) (xy -0.09144 -0.87376) (xy -0.0635 -0.889) (xy -0.03175 -0.89916) (xy 0 -0.9017)
						(xy 0.03175 -0.89916) (xy 0.0635 -0.889) (xy 0.09144 -0.87376) (xy 0.11684 -0.85344) (xy 0.13716 -0.82804)
						(xy 0.1524 -0.8001) (xy 0.16256 -0.76835) (xy 0.1651 -0.7366) (xy 0.1651 0.13462) (xy 0.17272 0.14224)
						(xy 0.19812 0.1778) (xy 0.2032 0.18796) (xy 0.20701 0.19685) (xy 0.21209 0.20701) (xy 0.2159 0.21717)
						(xy 0.21844 0.22733) (xy 0.22225 0.23876) (xy 0.22352 0.24892) (xy 0.22606 0.25908) (xy 0.22733 0.27051)
						(xy 0.22733 0.28067) (xy 0.2286 0.2921) (xy 0.22733 0.30353) (xy 0.22733 0.31369) (xy 0.22606 0.32512)
						(xy 0.22352 0.33528) (xy 0.22225 0.34544) (xy 0.21844 0.35687) (xy 0.2159 0.36703) (xy 0.21209 0.37719)
						(xy 0.20701 0.38735) (xy 0.2032 0.39624) (xy 0.19812 0.4064) (xy 0.17272 0.44196) (xy 0.1651 0.44958)
						(xy 0.1651 0.7366) (xy 0.16256 0.76835) (xy 0.1524 0.8001) (xy 0.13716 0.82804) (xy 0.11684 0.85344)
						(xy 0.09144 0.87376) (xy 0.0635 0.889) (xy 0.03175 0.89916)
					)
					(width 0)
					(fill yes)
				)
			)
		)
		(pad "55" smd custom
			(at -15.450058 4.106672)
			(size 0.1143 0.1143)
			(layers "F.Cu" "F.Mask" "F.Paste")
			(net "M_B_DQ28")
			(options
				(clearance outline)
				(anchor circle)
			)
			(primitives
				(gr_poly
					(pts
						(xy 0 0.9017) (xy -0.03175 0.89916) (xy -0.0635 0.889) (xy -0.09144 0.87376) (xy -0.11684 0.85344)
						(xy -0.13716 0.82804) (xy -0.1524 0.8001) (xy -0.16256 0.76835) (xy -0.1651 0.7366) (xy -0.1651 0.11938)
						(xy -0.17272 0.11176) (xy -0.19812 0.0762) (xy -0.2032 0.06604) (xy -0.20701 0.05715) (xy -0.21209 0.04699)
						(xy -0.2159 0.03683) (xy -0.21844 0.02667) (xy -0.22225 0.01524) (xy -0.22352 0.00508) (xy -0.22606 -0.00508)
						(xy -0.22733 -0.01651) (xy -0.22733 -0.02667) (xy -0.2286 -0.0381) (xy -0.22733 -0.04953) (xy -0.22733 -0.05969)
						(xy -0.22606 -0.07112) (xy -0.22352 -0.08128) (xy -0.22225 -0.09144) (xy -0.21844 -0.10287) (xy -0.2159 -0.11303)
						(xy -0.21209 -0.12319) (xy -0.20701 -0.13335) (xy -0.2032 -0.14224) (xy -0.19812 -0.1524) (xy -0.17272 -0.18796)
						(xy -0.1651 -0.19558) (xy -0.1651 -0.7366) (xy -0.16256 -0.76835) (xy -0.1524 -0.8001) (xy -0.13716 -0.82804)
						(xy -0.11684 -0.85344) (xy -0.09144 -0.87376) (xy -0.0635 -0.889) (xy -0.03175 -0.89916) (xy 0 -0.9017)
						(xy 0.03175 -0.89916) (xy 0.0635 -0.889) (xy 0.09144 -0.87376) (xy 0.11684 -0.85344) (xy 0.13716 -0.82804)
						(xy 0.1524 -0.8001) (xy 0.16256 -0.76835) (xy 0.1651 -0.7366) (xy 0.1651 -0.19685) (xy 0.17272 -0.18923)
						(xy 0.17907 -0.18034) (xy 0.18669 -0.17145) (xy 0.19177 -0.16256) (xy 0.19812 -0.15367) (xy 0.20828 -0.13335)
						(xy 0.21971 -0.10287) (xy 0.22225 -0.09271) (xy 0.22479 -0.08128) (xy 0.22606 -0.07112) (xy 0.2286 -0.05969)
						(xy 0.2286 -0.01651) (xy 0.22606 -0.00508) (xy 0.22479 0.00508) (xy 0.22225 0.01651) (xy 0.21971 0.02667)
						(xy 0.20828 0.05715) (xy 0.19812 0.07747) (xy 0.19177 0.08636) (xy 0.18669 0.09525) (xy 0.17907 0.10414)
						(xy 0.17272 0.11303) (xy 0.1651 0.12065) (xy 0.1651 0.7366) (xy 0.16256 0.76835) (xy 0.1524 0.8001)
						(xy 0.13716 0.82804) (xy 0.11684 0.85344) (xy 0.09144 0.87376) (xy 0.0635 0.889) (xy 0.03175 0.89916)
					)
					(width 0)
					(fill yes)
				)
			)
		)
		(pad "56" smd custom
			(at -15.150084 -4.106672)
			(size 0.1143 0.1143)
			(layers "F.Cu" "F.Mask" "F.Paste")
			(net "M_B_DQ25")
			(options
				(clearance outline)
				(anchor circle)
			)
			(primitives
				(gr_poly
					(pts
						(xy 0 0.9017) (xy -0.03175 0.89916) (xy -0.0635 0.889) (xy -0.09144 0.87376) (xy -0.11684 0.85344)
						(xy -0.13716 0.82804) (xy -0.1524 0.8001) (xy -0.16256 0.76835) (xy -0.1651 0.7366) (xy -0.1651 0.19685)
						(xy -0.17272 0.18923) (xy -0.17907 0.18034) (xy -0.18669 0.17145) (xy -0.19177 0.16256) (xy -0.19812 0.15367)
						(xy -0.20828 0.13335) (xy -0.21971 0.10287) (xy -0.22225 0.09271) (xy -0.22479 0.08128) (xy -0.22606 0.07112)
						(xy -0.2286 0.05969) (xy -0.2286 0.01651) (xy -0.22606 0.00508) (xy -0.22479 -0.00508) (xy -0.22225 -0.01651)
						(xy -0.21971 -0.02667) (xy -0.20828 -0.05715) (xy -0.19812 -0.07747) (xy -0.19177 -0.08636) (xy -0.18669 -0.09525)
						(xy -0.17907 -0.10414) (xy -0.17272 -0.11303) (xy -0.1651 -0.12065) (xy -0.1651 -0.7366) (xy -0.16256 -0.76835)
						(xy -0.1524 -0.8001) (xy -0.13716 -0.82804) (xy -0.11684 -0.85344) (xy -0.09144 -0.87376) (xy -0.0635 -0.889)
						(xy -0.03175 -0.89916) (xy 0 -0.9017) (xy 0.03175 -0.89916) (xy 0.0635 -0.889) (xy 0.09144 -0.87376)
						(xy 0.11684 -0.85344) (xy 0.13716 -0.82804) (xy 0.1524 -0.8001) (xy 0.16256 -0.76835) (xy 0.1651 -0.7366)
						(xy 0.1651 -0.11938) (xy 0.17272 -0.11176) (xy 0.19812 -0.0762) (xy 0.2032 -0.06604) (xy 0.20701 -0.05715)
						(xy 0.21209 -0.04699) (xy 0.2159 -0.03683) (xy 0.21844 -0.02667) (xy 0.22225 -0.01524) (xy 0.22352 -0.00508)
						(xy 0.22606 0.00508) (xy 0.22733 0.01651) (xy 0.22733 0.02667) (xy 0.2286 0.0381) (xy 0.22733 0.04953)
						(xy 0.22733 0.05969) (xy 0.22606 0.07112) (xy 0.22352 0.08128) (xy 0.22225 0.09144) (xy 0.21844 0.10287)
						(xy 0.2159 0.11303) (xy 0.21209 0.12319) (xy 0.20701 0.13335) (xy 0.2032 0.14224) (xy 0.19812 0.1524)
						(xy 0.17272 0.18796) (xy 0.1651 0.19558) (xy 0.1651 0.7366) (xy 0.16256 0.76835) (xy 0.1524 0.8001)
						(xy 0.13716 0.82804) (xy 0.11684 0.85344) (xy 0.09144 0.87376) (xy 0.0635 0.889) (xy 0.03175 0.89916)
					)
					(width 0)
					(fill yes)
				)
			)
		)
		(pad "57" smd custom
			(at -14.85011 4.106672)
			(size 0.1143 0.1143)
			(layers "F.Cu" "F.Mask" "F.Paste")
			(net "M_B_DQ29")
			(options
				(clearance outline)
				(anchor circle)
			)
			(primitives
				(gr_poly
					(pts
						(xy 0 0.9017) (xy -0.03175 0.89916) (xy -0.0635 0.889) (xy -0.09144 0.87376) (xy -0.11684 0.85344)
						(xy -0.13716 0.82804) (xy -0.1524 0.8001) (xy -0.16256 0.76835) (xy -0.1651 0.7366) (xy -0.1651 -0.13462)
						(xy -0.17272 -0.14224) (xy -0.19812 -0.1778) (xy -0.2032 -0.18796) (xy -0.20701 -0.19685) (xy -0.21209 -0.20701)
						(xy -0.2159 -0.21717) (xy -0.21844 -0.22733) (xy -0.22225 -0.23876) (xy -0.22352 -0.24892) (xy -0.22606 -0.25908)
						(xy -0.22733 -0.27051) (xy -0.22733 -0.28067) (xy -0.2286 -0.2921) (xy -0.22733 -0.30353) (xy -0.22733 -0.31369)
						(xy -0.22606 -0.32512) (xy -0.22352 -0.33528) (xy -0.22225 -0.34544) (xy -0.21844 -0.35687) (xy -0.2159 -0.36703)
						(xy -0.21209 -0.37719) (xy -0.20701 -0.38735) (xy -0.2032 -0.39624) (xy -0.19812 -0.4064) (xy -0.17272 -0.44196)
						(xy -0.1651 -0.44958) (xy -0.1651 -0.7366) (xy -0.16256 -0.76835) (xy -0.1524 -0.8001) (xy -0.13716 -0.82804)
						(xy -0.11684 -0.85344) (xy -0.09144 -0.87376) (xy -0.0635 -0.889) (xy -0.03175 -0.89916) (xy 0 -0.9017)
						(xy 0.03175 -0.89916) (xy 0.0635 -0.889) (xy 0.09144 -0.87376) (xy 0.11684 -0.85344) (xy 0.13716 -0.82804)
						(xy 0.1524 -0.8001) (xy 0.16256 -0.76835) (xy 0.1651 -0.7366) (xy 0.1651 -0.44958) (xy 0.17272 -0.44196)
						(xy 0.19812 -0.4064) (xy 0.2032 -0.39624) (xy 0.20701 -0.38735) (xy 0.21209 -0.37719) (xy 0.2159 -0.36703)
						(xy 0.21844 -0.35687) (xy 0.22225 -0.34544) (xy 0.22352 -0.33528) (xy 0.22606 -0.32512) (xy 0.22733 -0.31369)
						(xy 0.22733 -0.30353) (xy 0.2286 -0.2921) (xy 0.22733 -0.28067) (xy 0.22733 -0.27051) (xy 0.22606 -0.25908)
						(xy 0.22352 -0.24892) (xy 0.22225 -0.23876) (xy 0.21844 -0.22733) (xy 0.2159 -0.21717) (xy 0.21209 -0.20701)
						(xy 0.20701 -0.19685) (xy 0.2032 -0.18796) (xy 0.19812 -0.1778) (xy 0.17272 -0.14224) (xy 0.1651 -0.13462)
						(xy 0.1651 0.7366) (xy 0.16256 0.76835) (xy 0.1524 0.8001) (xy 0.13716 0.82804) (xy 0.11684 0.85344)
						(xy 0.09144 0.87376) (xy 0.0635 0.889) (xy 0.03175 0.89916)
					)
					(width 0)
					(fill yes)
				)
			)
		)
		(pad "58" smd custom
			(at -14.549882 -4.106672)
			(size 0.1143 0.1143)
			(layers "F.Cu" "F.Mask" "F.Paste")
			(net "GND")
			(options
				(clearance outline)
				(anchor circle)
			)
			(primitives
				(gr_poly
					(pts
						(xy 0 0.9017) (xy -0.03175 0.89916) (xy -0.0635 0.889) (xy -0.09144 0.87376) (xy -0.11684 0.85344)
						(xy -0.13716 0.82804) (xy -0.1524 0.8001) (xy -0.16256 0.76835) (xy -0.1651 0.7366) (xy -0.1651 0.44958)
						(xy -0.17272 0.44196) (xy -0.19812 0.4064) (xy -0.2032 0.39624) (xy -0.20701 0.38735) (xy -0.21209 0.37719)
						(xy -0.2159 0.36703) (xy -0.21844 0.35687) (xy -0.22225 0.34544) (xy -0.22352 0.33528) (xy -0.22606 0.32512)
						(xy -0.22733 0.31369) (xy -0.22733 0.30353) (xy -0.2286 0.2921) (xy -0.22733 0.28067) (xy -0.22733 0.27051)
						(xy -0.22606 0.25908) (xy -0.22352 0.24892) (xy -0.22225 0.23876) (xy -0.21844 0.22733) (xy -0.2159 0.21717)
						(xy -0.21209 0.20701) (xy -0.20701 0.19685) (xy -0.2032 0.18796) (xy -0.19812 0.1778) (xy -0.17272 0.14224)
						(xy -0.1651 0.13462) (xy -0.1651 -0.7366) (xy -0.16256 -0.76835) (xy -0.1524 -0.8001) (xy -0.13716 -0.82804)
						(xy -0.11684 -0.85344) (xy -0.09144 -0.87376) (xy -0.0635 -0.889) (xy -0.03175 -0.89916) (xy 0 -0.9017)
						(xy 0.03175 -0.89916) (xy 0.0635 -0.889) (xy 0.09144 -0.87376) (xy 0.11684 -0.85344) (xy 0.13716 -0.82804)
						(xy 0.1524 -0.8001) (xy 0.16256 -0.76835) (xy 0.1651 -0.7366) (xy 0.1651 0.13462) (xy 0.17272 0.14224)
						(xy 0.19812 0.1778) (xy 0.2032 0.18796) (xy 0.20701 0.19685) (xy 0.21209 0.20701) (xy 0.2159 0.21717)
						(xy 0.21844 0.22733) (xy 0.22225 0.23876) (xy 0.22352 0.24892) (xy 0.22606 0.25908) (xy 0.22733 0.27051)
						(xy 0.22733 0.28067) (xy 0.2286 0.2921) (xy 0.22733 0.30353) (xy 0.22733 0.31369) (xy 0.22606 0.32512)
						(xy 0.22352 0.33528) (xy 0.22225 0.34544) (xy 0.21844 0.35687) (xy 0.2159 0.36703) (xy 0.21209 0.37719)
						(xy 0.20701 0.38735) (xy 0.2032 0.39624) (xy 0.19812 0.4064) (xy 0.17272 0.44196) (xy 0.1651 0.44958)
						(xy 0.1651 0.7366) (xy 0.16256 0.76835) (xy 0.1524 0.8001) (xy 0.13716 0.82804) (xy 0.11684 0.85344)
						(xy 0.09144 0.87376) (xy 0.0635 0.889) (xy 0.03175 0.89916)
					)
					(width 0)
					(fill yes)
				)
			)
		)
		(pad "59" smd custom
			(at -14.249908 4.106672)
			(size 0.1143 0.1143)
			(layers "F.Cu" "F.Mask" "F.Paste")
			(net "GND")
			(options
				(clearance outline)
				(anchor circle)
			)
			(primitives
				(gr_poly
					(pts
						(xy 0 0.9017) (xy -0.03175 0.89916) (xy -0.0635 0.889) (xy -0.09144 0.87376) (xy -0.11684 0.85344)
						(xy -0.13716 0.82804) (xy -0.1524 0.8001) (xy -0.16256 0.76835) (xy -0.1651 0.7366) (xy -0.1651 0.11938)
						(xy -0.17272 0.11176) (xy -0.19812 0.0762) (xy -0.2032 0.06604) (xy -0.20701 0.05715) (xy -0.21209 0.04699)
						(xy -0.2159 0.03683) (xy -0.21844 0.02667) (xy -0.22225 0.01524) (xy -0.22352 0.00508) (xy -0.22606 -0.00508)
						(xy -0.22733 -0.01651) (xy -0.22733 -0.02667) (xy -0.2286 -0.0381) (xy -0.22733 -0.04953) (xy -0.22733 -0.05969)
						(xy -0.22606 -0.07112) (xy -0.22352 -0.08128) (xy -0.22225 -0.09144) (xy -0.21844 -0.10287) (xy -0.2159 -0.11303)
						(xy -0.21209 -0.12319) (xy -0.20701 -0.13335) (xy -0.2032 -0.14224) (xy -0.19812 -0.1524) (xy -0.17272 -0.18796)
						(xy -0.1651 -0.19558) (xy -0.1651 -0.7366) (xy -0.16256 -0.76835) (xy -0.1524 -0.8001) (xy -0.13716 -0.82804)
						(xy -0.11684 -0.85344) (xy -0.09144 -0.87376) (xy -0.0635 -0.889) (xy -0.03175 -0.89916) (xy 0 -0.9017)
						(xy 0.03175 -0.89916) (xy 0.0635 -0.889) (xy 0.09144 -0.87376) (xy 0.11684 -0.85344) (xy 0.13716 -0.82804)
						(xy 0.1524 -0.8001) (xy 0.16256 -0.76835) (xy 0.1651 -0.7366) (xy 0.1651 -0.19685) (xy 0.17272 -0.18923)
						(xy 0.17907 -0.18034) (xy 0.18669 -0.17145) (xy 0.19177 -0.16256) (xy 0.19812 -0.15367) (xy 0.20828 -0.13335)
						(xy 0.21971 -0.10287) (xy 0.22225 -0.09271) (xy 0.22479 -0.08128) (xy 0.22606 -0.07112) (xy 0.2286 -0.05969)
						(xy 0.2286 -0.01651) (xy 0.22606 -0.00508) (xy 0.22479 0.00508) (xy 0.22225 0.01651) (xy 0.21971 0.02667)
						(xy 0.20828 0.05715) (xy 0.19812 0.07747) (xy 0.19177 0.08636) (xy 0.18669 0.09525) (xy 0.17907 0.10414)
						(xy 0.17272 0.11303) (xy 0.1651 0.12065) (xy 0.1651 0.7366) (xy 0.16256 0.76835) (xy 0.1524 0.8001)
						(xy 0.13716 0.82804) (xy 0.11684 0.85344) (xy 0.09144 0.87376) (xy 0.0635 0.889) (xy 0.03175 0.89916)
					)
					(width 0)
					(fill yes)
				)
			)
		)
		(pad "60" smd custom
			(at -13.949934 -4.106672)
			(size 0.1143 0.1143)
			(layers "F.Cu" "F.Mask" "F.Paste")
			(net "M_B_DQS_DN3")
			(options
				(clearance outline)
				(anchor circle)
			)
			(primitives
				(gr_poly
					(pts
						(xy 0 0.9017) (xy -0.03175 0.89916) (xy -0.0635 0.889) (xy -0.09144 0.87376) (xy -0.11684 0.85344)
						(xy -0.13716 0.82804) (xy -0.1524 0.8001) (xy -0.16256 0.76835) (xy -0.1651 0.7366) (xy -0.1651 0.19685)
						(xy -0.17272 0.18923) (xy -0.17907 0.18034) (xy -0.18669 0.17145) (xy -0.19177 0.16256) (xy -0.19812 0.15367)
						(xy -0.20828 0.13335) (xy -0.21971 0.10287) (xy -0.22225 0.09271) (xy -0.22479 0.08128) (xy -0.22606 0.07112)
						(xy -0.2286 0.05969) (xy -0.2286 0.01651) (xy -0.22606 0.00508) (xy -0.22479 -0.00508) (xy -0.22225 -0.01651)
						(xy -0.21971 -0.02667) (xy -0.20828 -0.05715) (xy -0.19812 -0.07747) (xy -0.19177 -0.08636) (xy -0.18669 -0.09525)
						(xy -0.17907 -0.10414) (xy -0.17272 -0.11303) (xy -0.1651 -0.12065) (xy -0.1651 -0.7366) (xy -0.16256 -0.76835)
						(xy -0.1524 -0.8001) (xy -0.13716 -0.82804) (xy -0.11684 -0.85344) (xy -0.09144 -0.87376) (xy -0.0635 -0.889)
						(xy -0.03175 -0.89916) (xy 0 -0.9017) (xy 0.03175 -0.89916) (xy 0.0635 -0.889) (xy 0.09144 -0.87376)
						(xy 0.11684 -0.85344) (xy 0.13716 -0.82804) (xy 0.1524 -0.8001) (xy 0.16256 -0.76835) (xy 0.1651 -0.7366)
						(xy 0.1651 -0.11938) (xy 0.17272 -0.11176) (xy 0.19812 -0.0762) (xy 0.2032 -0.06604) (xy 0.20701 -0.05715)
						(xy 0.21209 -0.04699) (xy 0.2159 -0.03683) (xy 0.21844 -0.02667) (xy 0.22225 -0.01524) (xy 0.22352 -0.00508)
						(xy 0.22606 0.00508) (xy 0.22733 0.01651) (xy 0.22733 0.02667) (xy 0.2286 0.0381) (xy 0.22733 0.04953)
						(xy 0.22733 0.05969) (xy 0.22606 0.07112) (xy 0.22352 0.08128) (xy 0.22225 0.09144) (xy 0.21844 0.10287)
						(xy 0.2159 0.11303) (xy 0.21209 0.12319) (xy 0.20701 0.13335) (xy 0.2032 0.14224) (xy 0.19812 0.1524)
						(xy 0.17272 0.18796) (xy 0.1651 0.19558) (xy 0.1651 0.7366) (xy 0.16256 0.76835) (xy 0.1524 0.8001)
						(xy 0.13716 0.82804) (xy 0.11684 0.85344) (xy 0.09144 0.87376) (xy 0.0635 0.889) (xy 0.03175 0.89916)
					)
					(width 0)
					(fill yes)
				)
			)
		)
		(pad "61" smd custom
			(at -13.64996 4.106672)
			(size 0.1143 0.1143)
			(layers "F.Cu" "F.Mask" "F.Paste")
			(net "GND")
			(options
				(clearance outline)
				(anchor circle)
			)
			(primitives
				(gr_poly
					(pts
						(xy 0 0.9017) (xy -0.03175 0.89916) (xy -0.0635 0.889) (xy -0.09144 0.87376) (xy -0.11684 0.85344)
						(xy -0.13716 0.82804) (xy -0.1524 0.8001) (xy -0.16256 0.76835) (xy -0.1651 0.7366) (xy -0.1651 -0.13462)
						(xy -0.17272 -0.14224) (xy -0.19812 -0.1778) (xy -0.2032 -0.18796) (xy -0.20701 -0.19685) (xy -0.21209 -0.20701)
						(xy -0.2159 -0.21717) (xy -0.21844 -0.22733) (xy -0.22225 -0.23876) (xy -0.22352 -0.24892) (xy -0.22606 -0.25908)
						(xy -0.22733 -0.27051) (xy -0.22733 -0.28067) (xy -0.2286 -0.2921) (xy -0.22733 -0.30353) (xy -0.22733 -0.31369)
						(xy -0.22606 -0.32512) (xy -0.22352 -0.33528) (xy -0.22225 -0.34544) (xy -0.21844 -0.35687) (xy -0.2159 -0.36703)
						(xy -0.21209 -0.37719) (xy -0.20701 -0.38735) (xy -0.2032 -0.39624) (xy -0.19812 -0.4064) (xy -0.17272 -0.44196)
						(xy -0.1651 -0.44958) (xy -0.1651 -0.7366) (xy -0.16256 -0.76835) (xy -0.1524 -0.8001) (xy -0.13716 -0.82804)
						(xy -0.11684 -0.85344) (xy -0.09144 -0.87376) (xy -0.0635 -0.889) (xy -0.03175 -0.89916) (xy 0 -0.9017)
						(xy 0.03175 -0.89916) (xy 0.0635 -0.889) (xy 0.09144 -0.87376) (xy 0.11684 -0.85344) (xy 0.13716 -0.82804)
						(xy 0.1524 -0.8001) (xy 0.16256 -0.76835) (xy 0.1651 -0.7366) (xy 0.1651 -0.44958) (xy 0.17272 -0.44196)
						(xy 0.19812 -0.4064) (xy 0.2032 -0.39624) (xy 0.20701 -0.38735) (xy 0.21209 -0.37719) (xy 0.2159 -0.36703)
						(xy 0.21844 -0.35687) (xy 0.22225 -0.34544) (xy 0.22352 -0.33528) (xy 0.22606 -0.32512) (xy 0.22733 -0.31369)
						(xy 0.22733 -0.30353) (xy 0.2286 -0.2921) (xy 0.22733 -0.28067) (xy 0.22733 -0.27051) (xy 0.22606 -0.25908)
						(xy 0.22352 -0.24892) (xy 0.22225 -0.23876) (xy 0.21844 -0.22733) (xy 0.2159 -0.21717) (xy 0.21209 -0.20701)
						(xy 0.20701 -0.19685) (xy 0.2032 -0.18796) (xy 0.19812 -0.1778) (xy 0.17272 -0.14224) (xy 0.1651 -0.13462)
						(xy 0.1651 0.7366) (xy 0.16256 0.76835) (xy 0.1524 0.8001) (xy 0.13716 0.82804) (xy 0.11684 0.85344)
						(xy 0.09144 0.87376) (xy 0.0635 0.889) (xy 0.03175 0.89916)
					)
					(width 0)
					(fill yes)
				)
			)
		)
		(pad "62" smd custom
			(at -13.349986 -4.106672)
			(size 0.1143 0.1143)
			(layers "F.Cu" "F.Mask" "F.Paste")
			(net "M_B_DQS_DP3")
			(options
				(clearance outline)
				(anchor circle)
			)
			(primitives
				(gr_poly
					(pts
						(xy 0 0.9017) (xy -0.03175 0.89916) (xy -0.0635 0.889) (xy -0.09144 0.87376) (xy -0.11684 0.85344)
						(xy -0.13716 0.82804) (xy -0.1524 0.8001) (xy -0.16256 0.76835) (xy -0.1651 0.7366) (xy -0.1651 0.44958)
						(xy -0.17272 0.44196) (xy -0.19812 0.4064) (xy -0.2032 0.39624) (xy -0.20701 0.38735) (xy -0.21209 0.37719)
						(xy -0.2159 0.36703) (xy -0.21844 0.35687) (xy -0.22225 0.34544) (xy -0.22352 0.33528) (xy -0.22606 0.32512)
						(xy -0.22733 0.31369) (xy -0.22733 0.30353) (xy -0.2286 0.2921) (xy -0.22733 0.28067) (xy -0.22733 0.27051)
						(xy -0.22606 0.25908) (xy -0.22352 0.24892) (xy -0.22225 0.23876) (xy -0.21844 0.22733) (xy -0.2159 0.21717)
						(xy -0.21209 0.20701) (xy -0.20701 0.19685) (xy -0.2032 0.18796) (xy -0.19812 0.1778) (xy -0.17272 0.14224)
						(xy -0.1651 0.13462) (xy -0.1651 -0.7366) (xy -0.16256 -0.76835) (xy -0.1524 -0.8001) (xy -0.13716 -0.82804)
						(xy -0.11684 -0.85344) (xy -0.09144 -0.87376) (xy -0.0635 -0.889) (xy -0.03175 -0.89916) (xy 0 -0.9017)
						(xy 0.03175 -0.89916) (xy 0.0635 -0.889) (xy 0.09144 -0.87376) (xy 0.11684 -0.85344) (xy 0.13716 -0.82804)
						(xy 0.1524 -0.8001) (xy 0.16256 -0.76835) (xy 0.1651 -0.7366) (xy 0.1651 0.13462) (xy 0.17272 0.14224)
						(xy 0.19812 0.1778) (xy 0.2032 0.18796) (xy 0.20701 0.19685) (xy 0.21209 0.20701) (xy 0.2159 0.21717)
						(xy 0.21844 0.22733) (xy 0.22225 0.23876) (xy 0.22352 0.24892) (xy 0.22606 0.25908) (xy 0.22733 0.27051)
						(xy 0.22733 0.28067) (xy 0.2286 0.2921) (xy 0.22733 0.30353) (xy 0.22733 0.31369) (xy 0.22606 0.32512)
						(xy 0.22352 0.33528) (xy 0.22225 0.34544) (xy 0.21844 0.35687) (xy 0.2159 0.36703) (xy 0.21209 0.37719)
						(xy 0.20701 0.38735) (xy 0.2032 0.39624) (xy 0.19812 0.4064) (xy 0.17272 0.44196) (xy 0.1651 0.44958)
						(xy 0.1651 0.7366) (xy 0.16256 0.76835) (xy 0.1524 0.8001) (xy 0.13716 0.82804) (xy 0.11684 0.85344)
						(xy 0.09144 0.87376) (xy 0.0635 0.889) (xy 0.03175 0.89916)
					)
					(width 0)
					(fill yes)
				)
			)
		)
		(pad "63" smd custom
			(at -13.050012 4.106672)
			(size 0.1143 0.1143)
			(layers "F.Cu" "F.Mask" "F.Paste")
			(net "M_B_DQ30")
			(options
				(clearance outline)
				(anchor circle)
			)
			(primitives
				(gr_poly
					(pts
						(xy 0 0.9017) (xy -0.03175 0.89916) (xy -0.0635 0.889) (xy -0.09144 0.87376) (xy -0.11684 0.85344)
						(xy -0.13716 0.82804) (xy -0.1524 0.8001) (xy -0.16256 0.76835) (xy -0.1651 0.7366) (xy -0.1651 0.11938)
						(xy -0.17272 0.11176) (xy -0.19812 0.0762) (xy -0.2032 0.06604) (xy -0.20701 0.05715) (xy -0.21209 0.04699)
						(xy -0.2159 0.03683) (xy -0.21844 0.02667) (xy -0.22225 0.01524) (xy -0.22352 0.00508) (xy -0.22606 -0.00508)
						(xy -0.22733 -0.01651) (xy -0.22733 -0.02667) (xy -0.2286 -0.0381) (xy -0.22733 -0.04953) (xy -0.22733 -0.05969)
						(xy -0.22606 -0.07112) (xy -0.22352 -0.08128) (xy -0.22225 -0.09144) (xy -0.21844 -0.10287) (xy -0.2159 -0.11303)
						(xy -0.21209 -0.12319) (xy -0.20701 -0.13335) (xy -0.2032 -0.14224) (xy -0.19812 -0.1524) (xy -0.17272 -0.18796)
						(xy -0.1651 -0.19558) (xy -0.1651 -0.7366) (xy -0.16256 -0.76835) (xy -0.1524 -0.8001) (xy -0.13716 -0.82804)
						(xy -0.11684 -0.85344) (xy -0.09144 -0.87376) (xy -0.0635 -0.889) (xy -0.03175 -0.89916) (xy 0 -0.9017)
						(xy 0.03175 -0.89916) (xy 0.0635 -0.889) (xy 0.09144 -0.87376) (xy 0.11684 -0.85344) (xy 0.13716 -0.82804)
						(xy 0.1524 -0.8001) (xy 0.16256 -0.76835) (xy 0.1651 -0.7366) (xy 0.1651 -0.19685) (xy 0.17272 -0.18923)
						(xy 0.17907 -0.18034) (xy 0.18669 -0.17145) (xy 0.19177 -0.16256) (xy 0.19812 -0.15367) (xy 0.20828 -0.13335)
						(xy 0.21971 -0.10287) (xy 0.22225 -0.09271) (xy 0.22479 -0.08128) (xy 0.22606 -0.07112) (xy 0.2286 -0.05969)
						(xy 0.2286 -0.01651) (xy 0.22606 -0.00508) (xy 0.22479 0.00508) (xy 0.22225 0.01651) (xy 0.21971 0.02667)
						(xy 0.20828 0.05715) (xy 0.19812 0.07747) (xy 0.19177 0.08636) (xy 0.18669 0.09525) (xy 0.17907 0.10414)
						(xy 0.17272 0.11303) (xy 0.1651 0.12065) (xy 0.1651 0.7366) (xy 0.16256 0.76835) (xy 0.1524 0.8001)
						(xy 0.13716 0.82804) (xy 0.11684 0.85344) (xy 0.09144 0.87376) (xy 0.0635 0.889) (xy 0.03175 0.89916)
					)
					(width 0)
					(fill yes)
				)
			)
		)
		(pad "64" smd custom
			(at -12.750038 -4.106672)
			(size 0.1143 0.1143)
			(layers "F.Cu" "F.Mask" "F.Paste")
			(net "GND")
			(options
				(clearance outline)
				(anchor circle)
			)
			(primitives
				(gr_poly
					(pts
						(xy 0 0.9017) (xy -0.03175 0.89916) (xy -0.0635 0.889) (xy -0.09144 0.87376) (xy -0.11684 0.85344)
						(xy -0.13716 0.82804) (xy -0.1524 0.8001) (xy -0.16256 0.76835) (xy -0.1651 0.7366) (xy -0.1651 0.19685)
						(xy -0.17272 0.18923) (xy -0.17907 0.18034) (xy -0.18669 0.17145) (xy -0.19177 0.16256) (xy -0.19812 0.15367)
						(xy -0.20828 0.13335) (xy -0.21971 0.10287) (xy -0.22225 0.09271) (xy -0.22479 0.08128) (xy -0.22606 0.07112)
						(xy -0.2286 0.05969) (xy -0.2286 0.01651) (xy -0.22606 0.00508) (xy -0.22479 -0.00508) (xy -0.22225 -0.01651)
						(xy -0.21971 -0.02667) (xy -0.20828 -0.05715) (xy -0.19812 -0.07747) (xy -0.19177 -0.08636) (xy -0.18669 -0.09525)
						(xy -0.17907 -0.10414) (xy -0.17272 -0.11303) (xy -0.1651 -0.12065) (xy -0.1651 -0.7366) (xy -0.16256 -0.76835)
						(xy -0.1524 -0.8001) (xy -0.13716 -0.82804) (xy -0.11684 -0.85344) (xy -0.09144 -0.87376) (xy -0.0635 -0.889)
						(xy -0.03175 -0.89916) (xy 0 -0.9017) (xy 0.03175 -0.89916) (xy 0.0635 -0.889) (xy 0.09144 -0.87376)
						(xy 0.11684 -0.85344) (xy 0.13716 -0.82804) (xy 0.1524 -0.8001) (xy 0.16256 -0.76835) (xy 0.1651 -0.7366)
						(xy 0.1651 -0.11938) (xy 0.17272 -0.11176) (xy 0.19812 -0.0762) (xy 0.2032 -0.06604) (xy 0.20701 -0.05715)
						(xy 0.21209 -0.04699) (xy 0.2159 -0.03683) (xy 0.21844 -0.02667) (xy 0.22225 -0.01524) (xy 0.22352 -0.00508)
						(xy 0.22606 0.00508) (xy 0.22733 0.01651) (xy 0.22733 0.02667) (xy 0.2286 0.0381) (xy 0.22733 0.04953)
						(xy 0.22733 0.05969) (xy 0.22606 0.07112) (xy 0.22352 0.08128) (xy 0.22225 0.09144) (xy 0.21844 0.10287)
						(xy 0.2159 0.11303) (xy 0.21209 0.12319) (xy 0.20701 0.13335) (xy 0.2032 0.14224) (xy 0.19812 0.1524)
						(xy 0.17272 0.18796) (xy 0.1651 0.19558) (xy 0.1651 0.7366) (xy 0.16256 0.76835) (xy 0.1524 0.8001)
						(xy 0.13716 0.82804) (xy 0.11684 0.85344) (xy 0.09144 0.87376) (xy 0.0635 0.889) (xy 0.03175 0.89916)
					)
					(width 0)
					(fill yes)
				)
			)
		)
		(pad "65" smd custom
			(at -12.450064 4.106672)
			(size 0.1143 0.1143)
			(layers "F.Cu" "F.Mask" "F.Paste")
			(net "M_B_DQ31")
			(options
				(clearance outline)
				(anchor circle)
			)
			(primitives
				(gr_poly
					(pts
						(xy 0 0.9017) (xy -0.03175 0.89916) (xy -0.0635 0.889) (xy -0.09144 0.87376) (xy -0.11684 0.85344)
						(xy -0.13716 0.82804) (xy -0.1524 0.8001) (xy -0.16256 0.76835) (xy -0.1651 0.7366) (xy -0.1651 -0.13462)
						(xy -0.17272 -0.14224) (xy -0.19812 -0.1778) (xy -0.2032 -0.18796) (xy -0.20701 -0.19685) (xy -0.21209 -0.20701)
						(xy -0.2159 -0.21717) (xy -0.21844 -0.22733) (xy -0.22225 -0.23876) (xy -0.22352 -0.24892) (xy -0.22606 -0.25908)
						(xy -0.22733 -0.27051) (xy -0.22733 -0.28067) (xy -0.2286 -0.2921) (xy -0.22733 -0.30353) (xy -0.22733 -0.31369)
						(xy -0.22606 -0.32512) (xy -0.22352 -0.33528) (xy -0.22225 -0.34544) (xy -0.21844 -0.35687) (xy -0.2159 -0.36703)
						(xy -0.21209 -0.37719) (xy -0.20701 -0.38735) (xy -0.2032 -0.39624) (xy -0.19812 -0.4064) (xy -0.17272 -0.44196)
						(xy -0.1651 -0.44958) (xy -0.1651 -0.7366) (xy -0.16256 -0.76835) (xy -0.1524 -0.8001) (xy -0.13716 -0.82804)
						(xy -0.11684 -0.85344) (xy -0.09144 -0.87376) (xy -0.0635 -0.889) (xy -0.03175 -0.89916) (xy 0 -0.9017)
						(xy 0.03175 -0.89916) (xy 0.0635 -0.889) (xy 0.09144 -0.87376) (xy 0.11684 -0.85344) (xy 0.13716 -0.82804)
						(xy 0.1524 -0.8001) (xy 0.16256 -0.76835) (xy 0.1651 -0.7366) (xy 0.1651 -0.44958) (xy 0.17272 -0.44196)
						(xy 0.19812 -0.4064) (xy 0.2032 -0.39624) (xy 0.20701 -0.38735) (xy 0.21209 -0.37719) (xy 0.2159 -0.36703)
						(xy 0.21844 -0.35687) (xy 0.22225 -0.34544) (xy 0.22352 -0.33528) (xy 0.22606 -0.32512) (xy 0.22733 -0.31369)
						(xy 0.22733 -0.30353) (xy 0.2286 -0.2921) (xy 0.22733 -0.28067) (xy 0.22733 -0.27051) (xy 0.22606 -0.25908)
						(xy 0.22352 -0.24892) (xy 0.22225 -0.23876) (xy 0.21844 -0.22733) (xy 0.2159 -0.21717) (xy 0.21209 -0.20701)
						(xy 0.20701 -0.19685) (xy 0.2032 -0.18796) (xy 0.19812 -0.1778) (xy 0.17272 -0.14224) (xy 0.1651 -0.13462)
						(xy 0.1651 0.7366) (xy 0.16256 0.76835) (xy 0.1524 0.8001) (xy 0.13716 0.82804) (xy 0.11684 0.85344)
						(xy 0.09144 0.87376) (xy 0.0635 0.889) (xy 0.03175 0.89916)
					)
					(width 0)
					(fill yes)
				)
			)
		)
		(pad "66" smd custom
			(at -12.15009 -4.106672)
			(size 0.1143 0.1143)
			(layers "F.Cu" "F.Mask" "F.Paste")
			(net "M_B_DQ26")
			(options
				(clearance outline)
				(anchor circle)
			)
			(primitives
				(gr_poly
					(pts
						(xy 0 0.9017) (xy -0.03175 0.89916) (xy -0.0635 0.889) (xy -0.09144 0.87376) (xy -0.11684 0.85344)
						(xy -0.13716 0.82804) (xy -0.1524 0.8001) (xy -0.16256 0.76835) (xy -0.1651 0.7366) (xy -0.1651 0.44958)
						(xy -0.17272 0.44196) (xy -0.19812 0.4064) (xy -0.2032 0.39624) (xy -0.20701 0.38735) (xy -0.21209 0.37719)
						(xy -0.2159 0.36703) (xy -0.21844 0.35687) (xy -0.22225 0.34544) (xy -0.22352 0.33528) (xy -0.22606 0.32512)
						(xy -0.22733 0.31369) (xy -0.22733 0.30353) (xy -0.2286 0.2921) (xy -0.22733 0.28067) (xy -0.22733 0.27051)
						(xy -0.22606 0.25908) (xy -0.22352 0.24892) (xy -0.22225 0.23876) (xy -0.21844 0.22733) (xy -0.2159 0.21717)
						(xy -0.21209 0.20701) (xy -0.20701 0.19685) (xy -0.2032 0.18796) (xy -0.19812 0.1778) (xy -0.17272 0.14224)
						(xy -0.1651 0.13462) (xy -0.1651 -0.7366) (xy -0.16256 -0.76835) (xy -0.1524 -0.8001) (xy -0.13716 -0.82804)
						(xy -0.11684 -0.85344) (xy -0.09144 -0.87376) (xy -0.0635 -0.889) (xy -0.03175 -0.89916) (xy 0 -0.9017)
						(xy 0.03175 -0.89916) (xy 0.0635 -0.889) (xy 0.09144 -0.87376) (xy 0.11684 -0.85344) (xy 0.13716 -0.82804)
						(xy 0.1524 -0.8001) (xy 0.16256 -0.76835) (xy 0.1651 -0.7366) (xy 0.1651 0.13462) (xy 0.17272 0.14224)
						(xy 0.19812 0.1778) (xy 0.2032 0.18796) (xy 0.20701 0.19685) (xy 0.21209 0.20701) (xy 0.2159 0.21717)
						(xy 0.21844 0.22733) (xy 0.22225 0.23876) (xy 0.22352 0.24892) (xy 0.22606 0.25908) (xy 0.22733 0.27051)
						(xy 0.22733 0.28067) (xy 0.2286 0.2921) (xy 0.22733 0.30353) (xy 0.22733 0.31369) (xy 0.22606 0.32512)
						(xy 0.22352 0.33528) (xy 0.22225 0.34544) (xy 0.21844 0.35687) (xy 0.2159 0.36703) (xy 0.21209 0.37719)
						(xy 0.20701 0.38735) (xy 0.2032 0.39624) (xy 0.19812 0.4064) (xy 0.17272 0.44196) (xy 0.1651 0.44958)
						(xy 0.1651 0.7366) (xy 0.16256 0.76835) (xy 0.1524 0.8001) (xy 0.13716 0.82804) (xy 0.11684 0.85344)
						(xy 0.09144 0.87376) (xy 0.0635 0.889) (xy 0.03175 0.89916)
					)
					(width 0)
					(fill yes)
				)
			)
		)
		(pad "67" smd custom
			(at -11.850116 4.106672)
			(size 0.1143 0.1143)
			(layers "F.Cu" "F.Mask" "F.Paste")
			(net "GND")
			(options
				(clearance outline)
				(anchor circle)
			)
			(primitives
				(gr_poly
					(pts
						(xy 0 0.9017) (xy -0.03175 0.89916) (xy -0.0635 0.889) (xy -0.09144 0.87376) (xy -0.11684 0.85344)
						(xy -0.13716 0.82804) (xy -0.1524 0.8001) (xy -0.16256 0.76835) (xy -0.1651 0.7366) (xy -0.1651 0.11938)
						(xy -0.17272 0.11176) (xy -0.19812 0.0762) (xy -0.2032 0.06604) (xy -0.20701 0.05715) (xy -0.21209 0.04699)
						(xy -0.2159 0.03683) (xy -0.21844 0.02667) (xy -0.22225 0.01524) (xy -0.22352 0.00508) (xy -0.22606 -0.00508)
						(xy -0.22733 -0.01651) (xy -0.22733 -0.02667) (xy -0.2286 -0.0381) (xy -0.22733 -0.04953) (xy -0.22733 -0.05969)
						(xy -0.22606 -0.07112) (xy -0.22352 -0.08128) (xy -0.22225 -0.09144) (xy -0.21844 -0.10287) (xy -0.2159 -0.11303)
						(xy -0.21209 -0.12319) (xy -0.20701 -0.13335) (xy -0.2032 -0.14224) (xy -0.19812 -0.1524) (xy -0.17272 -0.18796)
						(xy -0.1651 -0.19558) (xy -0.1651 -0.7366) (xy -0.16256 -0.76835) (xy -0.1524 -0.8001) (xy -0.13716 -0.82804)
						(xy -0.11684 -0.85344) (xy -0.09144 -0.87376) (xy -0.0635 -0.889) (xy -0.03175 -0.89916) (xy 0 -0.9017)
						(xy 0.03175 -0.89916) (xy 0.0635 -0.889) (xy 0.09144 -0.87376) (xy 0.11684 -0.85344) (xy 0.13716 -0.82804)
						(xy 0.1524 -0.8001) (xy 0.16256 -0.76835) (xy 0.1651 -0.7366) (xy 0.1651 -0.19685) (xy 0.17272 -0.18923)
						(xy 0.17907 -0.18034) (xy 0.18669 -0.17145) (xy 0.19177 -0.16256) (xy 0.19812 -0.15367) (xy 0.20828 -0.13335)
						(xy 0.21971 -0.10287) (xy 0.22225 -0.09271) (xy 0.22479 -0.08128) (xy 0.22606 -0.07112) (xy 0.2286 -0.05969)
						(xy 0.2286 -0.01651) (xy 0.22606 -0.00508) (xy 0.22479 0.00508) (xy 0.22225 0.01651) (xy 0.21971 0.02667)
						(xy 0.20828 0.05715) (xy 0.19812 0.07747) (xy 0.19177 0.08636) (xy 0.18669 0.09525) (xy 0.17907 0.10414)
						(xy 0.17272 0.11303) (xy 0.1651 0.12065) (xy 0.1651 0.7366) (xy 0.16256 0.76835) (xy 0.1524 0.8001)
						(xy 0.13716 0.82804) (xy 0.11684 0.85344) (xy 0.09144 0.87376) (xy 0.0635 0.889) (xy 0.03175 0.89916)
					)
					(width 0)
					(fill yes)
				)
			)
		)
		(pad "68" smd custom
			(at -11.549888 -4.106672)
			(size 0.1143 0.1143)
			(layers "F.Cu" "F.Mask" "F.Paste")
			(net "M_B_DQ27")
			(options
				(clearance outline)
				(anchor circle)
			)
			(primitives
				(gr_poly
					(pts
						(xy 0 0.9017) (xy -0.03175 0.89916) (xy -0.0635 0.889) (xy -0.09144 0.87376) (xy -0.11684 0.85344)
						(xy -0.13716 0.82804) (xy -0.1524 0.8001) (xy -0.16256 0.76835) (xy -0.1651 0.7366) (xy -0.1651 0.19685)
						(xy -0.17272 0.18923) (xy -0.17907 0.18034) (xy -0.18669 0.17145) (xy -0.19177 0.16256) (xy -0.19812 0.15367)
						(xy -0.20828 0.13335) (xy -0.21971 0.10287) (xy -0.22225 0.09271) (xy -0.22479 0.08128) (xy -0.22606 0.07112)
						(xy -0.2286 0.05969) (xy -0.2286 0.01651) (xy -0.22606 0.00508) (xy -0.22479 -0.00508) (xy -0.22225 -0.01651)
						(xy -0.21971 -0.02667) (xy -0.20828 -0.05715) (xy -0.19812 -0.07747) (xy -0.19177 -0.08636) (xy -0.18669 -0.09525)
						(xy -0.17907 -0.10414) (xy -0.17272 -0.11303) (xy -0.1651 -0.12065) (xy -0.1651 -0.7366) (xy -0.16256 -0.76835)
						(xy -0.1524 -0.8001) (xy -0.13716 -0.82804) (xy -0.11684 -0.85344) (xy -0.09144 -0.87376) (xy -0.0635 -0.889)
						(xy -0.03175 -0.89916) (xy 0 -0.9017) (xy 0.03175 -0.89916) (xy 0.0635 -0.889) (xy 0.09144 -0.87376)
						(xy 0.11684 -0.85344) (xy 0.13716 -0.82804) (xy 0.1524 -0.8001) (xy 0.16256 -0.76835) (xy 0.1651 -0.7366)
						(xy 0.1651 -0.11938) (xy 0.17272 -0.11176) (xy 0.19812 -0.0762) (xy 0.2032 -0.06604) (xy 0.20701 -0.05715)
						(xy 0.21209 -0.04699) (xy 0.2159 -0.03683) (xy 0.21844 -0.02667) (xy 0.22225 -0.01524) (xy 0.22352 -0.00508)
						(xy 0.22606 0.00508) (xy 0.22733 0.01651) (xy 0.22733 0.02667) (xy 0.2286 0.0381) (xy 0.22733 0.04953)
						(xy 0.22733 0.05969) (xy 0.22606 0.07112) (xy 0.22352 0.08128) (xy 0.22225 0.09144) (xy 0.21844 0.10287)
						(xy 0.2159 0.11303) (xy 0.21209 0.12319) (xy 0.20701 0.13335) (xy 0.2032 0.14224) (xy 0.19812 0.1524)
						(xy 0.17272 0.18796) (xy 0.1651 0.19558) (xy 0.1651 0.7366) (xy 0.16256 0.76835) (xy 0.1524 0.8001)
						(xy 0.13716 0.82804) (xy 0.11684 0.85344) (xy 0.09144 0.87376) (xy 0.0635 0.889) (xy 0.03175 0.89916)
					)
					(width 0)
					(fill yes)
				)
			)
		)
		(pad "69" smd custom
			(at -11.249914 4.106672)
			(size 0.1143 0.1143)
			(layers "F.Cu" "F.Mask" "F.Paste")
			(net "M_B_ECC4")
			(options
				(clearance outline)
				(anchor circle)
			)
			(primitives
				(gr_poly
					(pts
						(xy 0 0.9017) (xy -0.03175 0.89916) (xy -0.0635 0.889) (xy -0.09144 0.87376) (xy -0.11684 0.85344)
						(xy -0.13716 0.82804) (xy -0.1524 0.8001) (xy -0.16256 0.76835) (xy -0.1651 0.7366) (xy -0.1651 -0.13462)
						(xy -0.17272 -0.14224) (xy -0.19812 -0.1778) (xy -0.2032 -0.18796) (xy -0.20701 -0.19685) (xy -0.21209 -0.20701)
						(xy -0.2159 -0.21717) (xy -0.21844 -0.22733) (xy -0.22225 -0.23876) (xy -0.22352 -0.24892) (xy -0.22606 -0.25908)
						(xy -0.22733 -0.27051) (xy -0.22733 -0.28067) (xy -0.2286 -0.2921) (xy -0.22733 -0.30353) (xy -0.22733 -0.31369)
						(xy -0.22606 -0.32512) (xy -0.22352 -0.33528) (xy -0.22225 -0.34544) (xy -0.21844 -0.35687) (xy -0.2159 -0.36703)
						(xy -0.21209 -0.37719) (xy -0.20701 -0.38735) (xy -0.2032 -0.39624) (xy -0.19812 -0.4064) (xy -0.17272 -0.44196)
						(xy -0.1651 -0.44958) (xy -0.1651 -0.7366) (xy -0.16256 -0.76835) (xy -0.1524 -0.8001) (xy -0.13716 -0.82804)
						(xy -0.11684 -0.85344) (xy -0.09144 -0.87376) (xy -0.0635 -0.889) (xy -0.03175 -0.89916) (xy 0 -0.9017)
						(xy 0.03175 -0.89916) (xy 0.0635 -0.889) (xy 0.09144 -0.87376) (xy 0.11684 -0.85344) (xy 0.13716 -0.82804)
						(xy 0.1524 -0.8001) (xy 0.16256 -0.76835) (xy 0.1651 -0.7366) (xy 0.1651 -0.44958) (xy 0.17272 -0.44196)
						(xy 0.19812 -0.4064) (xy 0.2032 -0.39624) (xy 0.20701 -0.38735) (xy 0.21209 -0.37719) (xy 0.2159 -0.36703)
						(xy 0.21844 -0.35687) (xy 0.22225 -0.34544) (xy 0.22352 -0.33528) (xy 0.22606 -0.32512) (xy 0.22733 -0.31369)
						(xy 0.22733 -0.30353) (xy 0.2286 -0.2921) (xy 0.22733 -0.28067) (xy 0.22733 -0.27051) (xy 0.22606 -0.25908)
						(xy 0.22352 -0.24892) (xy 0.22225 -0.23876) (xy 0.21844 -0.22733) (xy 0.2159 -0.21717) (xy 0.21209 -0.20701)
						(xy 0.20701 -0.19685) (xy 0.2032 -0.18796) (xy 0.19812 -0.1778) (xy 0.17272 -0.14224) (xy 0.1651 -0.13462)
						(xy 0.1651 0.7366) (xy 0.16256 0.76835) (xy 0.1524 0.8001) (xy 0.13716 0.82804) (xy 0.11684 0.85344)
						(xy 0.09144 0.87376) (xy 0.0635 0.889) (xy 0.03175 0.89916)
					)
					(width 0)
					(fill yes)
				)
			)
		)
		(pad "70" smd custom
			(at -10.94994 -4.106672)
			(size 0.1143 0.1143)
			(layers "F.Cu" "F.Mask" "F.Paste")
			(net "GND")
			(options
				(clearance outline)
				(anchor circle)
			)
			(primitives
				(gr_poly
					(pts
						(xy 0 0.9017) (xy -0.03175 0.89916) (xy -0.0635 0.889) (xy -0.09144 0.87376) (xy -0.11684 0.85344)
						(xy -0.13716 0.82804) (xy -0.1524 0.8001) (xy -0.16256 0.76835) (xy -0.1651 0.7366) (xy -0.1651 0.44958)
						(xy -0.17272 0.44196) (xy -0.19812 0.4064) (xy -0.2032 0.39624) (xy -0.20701 0.38735) (xy -0.21209 0.37719)
						(xy -0.2159 0.36703) (xy -0.21844 0.35687) (xy -0.22225 0.34544) (xy -0.22352 0.33528) (xy -0.22606 0.32512)
						(xy -0.22733 0.31369) (xy -0.22733 0.30353) (xy -0.2286 0.2921) (xy -0.22733 0.28067) (xy -0.22733 0.27051)
						(xy -0.22606 0.25908) (xy -0.22352 0.24892) (xy -0.22225 0.23876) (xy -0.21844 0.22733) (xy -0.2159 0.21717)
						(xy -0.21209 0.20701) (xy -0.20701 0.19685) (xy -0.2032 0.18796) (xy -0.19812 0.1778) (xy -0.17272 0.14224)
						(xy -0.1651 0.13462) (xy -0.1651 -0.7366) (xy -0.16256 -0.76835) (xy -0.1524 -0.8001) (xy -0.13716 -0.82804)
						(xy -0.11684 -0.85344) (xy -0.09144 -0.87376) (xy -0.0635 -0.889) (xy -0.03175 -0.89916) (xy 0 -0.9017)
						(xy 0.03175 -0.89916) (xy 0.0635 -0.889) (xy 0.09144 -0.87376) (xy 0.11684 -0.85344) (xy 0.13716 -0.82804)
						(xy 0.1524 -0.8001) (xy 0.16256 -0.76835) (xy 0.1651 -0.7366) (xy 0.1651 0.13462) (xy 0.17272 0.14224)
						(xy 0.19812 0.1778) (xy 0.2032 0.18796) (xy 0.20701 0.19685) (xy 0.21209 0.20701) (xy 0.2159 0.21717)
						(xy 0.21844 0.22733) (xy 0.22225 0.23876) (xy 0.22352 0.24892) (xy 0.22606 0.25908) (xy 0.22733 0.27051)
						(xy 0.22733 0.28067) (xy 0.2286 0.2921) (xy 0.22733 0.30353) (xy 0.22733 0.31369) (xy 0.22606 0.32512)
						(xy 0.22352 0.33528) (xy 0.22225 0.34544) (xy 0.21844 0.35687) (xy 0.2159 0.36703) (xy 0.21209 0.37719)
						(xy 0.20701 0.38735) (xy 0.2032 0.39624) (xy 0.19812 0.4064) (xy 0.17272 0.44196) (xy 0.1651 0.44958)
						(xy 0.1651 0.7366) (xy 0.16256 0.76835) (xy 0.1524 0.8001) (xy 0.13716 0.82804) (xy 0.11684 0.85344)
						(xy 0.09144 0.87376) (xy 0.0635 0.889) (xy 0.03175 0.89916)
					)
					(width 0)
					(fill yes)
				)
			)
		)
		(pad "71" smd custom
			(at -10.649966 4.106672)
			(size 0.1143 0.1143)
			(layers "F.Cu" "F.Mask" "F.Paste")
			(net "M_B_ECC5")
			(options
				(clearance outline)
				(anchor circle)
			)
			(primitives
				(gr_poly
					(pts
						(xy 0 0.9017) (xy -0.03175 0.89916) (xy -0.0635 0.889) (xy -0.09144 0.87376) (xy -0.11684 0.85344)
						(xy -0.13716 0.82804) (xy -0.1524 0.8001) (xy -0.16256 0.76835) (xy -0.1651 0.7366) (xy -0.1651 0.11938)
						(xy -0.17272 0.11176) (xy -0.19812 0.0762) (xy -0.2032 0.06604) (xy -0.20701 0.05715) (xy -0.21209 0.04699)
						(xy -0.2159 0.03683) (xy -0.21844 0.02667) (xy -0.22225 0.01524) (xy -0.22352 0.00508) (xy -0.22606 -0.00508)
						(xy -0.22733 -0.01651) (xy -0.22733 -0.02667) (xy -0.2286 -0.0381) (xy -0.22733 -0.04953) (xy -0.22733 -0.05969)
						(xy -0.22606 -0.07112) (xy -0.22352 -0.08128) (xy -0.22225 -0.09144) (xy -0.21844 -0.10287) (xy -0.2159 -0.11303)
						(xy -0.21209 -0.12319) (xy -0.20701 -0.13335) (xy -0.2032 -0.14224) (xy -0.19812 -0.1524) (xy -0.17272 -0.18796)
						(xy -0.1651 -0.19558) (xy -0.1651 -0.7366) (xy -0.16256 -0.76835) (xy -0.1524 -0.8001) (xy -0.13716 -0.82804)
						(xy -0.11684 -0.85344) (xy -0.09144 -0.87376) (xy -0.0635 -0.889) (xy -0.03175 -0.89916) (xy 0 -0.9017)
						(xy 0.03175 -0.89916) (xy 0.0635 -0.889) (xy 0.09144 -0.87376) (xy 0.11684 -0.85344) (xy 0.13716 -0.82804)
						(xy 0.1524 -0.8001) (xy 0.16256 -0.76835) (xy 0.1651 -0.7366) (xy 0.1651 -0.19685) (xy 0.17272 -0.18923)
						(xy 0.17907 -0.18034) (xy 0.18669 -0.17145) (xy 0.19177 -0.16256) (xy 0.19812 -0.15367) (xy 0.20828 -0.13335)
						(xy 0.21971 -0.10287) (xy 0.22225 -0.09271) (xy 0.22479 -0.08128) (xy 0.22606 -0.07112) (xy 0.2286 -0.05969)
						(xy 0.2286 -0.01651) (xy 0.22606 -0.00508) (xy 0.22479 0.00508) (xy 0.22225 0.01651) (xy 0.21971 0.02667)
						(xy 0.20828 0.05715) (xy 0.19812 0.07747) (xy 0.19177 0.08636) (xy 0.18669 0.09525) (xy 0.17907 0.10414)
						(xy 0.17272 0.11303) (xy 0.1651 0.12065) (xy 0.1651 0.7366) (xy 0.16256 0.76835) (xy 0.1524 0.8001)
						(xy 0.13716 0.82804) (xy 0.11684 0.85344) (xy 0.09144 0.87376) (xy 0.0635 0.889) (xy 0.03175 0.89916)
					)
					(width 0)
					(fill yes)
				)
			)
		)
		(pad "72" smd custom
			(at -10.349992 -4.106672)
			(size 0.1143 0.1143)
			(layers "F.Cu" "F.Mask" "F.Paste")
			(net "M_B_ECC0")
			(options
				(clearance outline)
				(anchor circle)
			)
			(primitives
				(gr_poly
					(pts
						(xy 0 0.9017) (xy -0.03175 0.89916) (xy -0.0635 0.889) (xy -0.09144 0.87376) (xy -0.11684 0.85344)
						(xy -0.13716 0.82804) (xy -0.1524 0.8001) (xy -0.16256 0.76835) (xy -0.1651 0.7366) (xy -0.1651 0.19685)
						(xy -0.17272 0.18923) (xy -0.17907 0.18034) (xy -0.18669 0.17145) (xy -0.19177 0.16256) (xy -0.19812 0.15367)
						(xy -0.20828 0.13335) (xy -0.21971 0.10287) (xy -0.22225 0.09271) (xy -0.22479 0.08128) (xy -0.22606 0.07112)
						(xy -0.2286 0.05969) (xy -0.2286 0.01651) (xy -0.22606 0.00508) (xy -0.22479 -0.00508) (xy -0.22225 -0.01651)
						(xy -0.21971 -0.02667) (xy -0.20828 -0.05715) (xy -0.19812 -0.07747) (xy -0.19177 -0.08636) (xy -0.18669 -0.09525)
						(xy -0.17907 -0.10414) (xy -0.17272 -0.11303) (xy -0.1651 -0.12065) (xy -0.1651 -0.7366) (xy -0.16256 -0.76835)
						(xy -0.1524 -0.8001) (xy -0.13716 -0.82804) (xy -0.11684 -0.85344) (xy -0.09144 -0.87376) (xy -0.0635 -0.889)
						(xy -0.03175 -0.89916) (xy 0 -0.9017) (xy 0.03175 -0.89916) (xy 0.0635 -0.889) (xy 0.09144 -0.87376)
						(xy 0.11684 -0.85344) (xy 0.13716 -0.82804) (xy 0.1524 -0.8001) (xy 0.16256 -0.76835) (xy 0.1651 -0.7366)
						(xy 0.1651 -0.11938) (xy 0.17272 -0.11176) (xy 0.19812 -0.0762) (xy 0.2032 -0.06604) (xy 0.20701 -0.05715)
						(xy 0.21209 -0.04699) (xy 0.2159 -0.03683) (xy 0.21844 -0.02667) (xy 0.22225 -0.01524) (xy 0.22352 -0.00508)
						(xy 0.22606 0.00508) (xy 0.22733 0.01651) (xy 0.22733 0.02667) (xy 0.2286 0.0381) (xy 0.22733 0.04953)
						(xy 0.22733 0.05969) (xy 0.22606 0.07112) (xy 0.22352 0.08128) (xy 0.22225 0.09144) (xy 0.21844 0.10287)
						(xy 0.2159 0.11303) (xy 0.21209 0.12319) (xy 0.20701 0.13335) (xy 0.2032 0.14224) (xy 0.19812 0.1524)
						(xy 0.17272 0.18796) (xy 0.1651 0.19558) (xy 0.1651 0.7366) (xy 0.16256 0.76835) (xy 0.1524 0.8001)
						(xy 0.13716 0.82804) (xy 0.11684 0.85344) (xy 0.09144 0.87376) (xy 0.0635 0.889) (xy 0.03175 0.89916)
					)
					(width 0)
					(fill yes)
				)
			)
		)
		(pad "73" smd custom
			(at -7.649972 4.106672)
			(size 0.1143 0.1143)
			(layers "F.Cu" "F.Mask" "F.Paste")
			(net "GND")
			(options
				(clearance outline)
				(anchor circle)
			)
			(primitives
				(gr_poly
					(pts
						(xy 0 0.9017) (xy -0.03175 0.89916) (xy -0.0635 0.889) (xy -0.09144 0.87376) (xy -0.11684 0.85344)
						(xy -0.13716 0.82804) (xy -0.1524 0.8001) (xy -0.16256 0.76835) (xy -0.1651 0.7366) (xy -0.1651 -0.13462)
						(xy -0.17272 -0.14224) (xy -0.19812 -0.1778) (xy -0.2032 -0.18796) (xy -0.20701 -0.19685) (xy -0.21209 -0.20701)
						(xy -0.2159 -0.21717) (xy -0.21844 -0.22733) (xy -0.22225 -0.23876) (xy -0.22352 -0.24892) (xy -0.22606 -0.25908)
						(xy -0.22733 -0.27051) (xy -0.22733 -0.28067) (xy -0.2286 -0.2921) (xy -0.22733 -0.30353) (xy -0.22733 -0.31369)
						(xy -0.22606 -0.32512) (xy -0.22352 -0.33528) (xy -0.22225 -0.34544) (xy -0.21844 -0.35687) (xy -0.2159 -0.36703)
						(xy -0.21209 -0.37719) (xy -0.20701 -0.38735) (xy -0.2032 -0.39624) (xy -0.19812 -0.4064) (xy -0.17272 -0.44196)
						(xy -0.1651 -0.44958) (xy -0.1651 -0.7366) (xy -0.16256 -0.76835) (xy -0.1524 -0.8001) (xy -0.13716 -0.82804)
						(xy -0.11684 -0.85344) (xy -0.09144 -0.87376) (xy -0.0635 -0.889) (xy -0.03175 -0.89916) (xy 0 -0.9017)
						(xy 0.03175 -0.89916) (xy 0.0635 -0.889) (xy 0.09144 -0.87376) (xy 0.11684 -0.85344) (xy 0.13716 -0.82804)
						(xy 0.1524 -0.8001) (xy 0.16256 -0.76835) (xy 0.1651 -0.7366) (xy 0.1651 -0.44958) (xy 0.17272 -0.44196)
						(xy 0.19812 -0.4064) (xy 0.2032 -0.39624) (xy 0.20701 -0.38735) (xy 0.21209 -0.37719) (xy 0.2159 -0.36703)
						(xy 0.21844 -0.35687) (xy 0.22225 -0.34544) (xy 0.22352 -0.33528) (xy 0.22606 -0.32512) (xy 0.22733 -0.31369)
						(xy 0.22733 -0.30353) (xy 0.2286 -0.2921) (xy 0.22733 -0.28067) (xy 0.22733 -0.27051) (xy 0.22606 -0.25908)
						(xy 0.22352 -0.24892) (xy 0.22225 -0.23876) (xy 0.21844 -0.22733) (xy 0.2159 -0.21717) (xy 0.21209 -0.20701)
						(xy 0.20701 -0.19685) (xy 0.2032 -0.18796) (xy 0.19812 -0.1778) (xy 0.17272 -0.14224) (xy 0.1651 -0.13462)
						(xy 0.1651 0.7366) (xy 0.16256 0.76835) (xy 0.1524 0.8001) (xy 0.13716 0.82804) (xy 0.11684 0.85344)
						(xy 0.09144 0.87376) (xy 0.0635 0.889) (xy 0.03175 0.89916)
					)
					(width 0)
					(fill yes)
				)
			)
		)
		(pad "74" smd custom
			(at -7.349998 -4.106672)
			(size 0.1143 0.1143)
			(layers "F.Cu" "F.Mask" "F.Paste")
			(net "M_B_ECC1")
			(options
				(clearance outline)
				(anchor circle)
			)
			(primitives
				(gr_poly
					(pts
						(xy 0 0.9017) (xy -0.03175 0.89916) (xy -0.0635 0.889) (xy -0.09144 0.87376) (xy -0.11684 0.85344)
						(xy -0.13716 0.82804) (xy -0.1524 0.8001) (xy -0.16256 0.76835) (xy -0.1651 0.7366) (xy -0.1651 0.44958)
						(xy -0.17272 0.44196) (xy -0.19812 0.4064) (xy -0.2032 0.39624) (xy -0.20701 0.38735) (xy -0.21209 0.37719)
						(xy -0.2159 0.36703) (xy -0.21844 0.35687) (xy -0.22225 0.34544) (xy -0.22352 0.33528) (xy -0.22606 0.32512)
						(xy -0.22733 0.31369) (xy -0.22733 0.30353) (xy -0.2286 0.2921) (xy -0.22733 0.28067) (xy -0.22733 0.27051)
						(xy -0.22606 0.25908) (xy -0.22352 0.24892) (xy -0.22225 0.23876) (xy -0.21844 0.22733) (xy -0.2159 0.21717)
						(xy -0.21209 0.20701) (xy -0.20701 0.19685) (xy -0.2032 0.18796) (xy -0.19812 0.1778) (xy -0.17272 0.14224)
						(xy -0.1651 0.13462) (xy -0.1651 -0.7366) (xy -0.16256 -0.76835) (xy -0.1524 -0.8001) (xy -0.13716 -0.82804)
						(xy -0.11684 -0.85344) (xy -0.09144 -0.87376) (xy -0.0635 -0.889) (xy -0.03175 -0.89916) (xy 0 -0.9017)
						(xy 0.03175 -0.89916) (xy 0.0635 -0.889) (xy 0.09144 -0.87376) (xy 0.11684 -0.85344) (xy 0.13716 -0.82804)
						(xy 0.1524 -0.8001) (xy 0.16256 -0.76835) (xy 0.1651 -0.7366) (xy 0.1651 0.13462) (xy 0.17272 0.14224)
						(xy 0.19812 0.1778) (xy 0.2032 0.18796) (xy 0.20701 0.19685) (xy 0.21209 0.20701) (xy 0.2159 0.21717)
						(xy 0.21844 0.22733) (xy 0.22225 0.23876) (xy 0.22352 0.24892) (xy 0.22606 0.25908) (xy 0.22733 0.27051)
						(xy 0.22733 0.28067) (xy 0.2286 0.2921) (xy 0.22733 0.30353) (xy 0.22733 0.31369) (xy 0.22606 0.32512)
						(xy 0.22352 0.33528) (xy 0.22225 0.34544) (xy 0.21844 0.35687) (xy 0.2159 0.36703) (xy 0.21209 0.37719)
						(xy 0.20701 0.38735) (xy 0.2032 0.39624) (xy 0.19812 0.4064) (xy 0.17272 0.44196) (xy 0.1651 0.44958)
						(xy 0.1651 0.7366) (xy 0.16256 0.76835) (xy 0.1524 0.8001) (xy 0.13716 0.82804) (xy 0.11684 0.85344)
						(xy 0.09144 0.87376) (xy 0.0635 0.889) (xy 0.03175 0.89916)
					)
					(width 0)
					(fill yes)
				)
			)
		)
		(pad "75" smd custom
			(at -7.050024 4.106672)
			(size 0.1143 0.1143)
			(layers "F.Cu" "F.Mask" "F.Paste")
			(net "M_B_DQS_DN8")
			(options
				(clearance outline)
				(anchor circle)
			)
			(primitives
				(gr_poly
					(pts
						(xy 0 0.9017) (xy -0.03175 0.89916) (xy -0.0635 0.889) (xy -0.09144 0.87376) (xy -0.11684 0.85344)
						(xy -0.13716 0.82804) (xy -0.1524 0.8001) (xy -0.16256 0.76835) (xy -0.1651 0.7366) (xy -0.1651 0.11938)
						(xy -0.17272 0.11176) (xy -0.19812 0.0762) (xy -0.2032 0.06604) (xy -0.20701 0.05715) (xy -0.21209 0.04699)
						(xy -0.2159 0.03683) (xy -0.21844 0.02667) (xy -0.22225 0.01524) (xy -0.22352 0.00508) (xy -0.22606 -0.00508)
						(xy -0.22733 -0.01651) (xy -0.22733 -0.02667) (xy -0.2286 -0.0381) (xy -0.22733 -0.04953) (xy -0.22733 -0.05969)
						(xy -0.22606 -0.07112) (xy -0.22352 -0.08128) (xy -0.22225 -0.09144) (xy -0.21844 -0.10287) (xy -0.2159 -0.11303)
						(xy -0.21209 -0.12319) (xy -0.20701 -0.13335) (xy -0.2032 -0.14224) (xy -0.19812 -0.1524) (xy -0.17272 -0.18796)
						(xy -0.1651 -0.19558) (xy -0.1651 -0.7366) (xy -0.16256 -0.76835) (xy -0.1524 -0.8001) (xy -0.13716 -0.82804)
						(xy -0.11684 -0.85344) (xy -0.09144 -0.87376) (xy -0.0635 -0.889) (xy -0.03175 -0.89916) (xy 0 -0.9017)
						(xy 0.03175 -0.89916) (xy 0.0635 -0.889) (xy 0.09144 -0.87376) (xy 0.11684 -0.85344) (xy 0.13716 -0.82804)
						(xy 0.1524 -0.8001) (xy 0.16256 -0.76835) (xy 0.1651 -0.7366) (xy 0.1651 -0.19685) (xy 0.17272 -0.18923)
						(xy 0.17907 -0.18034) (xy 0.18669 -0.17145) (xy 0.19177 -0.16256) (xy 0.19812 -0.15367) (xy 0.20828 -0.13335)
						(xy 0.21971 -0.10287) (xy 0.22225 -0.09271) (xy 0.22479 -0.08128) (xy 0.22606 -0.07112) (xy 0.2286 -0.05969)
						(xy 0.2286 -0.01651) (xy 0.22606 -0.00508) (xy 0.22479 0.00508) (xy 0.22225 0.01651) (xy 0.21971 0.02667)
						(xy 0.20828 0.05715) (xy 0.19812 0.07747) (xy 0.19177 0.08636) (xy 0.18669 0.09525) (xy 0.17907 0.10414)
						(xy 0.17272 0.11303) (xy 0.1651 0.12065) (xy 0.1651 0.7366) (xy 0.16256 0.76835) (xy 0.1524 0.8001)
						(xy 0.13716 0.82804) (xy 0.11684 0.85344) (xy 0.09144 0.87376) (xy 0.0635 0.889) (xy 0.03175 0.89916)
					)
					(width 0)
					(fill yes)
				)
			)
		)
		(pad "76" smd custom
			(at -6.75005 -4.106672)
			(size 0.1143 0.1143)
			(layers "F.Cu" "F.Mask" "F.Paste")
			(net "GND")
			(options
				(clearance outline)
				(anchor circle)
			)
			(primitives
				(gr_poly
					(pts
						(xy 0 0.9017) (xy -0.03175 0.89916) (xy -0.0635 0.889) (xy -0.09144 0.87376) (xy -0.11684 0.85344)
						(xy -0.13716 0.82804) (xy -0.1524 0.8001) (xy -0.16256 0.76835) (xy -0.1651 0.7366) (xy -0.1651 0.19685)
						(xy -0.17272 0.18923) (xy -0.17907 0.18034) (xy -0.18669 0.17145) (xy -0.19177 0.16256) (xy -0.19812 0.15367)
						(xy -0.20828 0.13335) (xy -0.21971 0.10287) (xy -0.22225 0.09271) (xy -0.22479 0.08128) (xy -0.22606 0.07112)
						(xy -0.2286 0.05969) (xy -0.2286 0.01651) (xy -0.22606 0.00508) (xy -0.22479 -0.00508) (xy -0.22225 -0.01651)
						(xy -0.21971 -0.02667) (xy -0.20828 -0.05715) (xy -0.19812 -0.07747) (xy -0.19177 -0.08636) (xy -0.18669 -0.09525)
						(xy -0.17907 -0.10414) (xy -0.17272 -0.11303) (xy -0.1651 -0.12065) (xy -0.1651 -0.7366) (xy -0.16256 -0.76835)
						(xy -0.1524 -0.8001) (xy -0.13716 -0.82804) (xy -0.11684 -0.85344) (xy -0.09144 -0.87376) (xy -0.0635 -0.889)
						(xy -0.03175 -0.89916) (xy 0 -0.9017) (xy 0.03175 -0.89916) (xy 0.0635 -0.889) (xy 0.09144 -0.87376)
						(xy 0.11684 -0.85344) (xy 0.13716 -0.82804) (xy 0.1524 -0.8001) (xy 0.16256 -0.76835) (xy 0.1651 -0.7366)
						(xy 0.1651 -0.11938) (xy 0.17272 -0.11176) (xy 0.19812 -0.0762) (xy 0.2032 -0.06604) (xy 0.20701 -0.05715)
						(xy 0.21209 -0.04699) (xy 0.2159 -0.03683) (xy 0.21844 -0.02667) (xy 0.22225 -0.01524) (xy 0.22352 -0.00508)
						(xy 0.22606 0.00508) (xy 0.22733 0.01651) (xy 0.22733 0.02667) (xy 0.2286 0.0381) (xy 0.22733 0.04953)
						(xy 0.22733 0.05969) (xy 0.22606 0.07112) (xy 0.22352 0.08128) (xy 0.22225 0.09144) (xy 0.21844 0.10287)
						(xy 0.2159 0.11303) (xy 0.21209 0.12319) (xy 0.20701 0.13335) (xy 0.2032 0.14224) (xy 0.19812 0.1524)
						(xy 0.17272 0.18796) (xy 0.1651 0.19558) (xy 0.1651 0.7366) (xy 0.16256 0.76835) (xy 0.1524 0.8001)
						(xy 0.13716 0.82804) (xy 0.11684 0.85344) (xy 0.09144 0.87376) (xy 0.0635 0.889) (xy 0.03175 0.89916)
					)
					(width 0)
					(fill yes)
				)
			)
		)
		(pad "77" smd custom
			(at -6.450076 4.106672)
			(size 0.1143 0.1143)
			(layers "F.Cu" "F.Mask" "F.Paste")
			(net "M_B_DQS_DP8")
			(options
				(clearance outline)
				(anchor circle)
			)
			(primitives
				(gr_poly
					(pts
						(xy 0 0.9017) (xy -0.03175 0.89916) (xy -0.0635 0.889) (xy -0.09144 0.87376) (xy -0.11684 0.85344)
						(xy -0.13716 0.82804) (xy -0.1524 0.8001) (xy -0.16256 0.76835) (xy -0.1651 0.7366) (xy -0.1651 -0.13462)
						(xy -0.17272 -0.14224) (xy -0.19812 -0.1778) (xy -0.2032 -0.18796) (xy -0.20701 -0.19685) (xy -0.21209 -0.20701)
						(xy -0.2159 -0.21717) (xy -0.21844 -0.22733) (xy -0.22225 -0.23876) (xy -0.22352 -0.24892) (xy -0.22606 -0.25908)
						(xy -0.22733 -0.27051) (xy -0.22733 -0.28067) (xy -0.2286 -0.2921) (xy -0.22733 -0.30353) (xy -0.22733 -0.31369)
						(xy -0.22606 -0.32512) (xy -0.22352 -0.33528) (xy -0.22225 -0.34544) (xy -0.21844 -0.35687) (xy -0.2159 -0.36703)
						(xy -0.21209 -0.37719) (xy -0.20701 -0.38735) (xy -0.2032 -0.39624) (xy -0.19812 -0.4064) (xy -0.17272 -0.44196)
						(xy -0.1651 -0.44958) (xy -0.1651 -0.7366) (xy -0.16256 -0.76835) (xy -0.1524 -0.8001) (xy -0.13716 -0.82804)
						(xy -0.11684 -0.85344) (xy -0.09144 -0.87376) (xy -0.0635 -0.889) (xy -0.03175 -0.89916) (xy 0 -0.9017)
						(xy 0.03175 -0.89916) (xy 0.0635 -0.889) (xy 0.09144 -0.87376) (xy 0.11684 -0.85344) (xy 0.13716 -0.82804)
						(xy 0.1524 -0.8001) (xy 0.16256 -0.76835) (xy 0.1651 -0.7366) (xy 0.1651 -0.44958) (xy 0.17272 -0.44196)
						(xy 0.19812 -0.4064) (xy 0.2032 -0.39624) (xy 0.20701 -0.38735) (xy 0.21209 -0.37719) (xy 0.2159 -0.36703)
						(xy 0.21844 -0.35687) (xy 0.22225 -0.34544) (xy 0.22352 -0.33528) (xy 0.22606 -0.32512) (xy 0.22733 -0.31369)
						(xy 0.22733 -0.30353) (xy 0.2286 -0.2921) (xy 0.22733 -0.28067) (xy 0.22733 -0.27051) (xy 0.22606 -0.25908)
						(xy 0.22352 -0.24892) (xy 0.22225 -0.23876) (xy 0.21844 -0.22733) (xy 0.2159 -0.21717) (xy 0.21209 -0.20701)
						(xy 0.20701 -0.19685) (xy 0.2032 -0.18796) (xy 0.19812 -0.1778) (xy 0.17272 -0.14224) (xy 0.1651 -0.13462)
						(xy 0.1651 0.7366) (xy 0.16256 0.76835) (xy 0.1524 0.8001) (xy 0.13716 0.82804) (xy 0.11684 0.85344)
						(xy 0.09144 0.87376) (xy 0.0635 0.889) (xy 0.03175 0.89916)
					)
					(width 0)
					(fill yes)
				)
			)
		)
		(pad "78" smd custom
			(at -6.150102 -4.106672)
			(size 0.1143 0.1143)
			(layers "F.Cu" "F.Mask" "F.Paste")
			(net "GND")
			(options
				(clearance outline)
				(anchor circle)
			)
			(primitives
				(gr_poly
					(pts
						(xy 0 0.9017) (xy -0.03175 0.89916) (xy -0.0635 0.889) (xy -0.09144 0.87376) (xy -0.11684 0.85344)
						(xy -0.13716 0.82804) (xy -0.1524 0.8001) (xy -0.16256 0.76835) (xy -0.1651 0.7366) (xy -0.1651 0.44958)
						(xy -0.17272 0.44196) (xy -0.19812 0.4064) (xy -0.2032 0.39624) (xy -0.20701 0.38735) (xy -0.21209 0.37719)
						(xy -0.2159 0.36703) (xy -0.21844 0.35687) (xy -0.22225 0.34544) (xy -0.22352 0.33528) (xy -0.22606 0.32512)
						(xy -0.22733 0.31369) (xy -0.22733 0.30353) (xy -0.2286 0.2921) (xy -0.22733 0.28067) (xy -0.22733 0.27051)
						(xy -0.22606 0.25908) (xy -0.22352 0.24892) (xy -0.22225 0.23876) (xy -0.21844 0.22733) (xy -0.2159 0.21717)
						(xy -0.21209 0.20701) (xy -0.20701 0.19685) (xy -0.2032 0.18796) (xy -0.19812 0.1778) (xy -0.17272 0.14224)
						(xy -0.1651 0.13462) (xy -0.1651 -0.7366) (xy -0.16256 -0.76835) (xy -0.1524 -0.8001) (xy -0.13716 -0.82804)
						(xy -0.11684 -0.85344) (xy -0.09144 -0.87376) (xy -0.0635 -0.889) (xy -0.03175 -0.89916) (xy 0 -0.9017)
						(xy 0.03175 -0.89916) (xy 0.0635 -0.889) (xy 0.09144 -0.87376) (xy 0.11684 -0.85344) (xy 0.13716 -0.82804)
						(xy 0.1524 -0.8001) (xy 0.16256 -0.76835) (xy 0.1651 -0.7366) (xy 0.1651 0.13462) (xy 0.17272 0.14224)
						(xy 0.19812 0.1778) (xy 0.2032 0.18796) (xy 0.20701 0.19685) (xy 0.21209 0.20701) (xy 0.2159 0.21717)
						(xy 0.21844 0.22733) (xy 0.22225 0.23876) (xy 0.22352 0.24892) (xy 0.22606 0.25908) (xy 0.22733 0.27051)
						(xy 0.22733 0.28067) (xy 0.2286 0.2921) (xy 0.22733 0.30353) (xy 0.22733 0.31369) (xy 0.22606 0.32512)
						(xy 0.22352 0.33528) (xy 0.22225 0.34544) (xy 0.21844 0.35687) (xy 0.2159 0.36703) (xy 0.21209 0.37719)
						(xy 0.20701 0.38735) (xy 0.2032 0.39624) (xy 0.19812 0.4064) (xy 0.17272 0.44196) (xy 0.1651 0.44958)
						(xy 0.1651 0.7366) (xy 0.16256 0.76835) (xy 0.1524 0.8001) (xy 0.13716 0.82804) (xy 0.11684 0.85344)
						(xy 0.09144 0.87376) (xy 0.0635 0.889) (xy 0.03175 0.89916)
					)
					(width 0)
					(fill yes)
				)
			)
		)
		(pad "79" smd custom
			(at -5.849874 4.106672)
			(size 0.1143 0.1143)
			(layers "F.Cu" "F.Mask" "F.Paste")
			(net "GND")
			(options
				(clearance outline)
				(anchor circle)
			)
			(primitives
				(gr_poly
					(pts
						(xy 0 0.9017) (xy -0.03175 0.89916) (xy -0.0635 0.889) (xy -0.09144 0.87376) (xy -0.11684 0.85344)
						(xy -0.13716 0.82804) (xy -0.1524 0.8001) (xy -0.16256 0.76835) (xy -0.1651 0.7366) (xy -0.1651 0.11938)
						(xy -0.17272 0.11176) (xy -0.19812 0.0762) (xy -0.2032 0.06604) (xy -0.20701 0.05715) (xy -0.21209 0.04699)
						(xy -0.2159 0.03683) (xy -0.21844 0.02667) (xy -0.22225 0.01524) (xy -0.22352 0.00508) (xy -0.22606 -0.00508)
						(xy -0.22733 -0.01651) (xy -0.22733 -0.02667) (xy -0.2286 -0.0381) (xy -0.22733 -0.04953) (xy -0.22733 -0.05969)
						(xy -0.22606 -0.07112) (xy -0.22352 -0.08128) (xy -0.22225 -0.09144) (xy -0.21844 -0.10287) (xy -0.2159 -0.11303)
						(xy -0.21209 -0.12319) (xy -0.20701 -0.13335) (xy -0.2032 -0.14224) (xy -0.19812 -0.1524) (xy -0.17272 -0.18796)
						(xy -0.1651 -0.19558) (xy -0.1651 -0.7366) (xy -0.16256 -0.76835) (xy -0.1524 -0.8001) (xy -0.13716 -0.82804)
						(xy -0.11684 -0.85344) (xy -0.09144 -0.87376) (xy -0.0635 -0.889) (xy -0.03175 -0.89916) (xy 0 -0.9017)
						(xy 0.03175 -0.89916) (xy 0.0635 -0.889) (xy 0.09144 -0.87376) (xy 0.11684 -0.85344) (xy 0.13716 -0.82804)
						(xy 0.1524 -0.8001) (xy 0.16256 -0.76835) (xy 0.1651 -0.7366) (xy 0.1651 -0.19685) (xy 0.17272 -0.18923)
						(xy 0.17907 -0.18034) (xy 0.18669 -0.17145) (xy 0.19177 -0.16256) (xy 0.19812 -0.15367) (xy 0.20828 -0.13335)
						(xy 0.21971 -0.10287) (xy 0.22225 -0.09271) (xy 0.22479 -0.08128) (xy 0.22606 -0.07112) (xy 0.2286 -0.05969)
						(xy 0.2286 -0.01651) (xy 0.22606 -0.00508) (xy 0.22479 0.00508) (xy 0.22225 0.01651) (xy 0.21971 0.02667)
						(xy 0.20828 0.05715) (xy 0.19812 0.07747) (xy 0.19177 0.08636) (xy 0.18669 0.09525) (xy 0.17907 0.10414)
						(xy 0.17272 0.11303) (xy 0.1651 0.12065) (xy 0.1651 0.7366) (xy 0.16256 0.76835) (xy 0.1524 0.8001)
						(xy 0.13716 0.82804) (xy 0.11684 0.85344) (xy 0.09144 0.87376) (xy 0.0635 0.889) (xy 0.03175 0.89916)
					)
					(width 0)
					(fill yes)
				)
			)
		)
		(pad "80" smd custom
			(at -5.5499 -4.106672)
			(size 0.1143 0.1143)
			(layers "F.Cu" "F.Mask" "F.Paste")
			(net "M_B_ECC2")
			(options
				(clearance outline)
				(anchor circle)
			)
			(primitives
				(gr_poly
					(pts
						(xy 0 0.9017) (xy -0.03175 0.89916) (xy -0.0635 0.889) (xy -0.09144 0.87376) (xy -0.11684 0.85344)
						(xy -0.13716 0.82804) (xy -0.1524 0.8001) (xy -0.16256 0.76835) (xy -0.1651 0.7366) (xy -0.1651 0.19685)
						(xy -0.17272 0.18923) (xy -0.17907 0.18034) (xy -0.18669 0.17145) (xy -0.19177 0.16256) (xy -0.19812 0.15367)
						(xy -0.20828 0.13335) (xy -0.21971 0.10287) (xy -0.22225 0.09271) (xy -0.22479 0.08128) (xy -0.22606 0.07112)
						(xy -0.2286 0.05969) (xy -0.2286 0.01651) (xy -0.22606 0.00508) (xy -0.22479 -0.00508) (xy -0.22225 -0.01651)
						(xy -0.21971 -0.02667) (xy -0.20828 -0.05715) (xy -0.19812 -0.07747) (xy -0.19177 -0.08636) (xy -0.18669 -0.09525)
						(xy -0.17907 -0.10414) (xy -0.17272 -0.11303) (xy -0.1651 -0.12065) (xy -0.1651 -0.7366) (xy -0.16256 -0.76835)
						(xy -0.1524 -0.8001) (xy -0.13716 -0.82804) (xy -0.11684 -0.85344) (xy -0.09144 -0.87376) (xy -0.0635 -0.889)
						(xy -0.03175 -0.89916) (xy 0 -0.9017) (xy 0.03175 -0.89916) (xy 0.0635 -0.889) (xy 0.09144 -0.87376)
						(xy 0.11684 -0.85344) (xy 0.13716 -0.82804) (xy 0.1524 -0.8001) (xy 0.16256 -0.76835) (xy 0.1651 -0.7366)
						(xy 0.1651 -0.11938) (xy 0.17272 -0.11176) (xy 0.19812 -0.0762) (xy 0.2032 -0.06604) (xy 0.20701 -0.05715)
						(xy 0.21209 -0.04699) (xy 0.2159 -0.03683) (xy 0.21844 -0.02667) (xy 0.22225 -0.01524) (xy 0.22352 -0.00508)
						(xy 0.22606 0.00508) (xy 0.22733 0.01651) (xy 0.22733 0.02667) (xy 0.2286 0.0381) (xy 0.22733 0.04953)
						(xy 0.22733 0.05969) (xy 0.22606 0.07112) (xy 0.22352 0.08128) (xy 0.22225 0.09144) (xy 0.21844 0.10287)
						(xy 0.2159 0.11303) (xy 0.21209 0.12319) (xy 0.20701 0.13335) (xy 0.2032 0.14224) (xy 0.19812 0.1524)
						(xy 0.17272 0.18796) (xy 0.1651 0.19558) (xy 0.1651 0.7366) (xy 0.16256 0.76835) (xy 0.1524 0.8001)
						(xy 0.13716 0.82804) (xy 0.11684 0.85344) (xy 0.09144 0.87376) (xy 0.0635 0.889) (xy 0.03175 0.89916)
					)
					(width 0)
					(fill yes)
				)
			)
		)
		(pad "81" smd custom
			(at -5.249926 4.106672)
			(size 0.1143 0.1143)
			(layers "F.Cu" "F.Mask" "F.Paste")
			(net "M_B_ECC6")
			(options
				(clearance outline)
				(anchor circle)
			)
			(primitives
				(gr_poly
					(pts
						(xy 0 0.9017) (xy -0.03175 0.89916) (xy -0.0635 0.889) (xy -0.09144 0.87376) (xy -0.11684 0.85344)
						(xy -0.13716 0.82804) (xy -0.1524 0.8001) (xy -0.16256 0.76835) (xy -0.1651 0.7366) (xy -0.1651 -0.13462)
						(xy -0.17272 -0.14224) (xy -0.19812 -0.1778) (xy -0.2032 -0.18796) (xy -0.20701 -0.19685) (xy -0.21209 -0.20701)
						(xy -0.2159 -0.21717) (xy -0.21844 -0.22733) (xy -0.22225 -0.23876) (xy -0.22352 -0.24892) (xy -0.22606 -0.25908)
						(xy -0.22733 -0.27051) (xy -0.22733 -0.28067) (xy -0.2286 -0.2921) (xy -0.22733 -0.30353) (xy -0.22733 -0.31369)
						(xy -0.22606 -0.32512) (xy -0.22352 -0.33528) (xy -0.22225 -0.34544) (xy -0.21844 -0.35687) (xy -0.2159 -0.36703)
						(xy -0.21209 -0.37719) (xy -0.20701 -0.38735) (xy -0.2032 -0.39624) (xy -0.19812 -0.4064) (xy -0.17272 -0.44196)
						(xy -0.1651 -0.44958) (xy -0.1651 -0.7366) (xy -0.16256 -0.76835) (xy -0.1524 -0.8001) (xy -0.13716 -0.82804)
						(xy -0.11684 -0.85344) (xy -0.09144 -0.87376) (xy -0.0635 -0.889) (xy -0.03175 -0.89916) (xy 0 -0.9017)
						(xy 0.03175 -0.89916) (xy 0.0635 -0.889) (xy 0.09144 -0.87376) (xy 0.11684 -0.85344) (xy 0.13716 -0.82804)
						(xy 0.1524 -0.8001) (xy 0.16256 -0.76835) (xy 0.1651 -0.7366) (xy 0.1651 -0.44958) (xy 0.17272 -0.44196)
						(xy 0.19812 -0.4064) (xy 0.2032 -0.39624) (xy 0.20701 -0.38735) (xy 0.21209 -0.37719) (xy 0.2159 -0.36703)
						(xy 0.21844 -0.35687) (xy 0.22225 -0.34544) (xy 0.22352 -0.33528) (xy 0.22606 -0.32512) (xy 0.22733 -0.31369)
						(xy 0.22733 -0.30353) (xy 0.2286 -0.2921) (xy 0.22733 -0.28067) (xy 0.22733 -0.27051) (xy 0.22606 -0.25908)
						(xy 0.22352 -0.24892) (xy 0.22225 -0.23876) (xy 0.21844 -0.22733) (xy 0.2159 -0.21717) (xy 0.21209 -0.20701)
						(xy 0.20701 -0.19685) (xy 0.2032 -0.18796) (xy 0.19812 -0.1778) (xy 0.17272 -0.14224) (xy 0.1651 -0.13462)
						(xy 0.1651 0.7366) (xy 0.16256 0.76835) (xy 0.1524 0.8001) (xy 0.13716 0.82804) (xy 0.11684 0.85344)
						(xy 0.09144 0.87376) (xy 0.0635 0.889) (xy 0.03175 0.89916)
					)
					(width 0)
					(fill yes)
				)
			)
		)
		(pad "82" smd custom
			(at -4.949952 -4.106672)
			(size 0.1143 0.1143)
			(layers "F.Cu" "F.Mask" "F.Paste")
			(net "M_B_ECC3")
			(options
				(clearance outline)
				(anchor circle)
			)
			(primitives
				(gr_poly
					(pts
						(xy 0 0.9017) (xy -0.03175 0.89916) (xy -0.0635 0.889) (xy -0.09144 0.87376) (xy -0.11684 0.85344)
						(xy -0.13716 0.82804) (xy -0.1524 0.8001) (xy -0.16256 0.76835) (xy -0.1651 0.7366) (xy -0.1651 0.44958)
						(xy -0.17272 0.44196) (xy -0.19812 0.4064) (xy -0.2032 0.39624) (xy -0.20701 0.38735) (xy -0.21209 0.37719)
						(xy -0.2159 0.36703) (xy -0.21844 0.35687) (xy -0.22225 0.34544) (xy -0.22352 0.33528) (xy -0.22606 0.32512)
						(xy -0.22733 0.31369) (xy -0.22733 0.30353) (xy -0.2286 0.2921) (xy -0.22733 0.28067) (xy -0.22733 0.27051)
						(xy -0.22606 0.25908) (xy -0.22352 0.24892) (xy -0.22225 0.23876) (xy -0.21844 0.22733) (xy -0.2159 0.21717)
						(xy -0.21209 0.20701) (xy -0.20701 0.19685) (xy -0.2032 0.18796) (xy -0.19812 0.1778) (xy -0.17272 0.14224)
						(xy -0.1651 0.13462) (xy -0.1651 -0.7366) (xy -0.16256 -0.76835) (xy -0.1524 -0.8001) (xy -0.13716 -0.82804)
						(xy -0.11684 -0.85344) (xy -0.09144 -0.87376) (xy -0.0635 -0.889) (xy -0.03175 -0.89916) (xy 0 -0.9017)
						(xy 0.03175 -0.89916) (xy 0.0635 -0.889) (xy 0.09144 -0.87376) (xy 0.11684 -0.85344) (xy 0.13716 -0.82804)
						(xy 0.1524 -0.8001) (xy 0.16256 -0.76835) (xy 0.1651 -0.7366) (xy 0.1651 0.13462) (xy 0.17272 0.14224)
						(xy 0.19812 0.1778) (xy 0.2032 0.18796) (xy 0.20701 0.19685) (xy 0.21209 0.20701) (xy 0.2159 0.21717)
						(xy 0.21844 0.22733) (xy 0.22225 0.23876) (xy 0.22352 0.24892) (xy 0.22606 0.25908) (xy 0.22733 0.27051)
						(xy 0.22733 0.28067) (xy 0.2286 0.2921) (xy 0.22733 0.30353) (xy 0.22733 0.31369) (xy 0.22606 0.32512)
						(xy 0.22352 0.33528) (xy 0.22225 0.34544) (xy 0.21844 0.35687) (xy 0.2159 0.36703) (xy 0.21209 0.37719)
						(xy 0.20701 0.38735) (xy 0.2032 0.39624) (xy 0.19812 0.4064) (xy 0.17272 0.44196) (xy 0.1651 0.44958)
						(xy 0.1651 0.7366) (xy 0.16256 0.76835) (xy 0.1524 0.8001) (xy 0.13716 0.82804) (xy 0.11684 0.85344)
						(xy 0.09144 0.87376) (xy 0.0635 0.889) (xy 0.03175 0.89916)
					)
					(width 0)
					(fill yes)
				)
			)
		)
		(pad "83" smd custom
			(at -4.649978 4.106672)
			(size 0.1143 0.1143)
			(layers "F.Cu" "F.Mask" "F.Paste")
			(net "M_B_ECC7")
			(options
				(clearance outline)
				(anchor circle)
			)
			(primitives
				(gr_poly
					(pts
						(xy 0 0.9017) (xy -0.03175 0.89916) (xy -0.0635 0.889) (xy -0.09144 0.87376) (xy -0.11684 0.85344)
						(xy -0.13716 0.82804) (xy -0.1524 0.8001) (xy -0.16256 0.76835) (xy -0.1651 0.7366) (xy -0.1651 0.11938)
						(xy -0.17272 0.11176) (xy -0.19812 0.0762) (xy -0.2032 0.06604) (xy -0.20701 0.05715) (xy -0.21209 0.04699)
						(xy -0.2159 0.03683) (xy -0.21844 0.02667) (xy -0.22225 0.01524) (xy -0.22352 0.00508) (xy -0.22606 -0.00508)
						(xy -0.22733 -0.01651) (xy -0.22733 -0.02667) (xy -0.2286 -0.0381) (xy -0.22733 -0.04953) (xy -0.22733 -0.05969)
						(xy -0.22606 -0.07112) (xy -0.22352 -0.08128) (xy -0.22225 -0.09144) (xy -0.21844 -0.10287) (xy -0.2159 -0.11303)
						(xy -0.21209 -0.12319) (xy -0.20701 -0.13335) (xy -0.2032 -0.14224) (xy -0.19812 -0.1524) (xy -0.17272 -0.18796)
						(xy -0.1651 -0.19558) (xy -0.1651 -0.7366) (xy -0.16256 -0.76835) (xy -0.1524 -0.8001) (xy -0.13716 -0.82804)
						(xy -0.11684 -0.85344) (xy -0.09144 -0.87376) (xy -0.0635 -0.889) (xy -0.03175 -0.89916) (xy 0 -0.9017)
						(xy 0.03175 -0.89916) (xy 0.0635 -0.889) (xy 0.09144 -0.87376) (xy 0.11684 -0.85344) (xy 0.13716 -0.82804)
						(xy 0.1524 -0.8001) (xy 0.16256 -0.76835) (xy 0.1651 -0.7366) (xy 0.1651 -0.19685) (xy 0.17272 -0.18923)
						(xy 0.17907 -0.18034) (xy 0.18669 -0.17145) (xy 0.19177 -0.16256) (xy 0.19812 -0.15367) (xy 0.20828 -0.13335)
						(xy 0.21971 -0.10287) (xy 0.22225 -0.09271) (xy 0.22479 -0.08128) (xy 0.22606 -0.07112) (xy 0.2286 -0.05969)
						(xy 0.2286 -0.01651) (xy 0.22606 -0.00508) (xy 0.22479 0.00508) (xy 0.22225 0.01651) (xy 0.21971 0.02667)
						(xy 0.20828 0.05715) (xy 0.19812 0.07747) (xy 0.19177 0.08636) (xy 0.18669 0.09525) (xy 0.17907 0.10414)
						(xy 0.17272 0.11303) (xy 0.1651 0.12065) (xy 0.1651 0.7366) (xy 0.16256 0.76835) (xy 0.1524 0.8001)
						(xy 0.13716 0.82804) (xy 0.11684 0.85344) (xy 0.09144 0.87376) (xy 0.0635 0.889) (xy 0.03175 0.89916)
					)
					(width 0)
					(fill yes)
				)
			)
		)
		(pad "84" smd custom
			(at -4.350004 -4.106672)
			(size 0.1143 0.1143)
			(layers "F.Cu" "F.Mask" "F.Paste")
			(net "DDR3_M_B_VREF_CA")
			(options
				(clearance outline)
				(anchor circle)
			)
			(primitives
				(gr_poly
					(pts
						(xy 0 0.9017) (xy -0.03175 0.89916) (xy -0.0635 0.889) (xy -0.09144 0.87376) (xy -0.11684 0.85344)
						(xy -0.13716 0.82804) (xy -0.1524 0.8001) (xy -0.16256 0.76835) (xy -0.1651 0.7366) (xy -0.1651 0.19685)
						(xy -0.17272 0.18923) (xy -0.17907 0.18034) (xy -0.18669 0.17145) (xy -0.19177 0.16256) (xy -0.19812 0.15367)
						(xy -0.20828 0.13335) (xy -0.21971 0.10287) (xy -0.22225 0.09271) (xy -0.22479 0.08128) (xy -0.22606 0.07112)
						(xy -0.2286 0.05969) (xy -0.2286 0.01651) (xy -0.22606 0.00508) (xy -0.22479 -0.00508) (xy -0.22225 -0.01651)
						(xy -0.21971 -0.02667) (xy -0.20828 -0.05715) (xy -0.19812 -0.07747) (xy -0.19177 -0.08636) (xy -0.18669 -0.09525)
						(xy -0.17907 -0.10414) (xy -0.17272 -0.11303) (xy -0.1651 -0.12065) (xy -0.1651 -0.7366) (xy -0.16256 -0.76835)
						(xy -0.1524 -0.8001) (xy -0.13716 -0.82804) (xy -0.11684 -0.85344) (xy -0.09144 -0.87376) (xy -0.0635 -0.889)
						(xy -0.03175 -0.89916) (xy 0 -0.9017) (xy 0.03175 -0.89916) (xy 0.0635 -0.889) (xy 0.09144 -0.87376)
						(xy 0.11684 -0.85344) (xy 0.13716 -0.82804) (xy 0.1524 -0.8001) (xy 0.16256 -0.76835) (xy 0.1651 -0.7366)
						(xy 0.1651 -0.11938) (xy 0.17272 -0.11176) (xy 0.19812 -0.0762) (xy 0.2032 -0.06604) (xy 0.20701 -0.05715)
						(xy 0.21209 -0.04699) (xy 0.2159 -0.03683) (xy 0.21844 -0.02667) (xy 0.22225 -0.01524) (xy 0.22352 -0.00508)
						(xy 0.22606 0.00508) (xy 0.22733 0.01651) (xy 0.22733 0.02667) (xy 0.2286 0.0381) (xy 0.22733 0.04953)
						(xy 0.22733 0.05969) (xy 0.22606 0.07112) (xy 0.22352 0.08128) (xy 0.22225 0.09144) (xy 0.21844 0.10287)
						(xy 0.2159 0.11303) (xy 0.21209 0.12319) (xy 0.20701 0.13335) (xy 0.2032 0.14224) (xy 0.19812 0.1524)
						(xy 0.17272 0.18796) (xy 0.1651 0.19558) (xy 0.1651 0.7366) (xy 0.16256 0.76835) (xy 0.1524 0.8001)
						(xy 0.13716 0.82804) (xy 0.11684 0.85344) (xy 0.09144 0.87376) (xy 0.0635 0.889) (xy 0.03175 0.89916)
					)
					(width 0)
					(fill yes)
				)
			)
		)
		(pad "85" smd custom
			(at -4.05003 4.106672)
			(size 0.1143 0.1143)
			(layers "F.Cu" "F.Mask" "F.Paste")
			(net "PV_VDDR")
			(options
				(clearance outline)
				(anchor circle)
			)
			(primitives
				(gr_poly
					(pts
						(xy 0 0.9017) (xy -0.03175 0.89916) (xy -0.0635 0.889) (xy -0.09144 0.87376) (xy -0.11684 0.85344)
						(xy -0.13716 0.82804) (xy -0.1524 0.8001) (xy -0.16256 0.76835) (xy -0.1651 0.7366) (xy -0.1651 -0.13462)
						(xy -0.17272 -0.14224) (xy -0.19812 -0.1778) (xy -0.2032 -0.18796) (xy -0.20701 -0.19685) (xy -0.21209 -0.20701)
						(xy -0.2159 -0.21717) (xy -0.21844 -0.22733) (xy -0.22225 -0.23876) (xy -0.22352 -0.24892) (xy -0.22606 -0.25908)
						(xy -0.22733 -0.27051) (xy -0.22733 -0.28067) (xy -0.2286 -0.2921) (xy -0.22733 -0.30353) (xy -0.22733 -0.31369)
						(xy -0.22606 -0.32512) (xy -0.22352 -0.33528) (xy -0.22225 -0.34544) (xy -0.21844 -0.35687) (xy -0.2159 -0.36703)
						(xy -0.21209 -0.37719) (xy -0.20701 -0.38735) (xy -0.2032 -0.39624) (xy -0.19812 -0.4064) (xy -0.17272 -0.44196)
						(xy -0.1651 -0.44958) (xy -0.1651 -0.7366) (xy -0.16256 -0.76835) (xy -0.1524 -0.8001) (xy -0.13716 -0.82804)
						(xy -0.11684 -0.85344) (xy -0.09144 -0.87376) (xy -0.0635 -0.889) (xy -0.03175 -0.89916) (xy 0 -0.9017)
						(xy 0.03175 -0.89916) (xy 0.0635 -0.889) (xy 0.09144 -0.87376) (xy 0.11684 -0.85344) (xy 0.13716 -0.82804)
						(xy 0.1524 -0.8001) (xy 0.16256 -0.76835) (xy 0.1651 -0.7366) (xy 0.1651 -0.44958) (xy 0.17272 -0.44196)
						(xy 0.19812 -0.4064) (xy 0.2032 -0.39624) (xy 0.20701 -0.38735) (xy 0.21209 -0.37719) (xy 0.2159 -0.36703)
						(xy 0.21844 -0.35687) (xy 0.22225 -0.34544) (xy 0.22352 -0.33528) (xy 0.22606 -0.32512) (xy 0.22733 -0.31369)
						(xy 0.22733 -0.30353) (xy 0.2286 -0.2921) (xy 0.22733 -0.28067) (xy 0.22733 -0.27051) (xy 0.22606 -0.25908)
						(xy 0.22352 -0.24892) (xy 0.22225 -0.23876) (xy 0.21844 -0.22733) (xy 0.2159 -0.21717) (xy 0.21209 -0.20701)
						(xy 0.20701 -0.19685) (xy 0.2032 -0.18796) (xy 0.19812 -0.1778) (xy 0.17272 -0.14224) (xy 0.1651 -0.13462)
						(xy 0.1651 0.7366) (xy 0.16256 0.76835) (xy 0.1524 0.8001) (xy 0.13716 0.82804) (xy 0.11684 0.85344)
						(xy 0.09144 0.87376) (xy 0.0635 0.889) (xy 0.03175 0.89916)
					)
					(width 0)
					(fill yes)
				)
			)
		)
		(pad "86" smd custom
			(at -3.750056 -4.106672)
			(size 0.1143 0.1143)
			(layers "F.Cu" "F.Mask" "F.Paste")
			(net "PV_VDDR")
			(options
				(clearance outline)
				(anchor circle)
			)
			(primitives
				(gr_poly
					(pts
						(xy 0 0.9017) (xy -0.03175 0.89916) (xy -0.0635 0.889) (xy -0.09144 0.87376) (xy -0.11684 0.85344)
						(xy -0.13716 0.82804) (xy -0.1524 0.8001) (xy -0.16256 0.76835) (xy -0.1651 0.7366) (xy -0.1651 0.44958)
						(xy -0.17272 0.44196) (xy -0.19812 0.4064) (xy -0.2032 0.39624) (xy -0.20701 0.38735) (xy -0.21209 0.37719)
						(xy -0.2159 0.36703) (xy -0.21844 0.35687) (xy -0.22225 0.34544) (xy -0.22352 0.33528) (xy -0.22606 0.32512)
						(xy -0.22733 0.31369) (xy -0.22733 0.30353) (xy -0.2286 0.2921) (xy -0.22733 0.28067) (xy -0.22733 0.27051)
						(xy -0.22606 0.25908) (xy -0.22352 0.24892) (xy -0.22225 0.23876) (xy -0.21844 0.22733) (xy -0.2159 0.21717)
						(xy -0.21209 0.20701) (xy -0.20701 0.19685) (xy -0.2032 0.18796) (xy -0.19812 0.1778) (xy -0.17272 0.14224)
						(xy -0.1651 0.13462) (xy -0.1651 -0.7366) (xy -0.16256 -0.76835) (xy -0.1524 -0.8001) (xy -0.13716 -0.82804)
						(xy -0.11684 -0.85344) (xy -0.09144 -0.87376) (xy -0.0635 -0.889) (xy -0.03175 -0.89916) (xy 0 -0.9017)
						(xy 0.03175 -0.89916) (xy 0.0635 -0.889) (xy 0.09144 -0.87376) (xy 0.11684 -0.85344) (xy 0.13716 -0.82804)
						(xy 0.1524 -0.8001) (xy 0.16256 -0.76835) (xy 0.1651 -0.7366) (xy 0.1651 0.13462) (xy 0.17272 0.14224)
						(xy 0.19812 0.1778) (xy 0.2032 0.18796) (xy 0.20701 0.19685) (xy 0.21209 0.20701) (xy 0.2159 0.21717)
						(xy 0.21844 0.22733) (xy 0.22225 0.23876) (xy 0.22352 0.24892) (xy 0.22606 0.25908) (xy 0.22733 0.27051)
						(xy 0.22733 0.28067) (xy 0.2286 0.2921) (xy 0.22733 0.30353) (xy 0.22733 0.31369) (xy 0.22606 0.32512)
						(xy 0.22352 0.33528) (xy 0.22225 0.34544) (xy 0.21844 0.35687) (xy 0.2159 0.36703) (xy 0.21209 0.37719)
						(xy 0.20701 0.38735) (xy 0.2032 0.39624) (xy 0.19812 0.4064) (xy 0.17272 0.44196) (xy 0.1651 0.44958)
						(xy 0.1651 0.7366) (xy 0.16256 0.76835) (xy 0.1524 0.8001) (xy 0.13716 0.82804) (xy 0.11684 0.85344)
						(xy 0.09144 0.87376) (xy 0.0635 0.889) (xy 0.03175 0.89916)
					)
					(width 0)
					(fill yes)
				)
			)
		)
		(pad "87" smd custom
			(at -3.450082 4.106672)
			(size 0.1143 0.1143)
			(layers "F.Cu" "F.Mask" "F.Paste")
			(net "M_B_CKE2")
			(options
				(clearance outline)
				(anchor circle)
			)
			(primitives
				(gr_poly
					(pts
						(xy 0 0.9017) (xy -0.03175 0.89916) (xy -0.0635 0.889) (xy -0.09144 0.87376) (xy -0.11684 0.85344)
						(xy -0.13716 0.82804) (xy -0.1524 0.8001) (xy -0.16256 0.76835) (xy -0.1651 0.7366) (xy -0.1651 0.11938)
						(xy -0.17272 0.11176) (xy -0.19812 0.0762) (xy -0.2032 0.06604) (xy -0.20701 0.05715) (xy -0.21209 0.04699)
						(xy -0.2159 0.03683) (xy -0.21844 0.02667) (xy -0.22225 0.01524) (xy -0.22352 0.00508) (xy -0.22606 -0.00508)
						(xy -0.22733 -0.01651) (xy -0.22733 -0.02667) (xy -0.2286 -0.0381) (xy -0.22733 -0.04953) (xy -0.22733 -0.05969)
						(xy -0.22606 -0.07112) (xy -0.22352 -0.08128) (xy -0.22225 -0.09144) (xy -0.21844 -0.10287) (xy -0.2159 -0.11303)
						(xy -0.21209 -0.12319) (xy -0.20701 -0.13335) (xy -0.2032 -0.14224) (xy -0.19812 -0.1524) (xy -0.17272 -0.18796)
						(xy -0.1651 -0.19558) (xy -0.1651 -0.7366) (xy -0.16256 -0.76835) (xy -0.1524 -0.8001) (xy -0.13716 -0.82804)
						(xy -0.11684 -0.85344) (xy -0.09144 -0.87376) (xy -0.0635 -0.889) (xy -0.03175 -0.89916) (xy 0 -0.9017)
						(xy 0.03175 -0.89916) (xy 0.0635 -0.889) (xy 0.09144 -0.87376) (xy 0.11684 -0.85344) (xy 0.13716 -0.82804)
						(xy 0.1524 -0.8001) (xy 0.16256 -0.76835) (xy 0.1651 -0.7366) (xy 0.1651 -0.19685) (xy 0.17272 -0.18923)
						(xy 0.17907 -0.18034) (xy 0.18669 -0.17145) (xy 0.19177 -0.16256) (xy 0.19812 -0.15367) (xy 0.20828 -0.13335)
						(xy 0.21971 -0.10287) (xy 0.22225 -0.09271) (xy 0.22479 -0.08128) (xy 0.22606 -0.07112) (xy 0.2286 -0.05969)
						(xy 0.2286 -0.01651) (xy 0.22606 -0.00508) (xy 0.22479 0.00508) (xy 0.22225 0.01651) (xy 0.21971 0.02667)
						(xy 0.20828 0.05715) (xy 0.19812 0.07747) (xy 0.19177 0.08636) (xy 0.18669 0.09525) (xy 0.17907 0.10414)
						(xy 0.17272 0.11303) (xy 0.1651 0.12065) (xy 0.1651 0.7366) (xy 0.16256 0.76835) (xy 0.1524 0.8001)
						(xy 0.13716 0.82804) (xy 0.11684 0.85344) (xy 0.09144 0.87376) (xy 0.0635 0.889) (xy 0.03175 0.89916)
					)
					(width 0)
					(fill yes)
				)
			)
		)
		(pad "88" smd custom
			(at -3.150108 -4.106672)
			(size 0.1143 0.1143)
			(layers "F.Cu" "F.Mask" "F.Paste")
			(net "M_B_MA15")
			(options
				(clearance outline)
				(anchor circle)
			)
			(primitives
				(gr_poly
					(pts
						(xy 0 0.9017) (xy -0.03175 0.89916) (xy -0.0635 0.889) (xy -0.09144 0.87376) (xy -0.11684 0.85344)
						(xy -0.13716 0.82804) (xy -0.1524 0.8001) (xy -0.16256 0.76835) (xy -0.1651 0.7366) (xy -0.1651 0.19685)
						(xy -0.17272 0.18923) (xy -0.17907 0.18034) (xy -0.18669 0.17145) (xy -0.19177 0.16256) (xy -0.19812 0.15367)
						(xy -0.20828 0.13335) (xy -0.21971 0.10287) (xy -0.22225 0.09271) (xy -0.22479 0.08128) (xy -0.22606 0.07112)
						(xy -0.2286 0.05969) (xy -0.2286 0.01651) (xy -0.22606 0.00508) (xy -0.22479 -0.00508) (xy -0.22225 -0.01651)
						(xy -0.21971 -0.02667) (xy -0.20828 -0.05715) (xy -0.19812 -0.07747) (xy -0.19177 -0.08636) (xy -0.18669 -0.09525)
						(xy -0.17907 -0.10414) (xy -0.17272 -0.11303) (xy -0.1651 -0.12065) (xy -0.1651 -0.7366) (xy -0.16256 -0.76835)
						(xy -0.1524 -0.8001) (xy -0.13716 -0.82804) (xy -0.11684 -0.85344) (xy -0.09144 -0.87376) (xy -0.0635 -0.889)
						(xy -0.03175 -0.89916) (xy 0 -0.9017) (xy 0.03175 -0.89916) (xy 0.0635 -0.889) (xy 0.09144 -0.87376)
						(xy 0.11684 -0.85344) (xy 0.13716 -0.82804) (xy 0.1524 -0.8001) (xy 0.16256 -0.76835) (xy 0.1651 -0.7366)
						(xy 0.1651 -0.11938) (xy 0.17272 -0.11176) (xy 0.19812 -0.0762) (xy 0.2032 -0.06604) (xy 0.20701 -0.05715)
						(xy 0.21209 -0.04699) (xy 0.2159 -0.03683) (xy 0.21844 -0.02667) (xy 0.22225 -0.01524) (xy 0.22352 -0.00508)
						(xy 0.22606 0.00508) (xy 0.22733 0.01651) (xy 0.22733 0.02667) (xy 0.2286 0.0381) (xy 0.22733 0.04953)
						(xy 0.22733 0.05969) (xy 0.22606 0.07112) (xy 0.22352 0.08128) (xy 0.22225 0.09144) (xy 0.21844 0.10287)
						(xy 0.2159 0.11303) (xy 0.21209 0.12319) (xy 0.20701 0.13335) (xy 0.2032 0.14224) (xy 0.19812 0.1524)
						(xy 0.17272 0.18796) (xy 0.1651 0.19558) (xy 0.1651 0.7366) (xy 0.16256 0.76835) (xy 0.1524 0.8001)
						(xy 0.13716 0.82804) (xy 0.11684 0.85344) (xy 0.09144 0.87376) (xy 0.0635 0.889) (xy 0.03175 0.89916)
					)
					(width 0)
					(fill yes)
				)
			)
		)
		(pad "89" smd custom
			(at -2.84988 4.106672)
			(size 0.1143 0.1143)
			(layers "F.Cu" "F.Mask" "F.Paste")
			(net "M_B_CKE3")
			(options
				(clearance outline)
				(anchor circle)
			)
			(primitives
				(gr_poly
					(pts
						(xy 0 0.9017) (xy -0.03175 0.89916) (xy -0.0635 0.889) (xy -0.09144 0.87376) (xy -0.11684 0.85344)
						(xy -0.13716 0.82804) (xy -0.1524 0.8001) (xy -0.16256 0.76835) (xy -0.1651 0.7366) (xy -0.1651 -0.13462)
						(xy -0.17272 -0.14224) (xy -0.19812 -0.1778) (xy -0.2032 -0.18796) (xy -0.20701 -0.19685) (xy -0.21209 -0.20701)
						(xy -0.2159 -0.21717) (xy -0.21844 -0.22733) (xy -0.22225 -0.23876) (xy -0.22352 -0.24892) (xy -0.22606 -0.25908)
						(xy -0.22733 -0.27051) (xy -0.22733 -0.28067) (xy -0.2286 -0.2921) (xy -0.22733 -0.30353) (xy -0.22733 -0.31369)
						(xy -0.22606 -0.32512) (xy -0.22352 -0.33528) (xy -0.22225 -0.34544) (xy -0.21844 -0.35687) (xy -0.2159 -0.36703)
						(xy -0.21209 -0.37719) (xy -0.20701 -0.38735) (xy -0.2032 -0.39624) (xy -0.19812 -0.4064) (xy -0.17272 -0.44196)
						(xy -0.1651 -0.44958) (xy -0.1651 -0.7366) (xy -0.16256 -0.76835) (xy -0.1524 -0.8001) (xy -0.13716 -0.82804)
						(xy -0.11684 -0.85344) (xy -0.09144 -0.87376) (xy -0.0635 -0.889) (xy -0.03175 -0.89916) (xy 0 -0.9017)
						(xy 0.03175 -0.89916) (xy 0.0635 -0.889) (xy 0.09144 -0.87376) (xy 0.11684 -0.85344) (xy 0.13716 -0.82804)
						(xy 0.1524 -0.8001) (xy 0.16256 -0.76835) (xy 0.1651 -0.7366) (xy 0.1651 -0.44958) (xy 0.17272 -0.44196)
						(xy 0.19812 -0.4064) (xy 0.2032 -0.39624) (xy 0.20701 -0.38735) (xy 0.21209 -0.37719) (xy 0.2159 -0.36703)
						(xy 0.21844 -0.35687) (xy 0.22225 -0.34544) (xy 0.22352 -0.33528) (xy 0.22606 -0.32512) (xy 0.22733 -0.31369)
						(xy 0.22733 -0.30353) (xy 0.2286 -0.2921) (xy 0.22733 -0.28067) (xy 0.22733 -0.27051) (xy 0.22606 -0.25908)
						(xy 0.22352 -0.24892) (xy 0.22225 -0.23876) (xy 0.21844 -0.22733) (xy 0.2159 -0.21717) (xy 0.21209 -0.20701)
						(xy 0.20701 -0.19685) (xy 0.2032 -0.18796) (xy 0.19812 -0.1778) (xy 0.17272 -0.14224) (xy 0.1651 -0.13462)
						(xy 0.1651 0.7366) (xy 0.16256 0.76835) (xy 0.1524 0.8001) (xy 0.13716 0.82804) (xy 0.11684 0.85344)
						(xy 0.09144 0.87376) (xy 0.0635 0.889) (xy 0.03175 0.89916)
					)
					(width 0)
					(fill yes)
				)
			)
		)
		(pad "90" smd custom
			(at -2.549906 -4.106672)
			(size 0.1143 0.1143)
			(layers "F.Cu" "F.Mask" "F.Paste")
			(net "M_B_MA14")
			(options
				(clearance outline)
				(anchor circle)
			)
			(primitives
				(gr_poly
					(pts
						(xy 0 0.9017) (xy -0.03175 0.89916) (xy -0.0635 0.889) (xy -0.09144 0.87376) (xy -0.11684 0.85344)
						(xy -0.13716 0.82804) (xy -0.1524 0.8001) (xy -0.16256 0.76835) (xy -0.1651 0.7366) (xy -0.1651 0.44958)
						(xy -0.17272 0.44196) (xy -0.19812 0.4064) (xy -0.2032 0.39624) (xy -0.20701 0.38735) (xy -0.21209 0.37719)
						(xy -0.2159 0.36703) (xy -0.21844 0.35687) (xy -0.22225 0.34544) (xy -0.22352 0.33528) (xy -0.22606 0.32512)
						(xy -0.22733 0.31369) (xy -0.22733 0.30353) (xy -0.2286 0.2921) (xy -0.22733 0.28067) (xy -0.22733 0.27051)
						(xy -0.22606 0.25908) (xy -0.22352 0.24892) (xy -0.22225 0.23876) (xy -0.21844 0.22733) (xy -0.2159 0.21717)
						(xy -0.21209 0.20701) (xy -0.20701 0.19685) (xy -0.2032 0.18796) (xy -0.19812 0.1778) (xy -0.17272 0.14224)
						(xy -0.1651 0.13462) (xy -0.1651 -0.7366) (xy -0.16256 -0.76835) (xy -0.1524 -0.8001) (xy -0.13716 -0.82804)
						(xy -0.11684 -0.85344) (xy -0.09144 -0.87376) (xy -0.0635 -0.889) (xy -0.03175 -0.89916) (xy 0 -0.9017)
						(xy 0.03175 -0.89916) (xy 0.0635 -0.889) (xy 0.09144 -0.87376) (xy 0.11684 -0.85344) (xy 0.13716 -0.82804)
						(xy 0.1524 -0.8001) (xy 0.16256 -0.76835) (xy 0.1651 -0.7366) (xy 0.1651 0.13462) (xy 0.17272 0.14224)
						(xy 0.19812 0.1778) (xy 0.2032 0.18796) (xy 0.20701 0.19685) (xy 0.21209 0.20701) (xy 0.2159 0.21717)
						(xy 0.21844 0.22733) (xy 0.22225 0.23876) (xy 0.22352 0.24892) (xy 0.22606 0.25908) (xy 0.22733 0.27051)
						(xy 0.22733 0.28067) (xy 0.2286 0.2921) (xy 0.22733 0.30353) (xy 0.22733 0.31369) (xy 0.22606 0.32512)
						(xy 0.22352 0.33528) (xy 0.22225 0.34544) (xy 0.21844 0.35687) (xy 0.2159 0.36703) (xy 0.21209 0.37719)
						(xy 0.20701 0.38735) (xy 0.2032 0.39624) (xy 0.19812 0.4064) (xy 0.17272 0.44196) (xy 0.1651 0.44958)
						(xy 0.1651 0.7366) (xy 0.16256 0.76835) (xy 0.1524 0.8001) (xy 0.13716 0.82804) (xy 0.11684 0.85344)
						(xy 0.09144 0.87376) (xy 0.0635 0.889) (xy 0.03175 0.89916)
					)
					(width 0)
					(fill yes)
				)
			)
		)
		(pad "91" smd custom
			(at -2.249932 4.106672)
			(size 0.1143 0.1143)
			(layers "F.Cu" "F.Mask" "F.Paste")
			(net "M_B_BS2")
			(options
				(clearance outline)
				(anchor circle)
			)
			(primitives
				(gr_poly
					(pts
						(xy 0 0.9017) (xy -0.03175 0.89916) (xy -0.0635 0.889) (xy -0.09144 0.87376) (xy -0.11684 0.85344)
						(xy -0.13716 0.82804) (xy -0.1524 0.8001) (xy -0.16256 0.76835) (xy -0.1651 0.7366) (xy -0.1651 0.11938)
						(xy -0.17272 0.11176) (xy -0.19812 0.0762) (xy -0.2032 0.06604) (xy -0.20701 0.05715) (xy -0.21209 0.04699)
						(xy -0.2159 0.03683) (xy -0.21844 0.02667) (xy -0.22225 0.01524) (xy -0.22352 0.00508) (xy -0.22606 -0.00508)
						(xy -0.22733 -0.01651) (xy -0.22733 -0.02667) (xy -0.2286 -0.0381) (xy -0.22733 -0.04953) (xy -0.22733 -0.05969)
						(xy -0.22606 -0.07112) (xy -0.22352 -0.08128) (xy -0.22225 -0.09144) (xy -0.21844 -0.10287) (xy -0.2159 -0.11303)
						(xy -0.21209 -0.12319) (xy -0.20701 -0.13335) (xy -0.2032 -0.14224) (xy -0.19812 -0.1524) (xy -0.17272 -0.18796)
						(xy -0.1651 -0.19558) (xy -0.1651 -0.7366) (xy -0.16256 -0.76835) (xy -0.1524 -0.8001) (xy -0.13716 -0.82804)
						(xy -0.11684 -0.85344) (xy -0.09144 -0.87376) (xy -0.0635 -0.889) (xy -0.03175 -0.89916) (xy 0 -0.9017)
						(xy 0.03175 -0.89916) (xy 0.0635 -0.889) (xy 0.09144 -0.87376) (xy 0.11684 -0.85344) (xy 0.13716 -0.82804)
						(xy 0.1524 -0.8001) (xy 0.16256 -0.76835) (xy 0.1651 -0.7366) (xy 0.1651 -0.19685) (xy 0.17272 -0.18923)
						(xy 0.17907 -0.18034) (xy 0.18669 -0.17145) (xy 0.19177 -0.16256) (xy 0.19812 -0.15367) (xy 0.20828 -0.13335)
						(xy 0.21971 -0.10287) (xy 0.22225 -0.09271) (xy 0.22479 -0.08128) (xy 0.22606 -0.07112) (xy 0.2286 -0.05969)
						(xy 0.2286 -0.01651) (xy 0.22606 -0.00508) (xy 0.22479 0.00508) (xy 0.22225 0.01651) (xy 0.21971 0.02667)
						(xy 0.20828 0.05715) (xy 0.19812 0.07747) (xy 0.19177 0.08636) (xy 0.18669 0.09525) (xy 0.17907 0.10414)
						(xy 0.17272 0.11303) (xy 0.1651 0.12065) (xy 0.1651 0.7366) (xy 0.16256 0.76835) (xy 0.1524 0.8001)
						(xy 0.13716 0.82804) (xy 0.11684 0.85344) (xy 0.09144 0.87376) (xy 0.0635 0.889) (xy 0.03175 0.89916)
					)
					(width 0)
					(fill yes)
				)
			)
		)
		(pad "92" smd custom
			(at -1.949958 -4.106672)
			(size 0.1143 0.1143)
			(layers "F.Cu" "F.Mask" "F.Paste")
			(net "M_B_MA9")
			(options
				(clearance outline)
				(anchor circle)
			)
			(primitives
				(gr_poly
					(pts
						(xy 0 0.9017) (xy -0.03175 0.89916) (xy -0.0635 0.889) (xy -0.09144 0.87376) (xy -0.11684 0.85344)
						(xy -0.13716 0.82804) (xy -0.1524 0.8001) (xy -0.16256 0.76835) (xy -0.1651 0.7366) (xy -0.1651 0.19685)
						(xy -0.17272 0.18923) (xy -0.17907 0.18034) (xy -0.18669 0.17145) (xy -0.19177 0.16256) (xy -0.19812 0.15367)
						(xy -0.20828 0.13335) (xy -0.21971 0.10287) (xy -0.22225 0.09271) (xy -0.22479 0.08128) (xy -0.22606 0.07112)
						(xy -0.2286 0.05969) (xy -0.2286 0.01651) (xy -0.22606 0.00508) (xy -0.22479 -0.00508) (xy -0.22225 -0.01651)
						(xy -0.21971 -0.02667) (xy -0.20828 -0.05715) (xy -0.19812 -0.07747) (xy -0.19177 -0.08636) (xy -0.18669 -0.09525)
						(xy -0.17907 -0.10414) (xy -0.17272 -0.11303) (xy -0.1651 -0.12065) (xy -0.1651 -0.7366) (xy -0.16256 -0.76835)
						(xy -0.1524 -0.8001) (xy -0.13716 -0.82804) (xy -0.11684 -0.85344) (xy -0.09144 -0.87376) (xy -0.0635 -0.889)
						(xy -0.03175 -0.89916) (xy 0 -0.9017) (xy 0.03175 -0.89916) (xy 0.0635 -0.889) (xy 0.09144 -0.87376)
						(xy 0.11684 -0.85344) (xy 0.13716 -0.82804) (xy 0.1524 -0.8001) (xy 0.16256 -0.76835) (xy 0.1651 -0.7366)
						(xy 0.1651 -0.11938) (xy 0.17272 -0.11176) (xy 0.19812 -0.0762) (xy 0.2032 -0.06604) (xy 0.20701 -0.05715)
						(xy 0.21209 -0.04699) (xy 0.2159 -0.03683) (xy 0.21844 -0.02667) (xy 0.22225 -0.01524) (xy 0.22352 -0.00508)
						(xy 0.22606 0.00508) (xy 0.22733 0.01651) (xy 0.22733 0.02667) (xy 0.2286 0.0381) (xy 0.22733 0.04953)
						(xy 0.22733 0.05969) (xy 0.22606 0.07112) (xy 0.22352 0.08128) (xy 0.22225 0.09144) (xy 0.21844 0.10287)
						(xy 0.2159 0.11303) (xy 0.21209 0.12319) (xy 0.20701 0.13335) (xy 0.2032 0.14224) (xy 0.19812 0.1524)
						(xy 0.17272 0.18796) (xy 0.1651 0.19558) (xy 0.1651 0.7366) (xy 0.16256 0.76835) (xy 0.1524 0.8001)
						(xy 0.13716 0.82804) (xy 0.11684 0.85344) (xy 0.09144 0.87376) (xy 0.0635 0.889) (xy 0.03175 0.89916)
					)
					(width 0)
					(fill yes)
				)
			)
		)
		(pad "93" smd custom
			(at -1.649984 4.106672)
			(size 0.1143 0.1143)
			(layers "F.Cu" "F.Mask" "F.Paste")
			(net "PV_VDDR")
			(options
				(clearance outline)
				(anchor circle)
			)
			(primitives
				(gr_poly
					(pts
						(xy 0 0.9017) (xy -0.03175 0.89916) (xy -0.0635 0.889) (xy -0.09144 0.87376) (xy -0.11684 0.85344)
						(xy -0.13716 0.82804) (xy -0.1524 0.8001) (xy -0.16256 0.76835) (xy -0.1651 0.7366) (xy -0.1651 -0.13462)
						(xy -0.17272 -0.14224) (xy -0.19812 -0.1778) (xy -0.2032 -0.18796) (xy -0.20701 -0.19685) (xy -0.21209 -0.20701)
						(xy -0.2159 -0.21717) (xy -0.21844 -0.22733) (xy -0.22225 -0.23876) (xy -0.22352 -0.24892) (xy -0.22606 -0.25908)
						(xy -0.22733 -0.27051) (xy -0.22733 -0.28067) (xy -0.2286 -0.2921) (xy -0.22733 -0.30353) (xy -0.22733 -0.31369)
						(xy -0.22606 -0.32512) (xy -0.22352 -0.33528) (xy -0.22225 -0.34544) (xy -0.21844 -0.35687) (xy -0.2159 -0.36703)
						(xy -0.21209 -0.37719) (xy -0.20701 -0.38735) (xy -0.2032 -0.39624) (xy -0.19812 -0.4064) (xy -0.17272 -0.44196)
						(xy -0.1651 -0.44958) (xy -0.1651 -0.7366) (xy -0.16256 -0.76835) (xy -0.1524 -0.8001) (xy -0.13716 -0.82804)
						(xy -0.11684 -0.85344) (xy -0.09144 -0.87376) (xy -0.0635 -0.889) (xy -0.03175 -0.89916) (xy 0 -0.9017)
						(xy 0.03175 -0.89916) (xy 0.0635 -0.889) (xy 0.09144 -0.87376) (xy 0.11684 -0.85344) (xy 0.13716 -0.82804)
						(xy 0.1524 -0.8001) (xy 0.16256 -0.76835) (xy 0.1651 -0.7366) (xy 0.1651 -0.44958) (xy 0.17272 -0.44196)
						(xy 0.19812 -0.4064) (xy 0.2032 -0.39624) (xy 0.20701 -0.38735) (xy 0.21209 -0.37719) (xy 0.2159 -0.36703)
						(xy 0.21844 -0.35687) (xy 0.22225 -0.34544) (xy 0.22352 -0.33528) (xy 0.22606 -0.32512) (xy 0.22733 -0.31369)
						(xy 0.22733 -0.30353) (xy 0.2286 -0.2921) (xy 0.22733 -0.28067) (xy 0.22733 -0.27051) (xy 0.22606 -0.25908)
						(xy 0.22352 -0.24892) (xy 0.22225 -0.23876) (xy 0.21844 -0.22733) (xy 0.2159 -0.21717) (xy 0.21209 -0.20701)
						(xy 0.20701 -0.19685) (xy 0.2032 -0.18796) (xy 0.19812 -0.1778) (xy 0.17272 -0.14224) (xy 0.1651 -0.13462)
						(xy 0.1651 0.7366) (xy 0.16256 0.76835) (xy 0.1524 0.8001) (xy 0.13716 0.82804) (xy 0.11684 0.85344)
						(xy 0.09144 0.87376) (xy 0.0635 0.889) (xy 0.03175 0.89916)
					)
					(width 0)
					(fill yes)
				)
			)
		)
		(pad "94" smd custom
			(at -1.35001 -4.106672)
			(size 0.1143 0.1143)
			(layers "F.Cu" "F.Mask" "F.Paste")
			(net "PV_VDDR")
			(options
				(clearance outline)
				(anchor circle)
			)
			(primitives
				(gr_poly
					(pts
						(xy 0 0.9017) (xy -0.03175 0.89916) (xy -0.0635 0.889) (xy -0.09144 0.87376) (xy -0.11684 0.85344)
						(xy -0.13716 0.82804) (xy -0.1524 0.8001) (xy -0.16256 0.76835) (xy -0.1651 0.7366) (xy -0.1651 0.44958)
						(xy -0.17272 0.44196) (xy -0.19812 0.4064) (xy -0.2032 0.39624) (xy -0.20701 0.38735) (xy -0.21209 0.37719)
						(xy -0.2159 0.36703) (xy -0.21844 0.35687) (xy -0.22225 0.34544) (xy -0.22352 0.33528) (xy -0.22606 0.32512)
						(xy -0.22733 0.31369) (xy -0.22733 0.30353) (xy -0.2286 0.2921) (xy -0.22733 0.28067) (xy -0.22733 0.27051)
						(xy -0.22606 0.25908) (xy -0.22352 0.24892) (xy -0.22225 0.23876) (xy -0.21844 0.22733) (xy -0.2159 0.21717)
						(xy -0.21209 0.20701) (xy -0.20701 0.19685) (xy -0.2032 0.18796) (xy -0.19812 0.1778) (xy -0.17272 0.14224)
						(xy -0.1651 0.13462) (xy -0.1651 -0.7366) (xy -0.16256 -0.76835) (xy -0.1524 -0.8001) (xy -0.13716 -0.82804)
						(xy -0.11684 -0.85344) (xy -0.09144 -0.87376) (xy -0.0635 -0.889) (xy -0.03175 -0.89916) (xy 0 -0.9017)
						(xy 0.03175 -0.89916) (xy 0.0635 -0.889) (xy 0.09144 -0.87376) (xy 0.11684 -0.85344) (xy 0.13716 -0.82804)
						(xy 0.1524 -0.8001) (xy 0.16256 -0.76835) (xy 0.1651 -0.7366) (xy 0.1651 0.13462) (xy 0.17272 0.14224)
						(xy 0.19812 0.1778) (xy 0.2032 0.18796) (xy 0.20701 0.19685) (xy 0.21209 0.20701) (xy 0.2159 0.21717)
						(xy 0.21844 0.22733) (xy 0.22225 0.23876) (xy 0.22352 0.24892) (xy 0.22606 0.25908) (xy 0.22733 0.27051)
						(xy 0.22733 0.28067) (xy 0.2286 0.2921) (xy 0.22733 0.30353) (xy 0.22733 0.31369) (xy 0.22606 0.32512)
						(xy 0.22352 0.33528) (xy 0.22225 0.34544) (xy 0.21844 0.35687) (xy 0.2159 0.36703) (xy 0.21209 0.37719)
						(xy 0.20701 0.38735) (xy 0.2032 0.39624) (xy 0.19812 0.4064) (xy 0.17272 0.44196) (xy 0.1651 0.44958)
						(xy 0.1651 0.7366) (xy 0.16256 0.76835) (xy 0.1524 0.8001) (xy 0.13716 0.82804) (xy 0.11684 0.85344)
						(xy 0.09144 0.87376) (xy 0.0635 0.889) (xy 0.03175 0.89916)
					)
					(width 0)
					(fill yes)
				)
			)
		)
		(pad "95" smd custom
			(at -1.050036 4.106672)
			(size 0.1143 0.1143)
			(layers "F.Cu" "F.Mask" "F.Paste")
			(net "M_B_MA12")
			(options
				(clearance outline)
				(anchor circle)
			)
			(primitives
				(gr_poly
					(pts
						(xy 0 0.9017) (xy -0.03175 0.89916) (xy -0.0635 0.889) (xy -0.09144 0.87376) (xy -0.11684 0.85344)
						(xy -0.13716 0.82804) (xy -0.1524 0.8001) (xy -0.16256 0.76835) (xy -0.1651 0.7366) (xy -0.1651 0.11938)
						(xy -0.17272 0.11176) (xy -0.19812 0.0762) (xy -0.2032 0.06604) (xy -0.20701 0.05715) (xy -0.21209 0.04699)
						(xy -0.2159 0.03683) (xy -0.21844 0.02667) (xy -0.22225 0.01524) (xy -0.22352 0.00508) (xy -0.22606 -0.00508)
						(xy -0.22733 -0.01651) (xy -0.22733 -0.02667) (xy -0.2286 -0.0381) (xy -0.22733 -0.04953) (xy -0.22733 -0.05969)
						(xy -0.22606 -0.07112) (xy -0.22352 -0.08128) (xy -0.22225 -0.09144) (xy -0.21844 -0.10287) (xy -0.2159 -0.11303)
						(xy -0.21209 -0.12319) (xy -0.20701 -0.13335) (xy -0.2032 -0.14224) (xy -0.19812 -0.1524) (xy -0.17272 -0.18796)
						(xy -0.1651 -0.19558) (xy -0.1651 -0.7366) (xy -0.16256 -0.76835) (xy -0.1524 -0.8001) (xy -0.13716 -0.82804)
						(xy -0.11684 -0.85344) (xy -0.09144 -0.87376) (xy -0.0635 -0.889) (xy -0.03175 -0.89916) (xy 0 -0.9017)
						(xy 0.03175 -0.89916) (xy 0.0635 -0.889) (xy 0.09144 -0.87376) (xy 0.11684 -0.85344) (xy 0.13716 -0.82804)
						(xy 0.1524 -0.8001) (xy 0.16256 -0.76835) (xy 0.1651 -0.7366) (xy 0.1651 -0.19685) (xy 0.17272 -0.18923)
						(xy 0.17907 -0.18034) (xy 0.18669 -0.17145) (xy 0.19177 -0.16256) (xy 0.19812 -0.15367) (xy 0.20828 -0.13335)
						(xy 0.21971 -0.10287) (xy 0.22225 -0.09271) (xy 0.22479 -0.08128) (xy 0.22606 -0.07112) (xy 0.2286 -0.05969)
						(xy 0.2286 -0.01651) (xy 0.22606 -0.00508) (xy 0.22479 0.00508) (xy 0.22225 0.01651) (xy 0.21971 0.02667)
						(xy 0.20828 0.05715) (xy 0.19812 0.07747) (xy 0.19177 0.08636) (xy 0.18669 0.09525) (xy 0.17907 0.10414)
						(xy 0.17272 0.11303) (xy 0.1651 0.12065) (xy 0.1651 0.7366) (xy 0.16256 0.76835) (xy 0.1524 0.8001)
						(xy 0.13716 0.82804) (xy 0.11684 0.85344) (xy 0.09144 0.87376) (xy 0.0635 0.889) (xy 0.03175 0.89916)
					)
					(width 0)
					(fill yes)
				)
			)
		)
		(pad "96" smd custom
			(at -0.750062 -4.106672)
			(size 0.1143 0.1143)
			(layers "F.Cu" "F.Mask" "F.Paste")
			(net "M_B_MA11")
			(options
				(clearance outline)
				(anchor circle)
			)
			(primitives
				(gr_poly
					(pts
						(xy 0 0.9017) (xy -0.03175 0.89916) (xy -0.0635 0.889) (xy -0.09144 0.87376) (xy -0.11684 0.85344)
						(xy -0.13716 0.82804) (xy -0.1524 0.8001) (xy -0.16256 0.76835) (xy -0.1651 0.7366) (xy -0.1651 0.19685)
						(xy -0.17272 0.18923) (xy -0.17907 0.18034) (xy -0.18669 0.17145) (xy -0.19177 0.16256) (xy -0.19812 0.15367)
						(xy -0.20828 0.13335) (xy -0.21971 0.10287) (xy -0.22225 0.09271) (xy -0.22479 0.08128) (xy -0.22606 0.07112)
						(xy -0.2286 0.05969) (xy -0.2286 0.01651) (xy -0.22606 0.00508) (xy -0.22479 -0.00508) (xy -0.22225 -0.01651)
						(xy -0.21971 -0.02667) (xy -0.20828 -0.05715) (xy -0.19812 -0.07747) (xy -0.19177 -0.08636) (xy -0.18669 -0.09525)
						(xy -0.17907 -0.10414) (xy -0.17272 -0.11303) (xy -0.1651 -0.12065) (xy -0.1651 -0.7366) (xy -0.16256 -0.76835)
						(xy -0.1524 -0.8001) (xy -0.13716 -0.82804) (xy -0.11684 -0.85344) (xy -0.09144 -0.87376) (xy -0.0635 -0.889)
						(xy -0.03175 -0.89916) (xy 0 -0.9017) (xy 0.03175 -0.89916) (xy 0.0635 -0.889) (xy 0.09144 -0.87376)
						(xy 0.11684 -0.85344) (xy 0.13716 -0.82804) (xy 0.1524 -0.8001) (xy 0.16256 -0.76835) (xy 0.1651 -0.7366)
						(xy 0.1651 -0.11938) (xy 0.17272 -0.11176) (xy 0.19812 -0.0762) (xy 0.2032 -0.06604) (xy 0.20701 -0.05715)
						(xy 0.21209 -0.04699) (xy 0.2159 -0.03683) (xy 0.21844 -0.02667) (xy 0.22225 -0.01524) (xy 0.22352 -0.00508)
						(xy 0.22606 0.00508) (xy 0.22733 0.01651) (xy 0.22733 0.02667) (xy 0.2286 0.0381) (xy 0.22733 0.04953)
						(xy 0.22733 0.05969) (xy 0.22606 0.07112) (xy 0.22352 0.08128) (xy 0.22225 0.09144) (xy 0.21844 0.10287)
						(xy 0.2159 0.11303) (xy 0.21209 0.12319) (xy 0.20701 0.13335) (xy 0.2032 0.14224) (xy 0.19812 0.1524)
						(xy 0.17272 0.18796) (xy 0.1651 0.19558) (xy 0.1651 0.7366) (xy 0.16256 0.76835) (xy 0.1524 0.8001)
						(xy 0.13716 0.82804) (xy 0.11684 0.85344) (xy 0.09144 0.87376) (xy 0.0635 0.889) (xy 0.03175 0.89916)
					)
					(width 0)
					(fill yes)
				)
			)
		)
		(pad "97" smd custom
			(at -0.450088 4.106672)
			(size 0.1143 0.1143)
			(layers "F.Cu" "F.Mask" "F.Paste")
			(net "M_B_MA8")
			(options
				(clearance outline)
				(anchor circle)
			)
			(primitives
				(gr_poly
					(pts
						(xy 0 0.9017) (xy -0.03175 0.89916) (xy -0.0635 0.889) (xy -0.09144 0.87376) (xy -0.11684 0.85344)
						(xy -0.13716 0.82804) (xy -0.1524 0.8001) (xy -0.16256 0.76835) (xy -0.1651 0.7366) (xy -0.1651 -0.13462)
						(xy -0.17272 -0.14224) (xy -0.19812 -0.1778) (xy -0.2032 -0.18796) (xy -0.20701 -0.19685) (xy -0.21209 -0.20701)
						(xy -0.2159 -0.21717) (xy -0.21844 -0.22733) (xy -0.22225 -0.23876) (xy -0.22352 -0.24892) (xy -0.22606 -0.25908)
						(xy -0.22733 -0.27051) (xy -0.22733 -0.28067) (xy -0.2286 -0.2921) (xy -0.22733 -0.30353) (xy -0.22733 -0.31369)
						(xy -0.22606 -0.32512) (xy -0.22352 -0.33528) (xy -0.22225 -0.34544) (xy -0.21844 -0.35687) (xy -0.2159 -0.36703)
						(xy -0.21209 -0.37719) (xy -0.20701 -0.38735) (xy -0.2032 -0.39624) (xy -0.19812 -0.4064) (xy -0.17272 -0.44196)
						(xy -0.1651 -0.44958) (xy -0.1651 -0.7366) (xy -0.16256 -0.76835) (xy -0.1524 -0.8001) (xy -0.13716 -0.82804)
						(xy -0.11684 -0.85344) (xy -0.09144 -0.87376) (xy -0.0635 -0.889) (xy -0.03175 -0.89916) (xy 0 -0.9017)
						(xy 0.03175 -0.89916) (xy 0.0635 -0.889) (xy 0.09144 -0.87376) (xy 0.11684 -0.85344) (xy 0.13716 -0.82804)
						(xy 0.1524 -0.8001) (xy 0.16256 -0.76835) (xy 0.1651 -0.7366) (xy 0.1651 -0.44958) (xy 0.17272 -0.44196)
						(xy 0.19812 -0.4064) (xy 0.2032 -0.39624) (xy 0.20701 -0.38735) (xy 0.21209 -0.37719) (xy 0.2159 -0.36703)
						(xy 0.21844 -0.35687) (xy 0.22225 -0.34544) (xy 0.22352 -0.33528) (xy 0.22606 -0.32512) (xy 0.22733 -0.31369)
						(xy 0.22733 -0.30353) (xy 0.2286 -0.2921) (xy 0.22733 -0.28067) (xy 0.22733 -0.27051) (xy 0.22606 -0.25908)
						(xy 0.22352 -0.24892) (xy 0.22225 -0.23876) (xy 0.21844 -0.22733) (xy 0.2159 -0.21717) (xy 0.21209 -0.20701)
						(xy 0.20701 -0.19685) (xy 0.2032 -0.18796) (xy 0.19812 -0.1778) (xy 0.17272 -0.14224) (xy 0.1651 -0.13462)
						(xy 0.1651 0.7366) (xy 0.16256 0.76835) (xy 0.1524 0.8001) (xy 0.13716 0.82804) (xy 0.11684 0.85344)
						(xy 0.09144 0.87376) (xy 0.0635 0.889) (xy 0.03175 0.89916)
					)
					(width 0)
					(fill yes)
				)
			)
		)
		(pad "98" smd custom
			(at -0.150114 -4.106672)
			(size 0.1143 0.1143)
			(layers "F.Cu" "F.Mask" "F.Paste")
			(net "M_B_MA7")
			(options
				(clearance outline)
				(anchor circle)
			)
			(primitives
				(gr_poly
					(pts
						(xy 0 0.9017) (xy -0.03175 0.89916) (xy -0.0635 0.889) (xy -0.09144 0.87376) (xy -0.11684 0.85344)
						(xy -0.13716 0.82804) (xy -0.1524 0.8001) (xy -0.16256 0.76835) (xy -0.1651 0.7366) (xy -0.1651 0.44958)
						(xy -0.17272 0.44196) (xy -0.19812 0.4064) (xy -0.2032 0.39624) (xy -0.20701 0.38735) (xy -0.21209 0.37719)
						(xy -0.2159 0.36703) (xy -0.21844 0.35687) (xy -0.22225 0.34544) (xy -0.22352 0.33528) (xy -0.22606 0.32512)
						(xy -0.22733 0.31369) (xy -0.22733 0.30353) (xy -0.2286 0.2921) (xy -0.22733 0.28067) (xy -0.22733 0.27051)
						(xy -0.22606 0.25908) (xy -0.22352 0.24892) (xy -0.22225 0.23876) (xy -0.21844 0.22733) (xy -0.2159 0.21717)
						(xy -0.21209 0.20701) (xy -0.20701 0.19685) (xy -0.2032 0.18796) (xy -0.19812 0.1778) (xy -0.17272 0.14224)
						(xy -0.1651 0.13462) (xy -0.1651 -0.7366) (xy -0.16256 -0.76835) (xy -0.1524 -0.8001) (xy -0.13716 -0.82804)
						(xy -0.11684 -0.85344) (xy -0.09144 -0.87376) (xy -0.0635 -0.889) (xy -0.03175 -0.89916) (xy 0 -0.9017)
						(xy 0.03175 -0.89916) (xy 0.0635 -0.889) (xy 0.09144 -0.87376) (xy 0.11684 -0.85344) (xy 0.13716 -0.82804)
						(xy 0.1524 -0.8001) (xy 0.16256 -0.76835) (xy 0.1651 -0.7366) (xy 0.1651 0.13462) (xy 0.17272 0.14224)
						(xy 0.19812 0.1778) (xy 0.2032 0.18796) (xy 0.20701 0.19685) (xy 0.21209 0.20701) (xy 0.2159 0.21717)
						(xy 0.21844 0.22733) (xy 0.22225 0.23876) (xy 0.22352 0.24892) (xy 0.22606 0.25908) (xy 0.22733 0.27051)
						(xy 0.22733 0.28067) (xy 0.2286 0.2921) (xy 0.22733 0.30353) (xy 0.22733 0.31369) (xy 0.22606 0.32512)
						(xy 0.22352 0.33528) (xy 0.22225 0.34544) (xy 0.21844 0.35687) (xy 0.2159 0.36703) (xy 0.21209 0.37719)
						(xy 0.20701 0.38735) (xy 0.2032 0.39624) (xy 0.19812 0.4064) (xy 0.17272 0.44196) (xy 0.1651 0.44958)
						(xy 0.1651 0.7366) (xy 0.16256 0.76835) (xy 0.1524 0.8001) (xy 0.13716 0.82804) (xy 0.11684 0.85344)
						(xy 0.09144 0.87376) (xy 0.0635 0.889) (xy 0.03175 0.89916)
					)
					(width 0)
					(fill yes)
				)
			)
		)
		(pad "99" smd custom
			(at 0.150114 4.106672)
			(size 0.1143 0.1143)
			(layers "F.Cu" "F.Mask" "F.Paste")
			(net "M_B_MA5")
			(options
				(clearance outline)
				(anchor circle)
			)
			(primitives
				(gr_poly
					(pts
						(xy 0 0.9017) (xy -0.03175 0.89916) (xy -0.0635 0.889) (xy -0.09144 0.87376) (xy -0.11684 0.85344)
						(xy -0.13716 0.82804) (xy -0.1524 0.8001) (xy -0.16256 0.76835) (xy -0.1651 0.7366) (xy -0.1651 0.11938)
						(xy -0.17272 0.11176) (xy -0.19812 0.0762) (xy -0.2032 0.06604) (xy -0.20701 0.05715) (xy -0.21209 0.04699)
						(xy -0.2159 0.03683) (xy -0.21844 0.02667) (xy -0.22225 0.01524) (xy -0.22352 0.00508) (xy -0.22606 -0.00508)
						(xy -0.22733 -0.01651) (xy -0.22733 -0.02667) (xy -0.2286 -0.0381) (xy -0.22733 -0.04953) (xy -0.22733 -0.05969)
						(xy -0.22606 -0.07112) (xy -0.22352 -0.08128) (xy -0.22225 -0.09144) (xy -0.21844 -0.10287) (xy -0.2159 -0.11303)
						(xy -0.21209 -0.12319) (xy -0.20701 -0.13335) (xy -0.2032 -0.14224) (xy -0.19812 -0.1524) (xy -0.17272 -0.18796)
						(xy -0.1651 -0.19558) (xy -0.1651 -0.7366) (xy -0.16256 -0.76835) (xy -0.1524 -0.8001) (xy -0.13716 -0.82804)
						(xy -0.11684 -0.85344) (xy -0.09144 -0.87376) (xy -0.0635 -0.889) (xy -0.03175 -0.89916) (xy 0 -0.9017)
						(xy 0.03175 -0.89916) (xy 0.0635 -0.889) (xy 0.09144 -0.87376) (xy 0.11684 -0.85344) (xy 0.13716 -0.82804)
						(xy 0.1524 -0.8001) (xy 0.16256 -0.76835) (xy 0.1651 -0.7366) (xy 0.1651 -0.19685) (xy 0.17272 -0.18923)
						(xy 0.17907 -0.18034) (xy 0.18669 -0.17145) (xy 0.19177 -0.16256) (xy 0.19812 -0.15367) (xy 0.20828 -0.13335)
						(xy 0.21971 -0.10287) (xy 0.22225 -0.09271) (xy 0.22479 -0.08128) (xy 0.22606 -0.07112) (xy 0.2286 -0.05969)
						(xy 0.2286 -0.01651) (xy 0.22606 -0.00508) (xy 0.22479 0.00508) (xy 0.22225 0.01651) (xy 0.21971 0.02667)
						(xy 0.20828 0.05715) (xy 0.19812 0.07747) (xy 0.19177 0.08636) (xy 0.18669 0.09525) (xy 0.17907 0.10414)
						(xy 0.17272 0.11303) (xy 0.1651 0.12065) (xy 0.1651 0.7366) (xy 0.16256 0.76835) (xy 0.1524 0.8001)
						(xy 0.13716 0.82804) (xy 0.11684 0.85344) (xy 0.09144 0.87376) (xy 0.0635 0.889) (xy 0.03175 0.89916)
					)
					(width 0)
					(fill yes)
				)
			)
		)
		(pad "100" smd custom
			(at 0.450088 -4.106672)
			(size 0.1143 0.1143)
			(layers "F.Cu" "F.Mask" "F.Paste")
			(net "M_B_MA6")
			(options
				(clearance outline)
				(anchor circle)
			)
			(primitives
				(gr_poly
					(pts
						(xy 0 0.9017) (xy -0.03175 0.89916) (xy -0.0635 0.889) (xy -0.09144 0.87376) (xy -0.11684 0.85344)
						(xy -0.13716 0.82804) (xy -0.1524 0.8001) (xy -0.16256 0.76835) (xy -0.1651 0.7366) (xy -0.1651 0.19685)
						(xy -0.17272 0.18923) (xy -0.17907 0.18034) (xy -0.18669 0.17145) (xy -0.19177 0.16256) (xy -0.19812 0.15367)
						(xy -0.20828 0.13335) (xy -0.21971 0.10287) (xy -0.22225 0.09271) (xy -0.22479 0.08128) (xy -0.22606 0.07112)
						(xy -0.2286 0.05969) (xy -0.2286 0.01651) (xy -0.22606 0.00508) (xy -0.22479 -0.00508) (xy -0.22225 -0.01651)
						(xy -0.21971 -0.02667) (xy -0.20828 -0.05715) (xy -0.19812 -0.07747) (xy -0.19177 -0.08636) (xy -0.18669 -0.09525)
						(xy -0.17907 -0.10414) (xy -0.17272 -0.11303) (xy -0.1651 -0.12065) (xy -0.1651 -0.7366) (xy -0.16256 -0.76835)
						(xy -0.1524 -0.8001) (xy -0.13716 -0.82804) (xy -0.11684 -0.85344) (xy -0.09144 -0.87376) (xy -0.0635 -0.889)
						(xy -0.03175 -0.89916) (xy 0 -0.9017) (xy 0.03175 -0.89916) (xy 0.0635 -0.889) (xy 0.09144 -0.87376)
						(xy 0.11684 -0.85344) (xy 0.13716 -0.82804) (xy 0.1524 -0.8001) (xy 0.16256 -0.76835) (xy 0.1651 -0.7366)
						(xy 0.1651 -0.11938) (xy 0.17272 -0.11176) (xy 0.19812 -0.0762) (xy 0.2032 -0.06604) (xy 0.20701 -0.05715)
						(xy 0.21209 -0.04699) (xy 0.2159 -0.03683) (xy 0.21844 -0.02667) (xy 0.22225 -0.01524) (xy 0.22352 -0.00508)
						(xy 0.22606 0.00508) (xy 0.22733 0.01651) (xy 0.22733 0.02667) (xy 0.2286 0.0381) (xy 0.22733 0.04953)
						(xy 0.22733 0.05969) (xy 0.22606 0.07112) (xy 0.22352 0.08128) (xy 0.22225 0.09144) (xy 0.21844 0.10287)
						(xy 0.2159 0.11303) (xy 0.21209 0.12319) (xy 0.20701 0.13335) (xy 0.2032 0.14224) (xy 0.19812 0.1524)
						(xy 0.17272 0.18796) (xy 0.1651 0.19558) (xy 0.1651 0.7366) (xy 0.16256 0.76835) (xy 0.1524 0.8001)
						(xy 0.13716 0.82804) (xy 0.11684 0.85344) (xy 0.09144 0.87376) (xy 0.0635 0.889) (xy 0.03175 0.89916)
					)
					(width 0)
					(fill yes)
				)
			)
		)
		(pad "101" smd custom
			(at 0.750062 4.106672)
			(size 0.1143 0.1143)
			(layers "F.Cu" "F.Mask" "F.Paste")
			(net "PV_VDDR")
			(options
				(clearance outline)
				(anchor circle)
			)
			(primitives
				(gr_poly
					(pts
						(xy 0 0.9017) (xy -0.03175 0.89916) (xy -0.0635 0.889) (xy -0.09144 0.87376) (xy -0.11684 0.85344)
						(xy -0.13716 0.82804) (xy -0.1524 0.8001) (xy -0.16256 0.76835) (xy -0.1651 0.7366) (xy -0.1651 -0.13462)
						(xy -0.17272 -0.14224) (xy -0.19812 -0.1778) (xy -0.2032 -0.18796) (xy -0.20701 -0.19685) (xy -0.21209 -0.20701)
						(xy -0.2159 -0.21717) (xy -0.21844 -0.22733) (xy -0.22225 -0.23876) (xy -0.22352 -0.24892) (xy -0.22606 -0.25908)
						(xy -0.22733 -0.27051) (xy -0.22733 -0.28067) (xy -0.2286 -0.2921) (xy -0.22733 -0.30353) (xy -0.22733 -0.31369)
						(xy -0.22606 -0.32512) (xy -0.22352 -0.33528) (xy -0.22225 -0.34544) (xy -0.21844 -0.35687) (xy -0.2159 -0.36703)
						(xy -0.21209 -0.37719) (xy -0.20701 -0.38735) (xy -0.2032 -0.39624) (xy -0.19812 -0.4064) (xy -0.17272 -0.44196)
						(xy -0.1651 -0.44958) (xy -0.1651 -0.7366) (xy -0.16256 -0.76835) (xy -0.1524 -0.8001) (xy -0.13716 -0.82804)
						(xy -0.11684 -0.85344) (xy -0.09144 -0.87376) (xy -0.0635 -0.889) (xy -0.03175 -0.89916) (xy 0 -0.9017)
						(xy 0.03175 -0.89916) (xy 0.0635 -0.889) (xy 0.09144 -0.87376) (xy 0.11684 -0.85344) (xy 0.13716 -0.82804)
						(xy 0.1524 -0.8001) (xy 0.16256 -0.76835) (xy 0.1651 -0.7366) (xy 0.1651 -0.44958) (xy 0.17272 -0.44196)
						(xy 0.19812 -0.4064) (xy 0.2032 -0.39624) (xy 0.20701 -0.38735) (xy 0.21209 -0.37719) (xy 0.2159 -0.36703)
						(xy 0.21844 -0.35687) (xy 0.22225 -0.34544) (xy 0.22352 -0.33528) (xy 0.22606 -0.32512) (xy 0.22733 -0.31369)
						(xy 0.22733 -0.30353) (xy 0.2286 -0.2921) (xy 0.22733 -0.28067) (xy 0.22733 -0.27051) (xy 0.22606 -0.25908)
						(xy 0.22352 -0.24892) (xy 0.22225 -0.23876) (xy 0.21844 -0.22733) (xy 0.2159 -0.21717) (xy 0.21209 -0.20701)
						(xy 0.20701 -0.19685) (xy 0.2032 -0.18796) (xy 0.19812 -0.1778) (xy 0.17272 -0.14224) (xy 0.1651 -0.13462)
						(xy 0.1651 0.7366) (xy 0.16256 0.76835) (xy 0.1524 0.8001) (xy 0.13716 0.82804) (xy 0.11684 0.85344)
						(xy 0.09144 0.87376) (xy 0.0635 0.889) (xy 0.03175 0.89916)
					)
					(width 0)
					(fill yes)
				)
			)
		)
		(pad "102" smd custom
			(at 1.050036 -4.106672)
			(size 0.1143 0.1143)
			(layers "F.Cu" "F.Mask" "F.Paste")
			(net "PV_VDDR")
			(options
				(clearance outline)
				(anchor circle)
			)
			(primitives
				(gr_poly
					(pts
						(xy 0 0.9017) (xy -0.03175 0.89916) (xy -0.0635 0.889) (xy -0.09144 0.87376) (xy -0.11684 0.85344)
						(xy -0.13716 0.82804) (xy -0.1524 0.8001) (xy -0.16256 0.76835) (xy -0.1651 0.7366) (xy -0.1651 0.44958)
						(xy -0.17272 0.44196) (xy -0.19812 0.4064) (xy -0.2032 0.39624) (xy -0.20701 0.38735) (xy -0.21209 0.37719)
						(xy -0.2159 0.36703) (xy -0.21844 0.35687) (xy -0.22225 0.34544) (xy -0.22352 0.33528) (xy -0.22606 0.32512)
						(xy -0.22733 0.31369) (xy -0.22733 0.30353) (xy -0.2286 0.2921) (xy -0.22733 0.28067) (xy -0.22733 0.27051)
						(xy -0.22606 0.25908) (xy -0.22352 0.24892) (xy -0.22225 0.23876) (xy -0.21844 0.22733) (xy -0.2159 0.21717)
						(xy -0.21209 0.20701) (xy -0.20701 0.19685) (xy -0.2032 0.18796) (xy -0.19812 0.1778) (xy -0.17272 0.14224)
						(xy -0.1651 0.13462) (xy -0.1651 -0.7366) (xy -0.16256 -0.76835) (xy -0.1524 -0.8001) (xy -0.13716 -0.82804)
						(xy -0.11684 -0.85344) (xy -0.09144 -0.87376) (xy -0.0635 -0.889) (xy -0.03175 -0.89916) (xy 0 -0.9017)
						(xy 0.03175 -0.89916) (xy 0.0635 -0.889) (xy 0.09144 -0.87376) (xy 0.11684 -0.85344) (xy 0.13716 -0.82804)
						(xy 0.1524 -0.8001) (xy 0.16256 -0.76835) (xy 0.1651 -0.7366) (xy 0.1651 0.13462) (xy 0.17272 0.14224)
						(xy 0.19812 0.1778) (xy 0.2032 0.18796) (xy 0.20701 0.19685) (xy 0.21209 0.20701) (xy 0.2159 0.21717)
						(xy 0.21844 0.22733) (xy 0.22225 0.23876) (xy 0.22352 0.24892) (xy 0.22606 0.25908) (xy 0.22733 0.27051)
						(xy 0.22733 0.28067) (xy 0.2286 0.2921) (xy 0.22733 0.30353) (xy 0.22733 0.31369) (xy 0.22606 0.32512)
						(xy 0.22352 0.33528) (xy 0.22225 0.34544) (xy 0.21844 0.35687) (xy 0.2159 0.36703) (xy 0.21209 0.37719)
						(xy 0.20701 0.38735) (xy 0.2032 0.39624) (xy 0.19812 0.4064) (xy 0.17272 0.44196) (xy 0.1651 0.44958)
						(xy 0.1651 0.7366) (xy 0.16256 0.76835) (xy 0.1524 0.8001) (xy 0.13716 0.82804) (xy 0.11684 0.85344)
						(xy 0.09144 0.87376) (xy 0.0635 0.889) (xy 0.03175 0.89916)
					)
					(width 0)
					(fill yes)
				)
			)
		)
		(pad "103" smd custom
			(at 1.35001 4.106672)
			(size 0.1143 0.1143)
			(layers "F.Cu" "F.Mask" "F.Paste")
			(net "M_B_MA3")
			(options
				(clearance outline)
				(anchor circle)
			)
			(primitives
				(gr_poly
					(pts
						(xy 0 0.9017) (xy -0.03175 0.89916) (xy -0.0635 0.889) (xy -0.09144 0.87376) (xy -0.11684 0.85344)
						(xy -0.13716 0.82804) (xy -0.1524 0.8001) (xy -0.16256 0.76835) (xy -0.1651 0.7366) (xy -0.1651 0.11938)
						(xy -0.17272 0.11176) (xy -0.19812 0.0762) (xy -0.2032 0.06604) (xy -0.20701 0.05715) (xy -0.21209 0.04699)
						(xy -0.2159 0.03683) (xy -0.21844 0.02667) (xy -0.22225 0.01524) (xy -0.22352 0.00508) (xy -0.22606 -0.00508)
						(xy -0.22733 -0.01651) (xy -0.22733 -0.02667) (xy -0.2286 -0.0381) (xy -0.22733 -0.04953) (xy -0.22733 -0.05969)
						(xy -0.22606 -0.07112) (xy -0.22352 -0.08128) (xy -0.22225 -0.09144) (xy -0.21844 -0.10287) (xy -0.2159 -0.11303)
						(xy -0.21209 -0.12319) (xy -0.20701 -0.13335) (xy -0.2032 -0.14224) (xy -0.19812 -0.1524) (xy -0.17272 -0.18796)
						(xy -0.1651 -0.19558) (xy -0.1651 -0.7366) (xy -0.16256 -0.76835) (xy -0.1524 -0.8001) (xy -0.13716 -0.82804)
						(xy -0.11684 -0.85344) (xy -0.09144 -0.87376) (xy -0.0635 -0.889) (xy -0.03175 -0.89916) (xy 0 -0.9017)
						(xy 0.03175 -0.89916) (xy 0.0635 -0.889) (xy 0.09144 -0.87376) (xy 0.11684 -0.85344) (xy 0.13716 -0.82804)
						(xy 0.1524 -0.8001) (xy 0.16256 -0.76835) (xy 0.1651 -0.7366) (xy 0.1651 -0.19685) (xy 0.17272 -0.18923)
						(xy 0.17907 -0.18034) (xy 0.18669 -0.17145) (xy 0.19177 -0.16256) (xy 0.19812 -0.15367) (xy 0.20828 -0.13335)
						(xy 0.21971 -0.10287) (xy 0.22225 -0.09271) (xy 0.22479 -0.08128) (xy 0.22606 -0.07112) (xy 0.2286 -0.05969)
						(xy 0.2286 -0.01651) (xy 0.22606 -0.00508) (xy 0.22479 0.00508) (xy 0.22225 0.01651) (xy 0.21971 0.02667)
						(xy 0.20828 0.05715) (xy 0.19812 0.07747) (xy 0.19177 0.08636) (xy 0.18669 0.09525) (xy 0.17907 0.10414)
						(xy 0.17272 0.11303) (xy 0.1651 0.12065) (xy 0.1651 0.7366) (xy 0.16256 0.76835) (xy 0.1524 0.8001)
						(xy 0.13716 0.82804) (xy 0.11684 0.85344) (xy 0.09144 0.87376) (xy 0.0635 0.889) (xy 0.03175 0.89916)
					)
					(width 0)
					(fill yes)
				)
			)
		)
		(pad "104" smd custom
			(at 1.649984 -4.106672)
			(size 0.1143 0.1143)
			(layers "F.Cu" "F.Mask" "F.Paste")
			(net "M_B_MA4")
			(options
				(clearance outline)
				(anchor circle)
			)
			(primitives
				(gr_poly
					(pts
						(xy 0 0.9017) (xy -0.03175 0.89916) (xy -0.0635 0.889) (xy -0.09144 0.87376) (xy -0.11684 0.85344)
						(xy -0.13716 0.82804) (xy -0.1524 0.8001) (xy -0.16256 0.76835) (xy -0.1651 0.7366) (xy -0.1651 0.19685)
						(xy -0.17272 0.18923) (xy -0.17907 0.18034) (xy -0.18669 0.17145) (xy -0.19177 0.16256) (xy -0.19812 0.15367)
						(xy -0.20828 0.13335) (xy -0.21971 0.10287) (xy -0.22225 0.09271) (xy -0.22479 0.08128) (xy -0.22606 0.07112)
						(xy -0.2286 0.05969) (xy -0.2286 0.01651) (xy -0.22606 0.00508) (xy -0.22479 -0.00508) (xy -0.22225 -0.01651)
						(xy -0.21971 -0.02667) (xy -0.20828 -0.05715) (xy -0.19812 -0.07747) (xy -0.19177 -0.08636) (xy -0.18669 -0.09525)
						(xy -0.17907 -0.10414) (xy -0.17272 -0.11303) (xy -0.1651 -0.12065) (xy -0.1651 -0.7366) (xy -0.16256 -0.76835)
						(xy -0.1524 -0.8001) (xy -0.13716 -0.82804) (xy -0.11684 -0.85344) (xy -0.09144 -0.87376) (xy -0.0635 -0.889)
						(xy -0.03175 -0.89916) (xy 0 -0.9017) (xy 0.03175 -0.89916) (xy 0.0635 -0.889) (xy 0.09144 -0.87376)
						(xy 0.11684 -0.85344) (xy 0.13716 -0.82804) (xy 0.1524 -0.8001) (xy 0.16256 -0.76835) (xy 0.1651 -0.7366)
						(xy 0.1651 -0.11938) (xy 0.17272 -0.11176) (xy 0.19812 -0.0762) (xy 0.2032 -0.06604) (xy 0.20701 -0.05715)
						(xy 0.21209 -0.04699) (xy 0.2159 -0.03683) (xy 0.21844 -0.02667) (xy 0.22225 -0.01524) (xy 0.22352 -0.00508)
						(xy 0.22606 0.00508) (xy 0.22733 0.01651) (xy 0.22733 0.02667) (xy 0.2286 0.0381) (xy 0.22733 0.04953)
						(xy 0.22733 0.05969) (xy 0.22606 0.07112) (xy 0.22352 0.08128) (xy 0.22225 0.09144) (xy 0.21844 0.10287)
						(xy 0.2159 0.11303) (xy 0.21209 0.12319) (xy 0.20701 0.13335) (xy 0.2032 0.14224) (xy 0.19812 0.1524)
						(xy 0.17272 0.18796) (xy 0.1651 0.19558) (xy 0.1651 0.7366) (xy 0.16256 0.76835) (xy 0.1524 0.8001)
						(xy 0.13716 0.82804) (xy 0.11684 0.85344) (xy 0.09144 0.87376) (xy 0.0635 0.889) (xy 0.03175 0.89916)
					)
					(width 0)
					(fill yes)
				)
			)
		)
		(pad "105" smd custom
			(at 1.949958 4.106672)
			(size 0.1143 0.1143)
			(layers "F.Cu" "F.Mask" "F.Paste")
			(net "M_B_MA1")
			(options
				(clearance outline)
				(anchor circle)
			)
			(primitives
				(gr_poly
					(pts
						(xy 0 0.9017) (xy -0.03175 0.89916) (xy -0.0635 0.889) (xy -0.09144 0.87376) (xy -0.11684 0.85344)
						(xy -0.13716 0.82804) (xy -0.1524 0.8001) (xy -0.16256 0.76835) (xy -0.1651 0.7366) (xy -0.1651 -0.13462)
						(xy -0.17272 -0.14224) (xy -0.19812 -0.1778) (xy -0.2032 -0.18796) (xy -0.20701 -0.19685) (xy -0.21209 -0.20701)
						(xy -0.2159 -0.21717) (xy -0.21844 -0.22733) (xy -0.22225 -0.23876) (xy -0.22352 -0.24892) (xy -0.22606 -0.25908)
						(xy -0.22733 -0.27051) (xy -0.22733 -0.28067) (xy -0.2286 -0.2921) (xy -0.22733 -0.30353) (xy -0.22733 -0.31369)
						(xy -0.22606 -0.32512) (xy -0.22352 -0.33528) (xy -0.22225 -0.34544) (xy -0.21844 -0.35687) (xy -0.2159 -0.36703)
						(xy -0.21209 -0.37719) (xy -0.20701 -0.38735) (xy -0.2032 -0.39624) (xy -0.19812 -0.4064) (xy -0.17272 -0.44196)
						(xy -0.1651 -0.44958) (xy -0.1651 -0.7366) (xy -0.16256 -0.76835) (xy -0.1524 -0.8001) (xy -0.13716 -0.82804)
						(xy -0.11684 -0.85344) (xy -0.09144 -0.87376) (xy -0.0635 -0.889) (xy -0.03175 -0.89916) (xy 0 -0.9017)
						(xy 0.03175 -0.89916) (xy 0.0635 -0.889) (xy 0.09144 -0.87376) (xy 0.11684 -0.85344) (xy 0.13716 -0.82804)
						(xy 0.1524 -0.8001) (xy 0.16256 -0.76835) (xy 0.1651 -0.7366) (xy 0.1651 -0.44958) (xy 0.17272 -0.44196)
						(xy 0.19812 -0.4064) (xy 0.2032 -0.39624) (xy 0.20701 -0.38735) (xy 0.21209 -0.37719) (xy 0.2159 -0.36703)
						(xy 0.21844 -0.35687) (xy 0.22225 -0.34544) (xy 0.22352 -0.33528) (xy 0.22606 -0.32512) (xy 0.22733 -0.31369)
						(xy 0.22733 -0.30353) (xy 0.2286 -0.2921) (xy 0.22733 -0.28067) (xy 0.22733 -0.27051) (xy 0.22606 -0.25908)
						(xy 0.22352 -0.24892) (xy 0.22225 -0.23876) (xy 0.21844 -0.22733) (xy 0.2159 -0.21717) (xy 0.21209 -0.20701)
						(xy 0.20701 -0.19685) (xy 0.2032 -0.18796) (xy 0.19812 -0.1778) (xy 0.17272 -0.14224) (xy 0.1651 -0.13462)
						(xy 0.1651 0.7366) (xy 0.16256 0.76835) (xy 0.1524 0.8001) (xy 0.13716 0.82804) (xy 0.11684 0.85344)
						(xy 0.09144 0.87376) (xy 0.0635 0.889) (xy 0.03175 0.89916)
					)
					(width 0)
					(fill yes)
				)
			)
		)
		(pad "106" smd custom
			(at 2.249932 -4.106672)
			(size 0.1143 0.1143)
			(layers "F.Cu" "F.Mask" "F.Paste")
			(net "M_B_MA2")
			(options
				(clearance outline)
				(anchor circle)
			)
			(primitives
				(gr_poly
					(pts
						(xy 0 0.9017) (xy -0.03175 0.89916) (xy -0.0635 0.889) (xy -0.09144 0.87376) (xy -0.11684 0.85344)
						(xy -0.13716 0.82804) (xy -0.1524 0.8001) (xy -0.16256 0.76835) (xy -0.1651 0.7366) (xy -0.1651 0.44958)
						(xy -0.17272 0.44196) (xy -0.19812 0.4064) (xy -0.2032 0.39624) (xy -0.20701 0.38735) (xy -0.21209 0.37719)
						(xy -0.2159 0.36703) (xy -0.21844 0.35687) (xy -0.22225 0.34544) (xy -0.22352 0.33528) (xy -0.22606 0.32512)
						(xy -0.22733 0.31369) (xy -0.22733 0.30353) (xy -0.2286 0.2921) (xy -0.22733 0.28067) (xy -0.22733 0.27051)
						(xy -0.22606 0.25908) (xy -0.22352 0.24892) (xy -0.22225 0.23876) (xy -0.21844 0.22733) (xy -0.2159 0.21717)
						(xy -0.21209 0.20701) (xy -0.20701 0.19685) (xy -0.2032 0.18796) (xy -0.19812 0.1778) (xy -0.17272 0.14224)
						(xy -0.1651 0.13462) (xy -0.1651 -0.7366) (xy -0.16256 -0.76835) (xy -0.1524 -0.8001) (xy -0.13716 -0.82804)
						(xy -0.11684 -0.85344) (xy -0.09144 -0.87376) (xy -0.0635 -0.889) (xy -0.03175 -0.89916) (xy 0 -0.9017)
						(xy 0.03175 -0.89916) (xy 0.0635 -0.889) (xy 0.09144 -0.87376) (xy 0.11684 -0.85344) (xy 0.13716 -0.82804)
						(xy 0.1524 -0.8001) (xy 0.16256 -0.76835) (xy 0.1651 -0.7366) (xy 0.1651 0.13462) (xy 0.17272 0.14224)
						(xy 0.19812 0.1778) (xy 0.2032 0.18796) (xy 0.20701 0.19685) (xy 0.21209 0.20701) (xy 0.2159 0.21717)
						(xy 0.21844 0.22733) (xy 0.22225 0.23876) (xy 0.22352 0.24892) (xy 0.22606 0.25908) (xy 0.22733 0.27051)
						(xy 0.22733 0.28067) (xy 0.2286 0.2921) (xy 0.22733 0.30353) (xy 0.22733 0.31369) (xy 0.22606 0.32512)
						(xy 0.22352 0.33528) (xy 0.22225 0.34544) (xy 0.21844 0.35687) (xy 0.2159 0.36703) (xy 0.21209 0.37719)
						(xy 0.20701 0.38735) (xy 0.2032 0.39624) (xy 0.19812 0.4064) (xy 0.17272 0.44196) (xy 0.1651 0.44958)
						(xy 0.1651 0.7366) (xy 0.16256 0.76835) (xy 0.1524 0.8001) (xy 0.13716 0.82804) (xy 0.11684 0.85344)
						(xy 0.09144 0.87376) (xy 0.0635 0.889) (xy 0.03175 0.89916)
					)
					(width 0)
					(fill yes)
				)
			)
		)
		(pad "107" smd custom
			(at 2.549906 4.106672)
			(size 0.1143 0.1143)
			(layers "F.Cu" "F.Mask" "F.Paste")
			(net "M_B_MA0")
			(options
				(clearance outline)
				(anchor circle)
			)
			(primitives
				(gr_poly
					(pts
						(xy 0 0.9017) (xy -0.03175 0.89916) (xy -0.0635 0.889) (xy -0.09144 0.87376) (xy -0.11684 0.85344)
						(xy -0.13716 0.82804) (xy -0.1524 0.8001) (xy -0.16256 0.76835) (xy -0.1651 0.7366) (xy -0.1651 0.11938)
						(xy -0.17272 0.11176) (xy -0.19812 0.0762) (xy -0.2032 0.06604) (xy -0.20701 0.05715) (xy -0.21209 0.04699)
						(xy -0.2159 0.03683) (xy -0.21844 0.02667) (xy -0.22225 0.01524) (xy -0.22352 0.00508) (xy -0.22606 -0.00508)
						(xy -0.22733 -0.01651) (xy -0.22733 -0.02667) (xy -0.2286 -0.0381) (xy -0.22733 -0.04953) (xy -0.22733 -0.05969)
						(xy -0.22606 -0.07112) (xy -0.22352 -0.08128) (xy -0.22225 -0.09144) (xy -0.21844 -0.10287) (xy -0.2159 -0.11303)
						(xy -0.21209 -0.12319) (xy -0.20701 -0.13335) (xy -0.2032 -0.14224) (xy -0.19812 -0.1524) (xy -0.17272 -0.18796)
						(xy -0.1651 -0.19558) (xy -0.1651 -0.7366) (xy -0.16256 -0.76835) (xy -0.1524 -0.8001) (xy -0.13716 -0.82804)
						(xy -0.11684 -0.85344) (xy -0.09144 -0.87376) (xy -0.0635 -0.889) (xy -0.03175 -0.89916) (xy 0 -0.9017)
						(xy 0.03175 -0.89916) (xy 0.0635 -0.889) (xy 0.09144 -0.87376) (xy 0.11684 -0.85344) (xy 0.13716 -0.82804)
						(xy 0.1524 -0.8001) (xy 0.16256 -0.76835) (xy 0.1651 -0.7366) (xy 0.1651 -0.19685) (xy 0.17272 -0.18923)
						(xy 0.17907 -0.18034) (xy 0.18669 -0.17145) (xy 0.19177 -0.16256) (xy 0.19812 -0.15367) (xy 0.20828 -0.13335)
						(xy 0.21971 -0.10287) (xy 0.22225 -0.09271) (xy 0.22479 -0.08128) (xy 0.22606 -0.07112) (xy 0.2286 -0.05969)
						(xy 0.2286 -0.01651) (xy 0.22606 -0.00508) (xy 0.22479 0.00508) (xy 0.22225 0.01651) (xy 0.21971 0.02667)
						(xy 0.20828 0.05715) (xy 0.19812 0.07747) (xy 0.19177 0.08636) (xy 0.18669 0.09525) (xy 0.17907 0.10414)
						(xy 0.17272 0.11303) (xy 0.1651 0.12065) (xy 0.1651 0.7366) (xy 0.16256 0.76835) (xy 0.1524 0.8001)
						(xy 0.13716 0.82804) (xy 0.11684 0.85344) (xy 0.09144 0.87376) (xy 0.0635 0.889) (xy 0.03175 0.89916)
					)
					(width 0)
					(fill yes)
				)
			)
		)
		(pad "108" smd custom
			(at 2.84988 -4.106672)
			(size 0.1143 0.1143)
			(layers "F.Cu" "F.Mask" "F.Paste")
			(net "M_B_BS1")
			(options
				(clearance outline)
				(anchor circle)
			)
			(primitives
				(gr_poly
					(pts
						(xy 0 0.9017) (xy -0.03175 0.89916) (xy -0.0635 0.889) (xy -0.09144 0.87376) (xy -0.11684 0.85344)
						(xy -0.13716 0.82804) (xy -0.1524 0.8001) (xy -0.16256 0.76835) (xy -0.1651 0.7366) (xy -0.1651 0.19685)
						(xy -0.17272 0.18923) (xy -0.17907 0.18034) (xy -0.18669 0.17145) (xy -0.19177 0.16256) (xy -0.19812 0.15367)
						(xy -0.20828 0.13335) (xy -0.21971 0.10287) (xy -0.22225 0.09271) (xy -0.22479 0.08128) (xy -0.22606 0.07112)
						(xy -0.2286 0.05969) (xy -0.2286 0.01651) (xy -0.22606 0.00508) (xy -0.22479 -0.00508) (xy -0.22225 -0.01651)
						(xy -0.21971 -0.02667) (xy -0.20828 -0.05715) (xy -0.19812 -0.07747) (xy -0.19177 -0.08636) (xy -0.18669 -0.09525)
						(xy -0.17907 -0.10414) (xy -0.17272 -0.11303) (xy -0.1651 -0.12065) (xy -0.1651 -0.7366) (xy -0.16256 -0.76835)
						(xy -0.1524 -0.8001) (xy -0.13716 -0.82804) (xy -0.11684 -0.85344) (xy -0.09144 -0.87376) (xy -0.0635 -0.889)
						(xy -0.03175 -0.89916) (xy 0 -0.9017) (xy 0.03175 -0.89916) (xy 0.0635 -0.889) (xy 0.09144 -0.87376)
						(xy 0.11684 -0.85344) (xy 0.13716 -0.82804) (xy 0.1524 -0.8001) (xy 0.16256 -0.76835) (xy 0.1651 -0.7366)
						(xy 0.1651 -0.11938) (xy 0.17272 -0.11176) (xy 0.19812 -0.0762) (xy 0.2032 -0.06604) (xy 0.20701 -0.05715)
						(xy 0.21209 -0.04699) (xy 0.2159 -0.03683) (xy 0.21844 -0.02667) (xy 0.22225 -0.01524) (xy 0.22352 -0.00508)
						(xy 0.22606 0.00508) (xy 0.22733 0.01651) (xy 0.22733 0.02667) (xy 0.2286 0.0381) (xy 0.22733 0.04953)
						(xy 0.22733 0.05969) (xy 0.22606 0.07112) (xy 0.22352 0.08128) (xy 0.22225 0.09144) (xy 0.21844 0.10287)
						(xy 0.2159 0.11303) (xy 0.21209 0.12319) (xy 0.20701 0.13335) (xy 0.2032 0.14224) (xy 0.19812 0.1524)
						(xy 0.17272 0.18796) (xy 0.1651 0.19558) (xy 0.1651 0.7366) (xy 0.16256 0.76835) (xy 0.1524 0.8001)
						(xy 0.13716 0.82804) (xy 0.11684 0.85344) (xy 0.09144 0.87376) (xy 0.0635 0.889) (xy 0.03175 0.89916)
					)
					(width 0)
					(fill yes)
				)
			)
		)
		(pad "109" smd custom
			(at 3.150108 4.106672)
			(size 0.1143 0.1143)
			(layers "F.Cu" "F.Mask" "F.Paste")
			(net "PV_VDDR")
			(options
				(clearance outline)
				(anchor circle)
			)
			(primitives
				(gr_poly
					(pts
						(xy 0 0.9017) (xy -0.03175 0.89916) (xy -0.0635 0.889) (xy -0.09144 0.87376) (xy -0.11684 0.85344)
						(xy -0.13716 0.82804) (xy -0.1524 0.8001) (xy -0.16256 0.76835) (xy -0.1651 0.7366) (xy -0.1651 -0.13462)
						(xy -0.17272 -0.14224) (xy -0.19812 -0.1778) (xy -0.2032 -0.18796) (xy -0.20701 -0.19685) (xy -0.21209 -0.20701)
						(xy -0.2159 -0.21717) (xy -0.21844 -0.22733) (xy -0.22225 -0.23876) (xy -0.22352 -0.24892) (xy -0.22606 -0.25908)
						(xy -0.22733 -0.27051) (xy -0.22733 -0.28067) (xy -0.2286 -0.2921) (xy -0.22733 -0.30353) (xy -0.22733 -0.31369)
						(xy -0.22606 -0.32512) (xy -0.22352 -0.33528) (xy -0.22225 -0.34544) (xy -0.21844 -0.35687) (xy -0.2159 -0.36703)
						(xy -0.21209 -0.37719) (xy -0.20701 -0.38735) (xy -0.2032 -0.39624) (xy -0.19812 -0.4064) (xy -0.17272 -0.44196)
						(xy -0.1651 -0.44958) (xy -0.1651 -0.7366) (xy -0.16256 -0.76835) (xy -0.1524 -0.8001) (xy -0.13716 -0.82804)
						(xy -0.11684 -0.85344) (xy -0.09144 -0.87376) (xy -0.0635 -0.889) (xy -0.03175 -0.89916) (xy 0 -0.9017)
						(xy 0.03175 -0.89916) (xy 0.0635 -0.889) (xy 0.09144 -0.87376) (xy 0.11684 -0.85344) (xy 0.13716 -0.82804)
						(xy 0.1524 -0.8001) (xy 0.16256 -0.76835) (xy 0.1651 -0.7366) (xy 0.1651 -0.44958) (xy 0.17272 -0.44196)
						(xy 0.19812 -0.4064) (xy 0.2032 -0.39624) (xy 0.20701 -0.38735) (xy 0.21209 -0.37719) (xy 0.2159 -0.36703)
						(xy 0.21844 -0.35687) (xy 0.22225 -0.34544) (xy 0.22352 -0.33528) (xy 0.22606 -0.32512) (xy 0.22733 -0.31369)
						(xy 0.22733 -0.30353) (xy 0.2286 -0.2921) (xy 0.22733 -0.28067) (xy 0.22733 -0.27051) (xy 0.22606 -0.25908)
						(xy 0.22352 -0.24892) (xy 0.22225 -0.23876) (xy 0.21844 -0.22733) (xy 0.2159 -0.21717) (xy 0.21209 -0.20701)
						(xy 0.20701 -0.19685) (xy 0.2032 -0.18796) (xy 0.19812 -0.1778) (xy 0.17272 -0.14224) (xy 0.1651 -0.13462)
						(xy 0.1651 0.7366) (xy 0.16256 0.76835) (xy 0.1524 0.8001) (xy 0.13716 0.82804) (xy 0.11684 0.85344)
						(xy 0.09144 0.87376) (xy 0.0635 0.889) (xy 0.03175 0.89916)
					)
					(width 0)
					(fill yes)
				)
			)
		)
		(pad "110" smd custom
			(at 3.450082 -4.106672)
			(size 0.1143 0.1143)
			(layers "F.Cu" "F.Mask" "F.Paste")
			(net "PV_VDDR")
			(options
				(clearance outline)
				(anchor circle)
			)
			(primitives
				(gr_poly
					(pts
						(xy 0 0.9017) (xy -0.03175 0.89916) (xy -0.0635 0.889) (xy -0.09144 0.87376) (xy -0.11684 0.85344)
						(xy -0.13716 0.82804) (xy -0.1524 0.8001) (xy -0.16256 0.76835) (xy -0.1651 0.7366) (xy -0.1651 0.44958)
						(xy -0.17272 0.44196) (xy -0.19812 0.4064) (xy -0.2032 0.39624) (xy -0.20701 0.38735) (xy -0.21209 0.37719)
						(xy -0.2159 0.36703) (xy -0.21844 0.35687) (xy -0.22225 0.34544) (xy -0.22352 0.33528) (xy -0.22606 0.32512)
						(xy -0.22733 0.31369) (xy -0.22733 0.30353) (xy -0.2286 0.2921) (xy -0.22733 0.28067) (xy -0.22733 0.27051)
						(xy -0.22606 0.25908) (xy -0.22352 0.24892) (xy -0.22225 0.23876) (xy -0.21844 0.22733) (xy -0.2159 0.21717)
						(xy -0.21209 0.20701) (xy -0.20701 0.19685) (xy -0.2032 0.18796) (xy -0.19812 0.1778) (xy -0.17272 0.14224)
						(xy -0.1651 0.13462) (xy -0.1651 -0.7366) (xy -0.16256 -0.76835) (xy -0.1524 -0.8001) (xy -0.13716 -0.82804)
						(xy -0.11684 -0.85344) (xy -0.09144 -0.87376) (xy -0.0635 -0.889) (xy -0.03175 -0.89916) (xy 0 -0.9017)
						(xy 0.03175 -0.89916) (xy 0.0635 -0.889) (xy 0.09144 -0.87376) (xy 0.11684 -0.85344) (xy 0.13716 -0.82804)
						(xy 0.1524 -0.8001) (xy 0.16256 -0.76835) (xy 0.1651 -0.7366) (xy 0.1651 0.13462) (xy 0.17272 0.14224)
						(xy 0.19812 0.1778) (xy 0.2032 0.18796) (xy 0.20701 0.19685) (xy 0.21209 0.20701) (xy 0.2159 0.21717)
						(xy 0.21844 0.22733) (xy 0.22225 0.23876) (xy 0.22352 0.24892) (xy 0.22606 0.25908) (xy 0.22733 0.27051)
						(xy 0.22733 0.28067) (xy 0.2286 0.2921) (xy 0.22733 0.30353) (xy 0.22733 0.31369) (xy 0.22606 0.32512)
						(xy 0.22352 0.33528) (xy 0.22225 0.34544) (xy 0.21844 0.35687) (xy 0.2159 0.36703) (xy 0.21209 0.37719)
						(xy 0.20701 0.38735) (xy 0.2032 0.39624) (xy 0.19812 0.4064) (xy 0.17272 0.44196) (xy 0.1651 0.44958)
						(xy 0.1651 0.7366) (xy 0.16256 0.76835) (xy 0.1524 0.8001) (xy 0.13716 0.82804) (xy 0.11684 0.85344)
						(xy 0.09144 0.87376) (xy 0.0635 0.889) (xy 0.03175 0.89916)
					)
					(width 0)
					(fill yes)
				)
			)
		)
		(pad "111" smd custom
			(at 3.750056 4.106672)
			(size 0.1143 0.1143)
			(layers "F.Cu" "F.Mask" "F.Paste")
			(net "M_B_CK_DP2")
			(options
				(clearance outline)
				(anchor circle)
			)
			(primitives
				(gr_poly
					(pts
						(xy 0 0.9017) (xy -0.03175 0.89916) (xy -0.0635 0.889) (xy -0.09144 0.87376) (xy -0.11684 0.85344)
						(xy -0.13716 0.82804) (xy -0.1524 0.8001) (xy -0.16256 0.76835) (xy -0.1651 0.7366) (xy -0.1651 0.11938)
						(xy -0.17272 0.11176) (xy -0.19812 0.0762) (xy -0.2032 0.06604) (xy -0.20701 0.05715) (xy -0.21209 0.04699)
						(xy -0.2159 0.03683) (xy -0.21844 0.02667) (xy -0.22225 0.01524) (xy -0.22352 0.00508) (xy -0.22606 -0.00508)
						(xy -0.22733 -0.01651) (xy -0.22733 -0.02667) (xy -0.2286 -0.0381) (xy -0.22733 -0.04953) (xy -0.22733 -0.05969)
						(xy -0.22606 -0.07112) (xy -0.22352 -0.08128) (xy -0.22225 -0.09144) (xy -0.21844 -0.10287) (xy -0.2159 -0.11303)
						(xy -0.21209 -0.12319) (xy -0.20701 -0.13335) (xy -0.2032 -0.14224) (xy -0.19812 -0.1524) (xy -0.17272 -0.18796)
						(xy -0.1651 -0.19558) (xy -0.1651 -0.7366) (xy -0.16256 -0.76835) (xy -0.1524 -0.8001) (xy -0.13716 -0.82804)
						(xy -0.11684 -0.85344) (xy -0.09144 -0.87376) (xy -0.0635 -0.889) (xy -0.03175 -0.89916) (xy 0 -0.9017)
						(xy 0.03175 -0.89916) (xy 0.0635 -0.889) (xy 0.09144 -0.87376) (xy 0.11684 -0.85344) (xy 0.13716 -0.82804)
						(xy 0.1524 -0.8001) (xy 0.16256 -0.76835) (xy 0.1651 -0.7366) (xy 0.1651 -0.19685) (xy 0.17272 -0.18923)
						(xy 0.17907 -0.18034) (xy 0.18669 -0.17145) (xy 0.19177 -0.16256) (xy 0.19812 -0.15367) (xy 0.20828 -0.13335)
						(xy 0.21971 -0.10287) (xy 0.22225 -0.09271) (xy 0.22479 -0.08128) (xy 0.22606 -0.07112) (xy 0.2286 -0.05969)
						(xy 0.2286 -0.01651) (xy 0.22606 -0.00508) (xy 0.22479 0.00508) (xy 0.22225 0.01651) (xy 0.21971 0.02667)
						(xy 0.20828 0.05715) (xy 0.19812 0.07747) (xy 0.19177 0.08636) (xy 0.18669 0.09525) (xy 0.17907 0.10414)
						(xy 0.17272 0.11303) (xy 0.1651 0.12065) (xy 0.1651 0.7366) (xy 0.16256 0.76835) (xy 0.1524 0.8001)
						(xy 0.13716 0.82804) (xy 0.11684 0.85344) (xy 0.09144 0.87376) (xy 0.0635 0.889) (xy 0.03175 0.89916)
					)
					(width 0)
					(fill yes)
				)
			)
		)
		(pad "112" smd custom
			(at 4.05003 -4.106672)
			(size 0.1143 0.1143)
			(layers "F.Cu" "F.Mask" "F.Paste")
			(net "M_B_CK_DP3")
			(options
				(clearance outline)
				(anchor circle)
			)
			(primitives
				(gr_poly
					(pts
						(xy 0 0.9017) (xy -0.03175 0.89916) (xy -0.0635 0.889) (xy -0.09144 0.87376) (xy -0.11684 0.85344)
						(xy -0.13716 0.82804) (xy -0.1524 0.8001) (xy -0.16256 0.76835) (xy -0.1651 0.7366) (xy -0.1651 0.19685)
						(xy -0.17272 0.18923) (xy -0.17907 0.18034) (xy -0.18669 0.17145) (xy -0.19177 0.16256) (xy -0.19812 0.15367)
						(xy -0.20828 0.13335) (xy -0.21971 0.10287) (xy -0.22225 0.09271) (xy -0.22479 0.08128) (xy -0.22606 0.07112)
						(xy -0.2286 0.05969) (xy -0.2286 0.01651) (xy -0.22606 0.00508) (xy -0.22479 -0.00508) (xy -0.22225 -0.01651)
						(xy -0.21971 -0.02667) (xy -0.20828 -0.05715) (xy -0.19812 -0.07747) (xy -0.19177 -0.08636) (xy -0.18669 -0.09525)
						(xy -0.17907 -0.10414) (xy -0.17272 -0.11303) (xy -0.1651 -0.12065) (xy -0.1651 -0.7366) (xy -0.16256 -0.76835)
						(xy -0.1524 -0.8001) (xy -0.13716 -0.82804) (xy -0.11684 -0.85344) (xy -0.09144 -0.87376) (xy -0.0635 -0.889)
						(xy -0.03175 -0.89916) (xy 0 -0.9017) (xy 0.03175 -0.89916) (xy 0.0635 -0.889) (xy 0.09144 -0.87376)
						(xy 0.11684 -0.85344) (xy 0.13716 -0.82804) (xy 0.1524 -0.8001) (xy 0.16256 -0.76835) (xy 0.1651 -0.7366)
						(xy 0.1651 -0.11938) (xy 0.17272 -0.11176) (xy 0.19812 -0.0762) (xy 0.2032 -0.06604) (xy 0.20701 -0.05715)
						(xy 0.21209 -0.04699) (xy 0.2159 -0.03683) (xy 0.21844 -0.02667) (xy 0.22225 -0.01524) (xy 0.22352 -0.00508)
						(xy 0.22606 0.00508) (xy 0.22733 0.01651) (xy 0.22733 0.02667) (xy 0.2286 0.0381) (xy 0.22733 0.04953)
						(xy 0.22733 0.05969) (xy 0.22606 0.07112) (xy 0.22352 0.08128) (xy 0.22225 0.09144) (xy 0.21844 0.10287)
						(xy 0.2159 0.11303) (xy 0.21209 0.12319) (xy 0.20701 0.13335) (xy 0.2032 0.14224) (xy 0.19812 0.1524)
						(xy 0.17272 0.18796) (xy 0.1651 0.19558) (xy 0.1651 0.7366) (xy 0.16256 0.76835) (xy 0.1524 0.8001)
						(xy 0.13716 0.82804) (xy 0.11684 0.85344) (xy 0.09144 0.87376) (xy 0.0635 0.889) (xy 0.03175 0.89916)
					)
					(width 0)
					(fill yes)
				)
			)
		)
		(pad "113" smd custom
			(at 4.350004 4.106672)
			(size 0.1143 0.1143)
			(layers "F.Cu" "F.Mask" "F.Paste")
			(net "M_B_CK_DN2")
			(options
				(clearance outline)
				(anchor circle)
			)
			(primitives
				(gr_poly
					(pts
						(xy 0 0.9017) (xy -0.03175 0.89916) (xy -0.0635 0.889) (xy -0.09144 0.87376) (xy -0.11684 0.85344)
						(xy -0.13716 0.82804) (xy -0.1524 0.8001) (xy -0.16256 0.76835) (xy -0.1651 0.7366) (xy -0.1651 -0.13462)
						(xy -0.17272 -0.14224) (xy -0.19812 -0.1778) (xy -0.2032 -0.18796) (xy -0.20701 -0.19685) (xy -0.21209 -0.20701)
						(xy -0.2159 -0.21717) (xy -0.21844 -0.22733) (xy -0.22225 -0.23876) (xy -0.22352 -0.24892) (xy -0.22606 -0.25908)
						(xy -0.22733 -0.27051) (xy -0.22733 -0.28067) (xy -0.2286 -0.2921) (xy -0.22733 -0.30353) (xy -0.22733 -0.31369)
						(xy -0.22606 -0.32512) (xy -0.22352 -0.33528) (xy -0.22225 -0.34544) (xy -0.21844 -0.35687) (xy -0.2159 -0.36703)
						(xy -0.21209 -0.37719) (xy -0.20701 -0.38735) (xy -0.2032 -0.39624) (xy -0.19812 -0.4064) (xy -0.17272 -0.44196)
						(xy -0.1651 -0.44958) (xy -0.1651 -0.7366) (xy -0.16256 -0.76835) (xy -0.1524 -0.8001) (xy -0.13716 -0.82804)
						(xy -0.11684 -0.85344) (xy -0.09144 -0.87376) (xy -0.0635 -0.889) (xy -0.03175 -0.89916) (xy 0 -0.9017)
						(xy 0.03175 -0.89916) (xy 0.0635 -0.889) (xy 0.09144 -0.87376) (xy 0.11684 -0.85344) (xy 0.13716 -0.82804)
						(xy 0.1524 -0.8001) (xy 0.16256 -0.76835) (xy 0.1651 -0.7366) (xy 0.1651 -0.44958) (xy 0.17272 -0.44196)
						(xy 0.19812 -0.4064) (xy 0.2032 -0.39624) (xy 0.20701 -0.38735) (xy 0.21209 -0.37719) (xy 0.2159 -0.36703)
						(xy 0.21844 -0.35687) (xy 0.22225 -0.34544) (xy 0.22352 -0.33528) (xy 0.22606 -0.32512) (xy 0.22733 -0.31369)
						(xy 0.22733 -0.30353) (xy 0.2286 -0.2921) (xy 0.22733 -0.28067) (xy 0.22733 -0.27051) (xy 0.22606 -0.25908)
						(xy 0.22352 -0.24892) (xy 0.22225 -0.23876) (xy 0.21844 -0.22733) (xy 0.2159 -0.21717) (xy 0.21209 -0.20701)
						(xy 0.20701 -0.19685) (xy 0.2032 -0.18796) (xy 0.19812 -0.1778) (xy 0.17272 -0.14224) (xy 0.1651 -0.13462)
						(xy 0.1651 0.7366) (xy 0.16256 0.76835) (xy 0.1524 0.8001) (xy 0.13716 0.82804) (xy 0.11684 0.85344)
						(xy 0.09144 0.87376) (xy 0.0635 0.889) (xy 0.03175 0.89916)
					)
					(width 0)
					(fill yes)
				)
			)
		)
		(pad "114" smd custom
			(at 4.649978 -4.106672)
			(size 0.1143 0.1143)
			(layers "F.Cu" "F.Mask" "F.Paste")
			(net "M_B_CK_DN3")
			(options
				(clearance outline)
				(anchor circle)
			)
			(primitives
				(gr_poly
					(pts
						(xy 0 0.9017) (xy -0.03175 0.89916) (xy -0.0635 0.889) (xy -0.09144 0.87376) (xy -0.11684 0.85344)
						(xy -0.13716 0.82804) (xy -0.1524 0.8001) (xy -0.16256 0.76835) (xy -0.1651 0.7366) (xy -0.1651 0.44958)
						(xy -0.17272 0.44196) (xy -0.19812 0.4064) (xy -0.2032 0.39624) (xy -0.20701 0.38735) (xy -0.21209 0.37719)
						(xy -0.2159 0.36703) (xy -0.21844 0.35687) (xy -0.22225 0.34544) (xy -0.22352 0.33528) (xy -0.22606 0.32512)
						(xy -0.22733 0.31369) (xy -0.22733 0.30353) (xy -0.2286 0.2921) (xy -0.22733 0.28067) (xy -0.22733 0.27051)
						(xy -0.22606 0.25908) (xy -0.22352 0.24892) (xy -0.22225 0.23876) (xy -0.21844 0.22733) (xy -0.2159 0.21717)
						(xy -0.21209 0.20701) (xy -0.20701 0.19685) (xy -0.2032 0.18796) (xy -0.19812 0.1778) (xy -0.17272 0.14224)
						(xy -0.1651 0.13462) (xy -0.1651 -0.7366) (xy -0.16256 -0.76835) (xy -0.1524 -0.8001) (xy -0.13716 -0.82804)
						(xy -0.11684 -0.85344) (xy -0.09144 -0.87376) (xy -0.0635 -0.889) (xy -0.03175 -0.89916) (xy 0 -0.9017)
						(xy 0.03175 -0.89916) (xy 0.0635 -0.889) (xy 0.09144 -0.87376) (xy 0.11684 -0.85344) (xy 0.13716 -0.82804)
						(xy 0.1524 -0.8001) (xy 0.16256 -0.76835) (xy 0.1651 -0.7366) (xy 0.1651 0.13462) (xy 0.17272 0.14224)
						(xy 0.19812 0.1778) (xy 0.2032 0.18796) (xy 0.20701 0.19685) (xy 0.21209 0.20701) (xy 0.2159 0.21717)
						(xy 0.21844 0.22733) (xy 0.22225 0.23876) (xy 0.22352 0.24892) (xy 0.22606 0.25908) (xy 0.22733 0.27051)
						(xy 0.22733 0.28067) (xy 0.2286 0.2921) (xy 0.22733 0.30353) (xy 0.22733 0.31369) (xy 0.22606 0.32512)
						(xy 0.22352 0.33528) (xy 0.22225 0.34544) (xy 0.21844 0.35687) (xy 0.2159 0.36703) (xy 0.21209 0.37719)
						(xy 0.20701 0.38735) (xy 0.2032 0.39624) (xy 0.19812 0.4064) (xy 0.17272 0.44196) (xy 0.1651 0.44958)
						(xy 0.1651 0.7366) (xy 0.16256 0.76835) (xy 0.1524 0.8001) (xy 0.13716 0.82804) (xy 0.11684 0.85344)
						(xy 0.09144 0.87376) (xy 0.0635 0.889) (xy 0.03175 0.89916)
					)
					(width 0)
					(fill yes)
				)
			)
		)
		(pad "115" smd custom
			(at 4.949952 4.106672)
			(size 0.1143 0.1143)
			(layers "F.Cu" "F.Mask" "F.Paste")
			(net "PV_VDDR")
			(options
				(clearance outline)
				(anchor circle)
			)
			(primitives
				(gr_poly
					(pts
						(xy 0 0.9017) (xy -0.03175 0.89916) (xy -0.0635 0.889) (xy -0.09144 0.87376) (xy -0.11684 0.85344)
						(xy -0.13716 0.82804) (xy -0.1524 0.8001) (xy -0.16256 0.76835) (xy -0.1651 0.7366) (xy -0.1651 0.11938)
						(xy -0.17272 0.11176) (xy -0.19812 0.0762) (xy -0.2032 0.06604) (xy -0.20701 0.05715) (xy -0.21209 0.04699)
						(xy -0.2159 0.03683) (xy -0.21844 0.02667) (xy -0.22225 0.01524) (xy -0.22352 0.00508) (xy -0.22606 -0.00508)
						(xy -0.22733 -0.01651) (xy -0.22733 -0.02667) (xy -0.2286 -0.0381) (xy -0.22733 -0.04953) (xy -0.22733 -0.05969)
						(xy -0.22606 -0.07112) (xy -0.22352 -0.08128) (xy -0.22225 -0.09144) (xy -0.21844 -0.10287) (xy -0.2159 -0.11303)
						(xy -0.21209 -0.12319) (xy -0.20701 -0.13335) (xy -0.2032 -0.14224) (xy -0.19812 -0.1524) (xy -0.17272 -0.18796)
						(xy -0.1651 -0.19558) (xy -0.1651 -0.7366) (xy -0.16256 -0.76835) (xy -0.1524 -0.8001) (xy -0.13716 -0.82804)
						(xy -0.11684 -0.85344) (xy -0.09144 -0.87376) (xy -0.0635 -0.889) (xy -0.03175 -0.89916) (xy 0 -0.9017)
						(xy 0.03175 -0.89916) (xy 0.0635 -0.889) (xy 0.09144 -0.87376) (xy 0.11684 -0.85344) (xy 0.13716 -0.82804)
						(xy 0.1524 -0.8001) (xy 0.16256 -0.76835) (xy 0.1651 -0.7366) (xy 0.1651 -0.19685) (xy 0.17272 -0.18923)
						(xy 0.17907 -0.18034) (xy 0.18669 -0.17145) (xy 0.19177 -0.16256) (xy 0.19812 -0.15367) (xy 0.20828 -0.13335)
						(xy 0.21971 -0.10287) (xy 0.22225 -0.09271) (xy 0.22479 -0.08128) (xy 0.22606 -0.07112) (xy 0.2286 -0.05969)
						(xy 0.2286 -0.01651) (xy 0.22606 -0.00508) (xy 0.22479 0.00508) (xy 0.22225 0.01651) (xy 0.21971 0.02667)
						(xy 0.20828 0.05715) (xy 0.19812 0.07747) (xy 0.19177 0.08636) (xy 0.18669 0.09525) (xy 0.17907 0.10414)
						(xy 0.17272 0.11303) (xy 0.1651 0.12065) (xy 0.1651 0.7366) (xy 0.16256 0.76835) (xy 0.1524 0.8001)
						(xy 0.13716 0.82804) (xy 0.11684 0.85344) (xy 0.09144 0.87376) (xy 0.0635 0.889) (xy 0.03175 0.89916)
					)
					(width 0)
					(fill yes)
				)
			)
		)
		(pad "116" smd custom
			(at 5.249926 -4.106672)
			(size 0.1143 0.1143)
			(layers "F.Cu" "F.Mask" "F.Paste")
			(net "PV_VDDR")
			(options
				(clearance outline)
				(anchor circle)
			)
			(primitives
				(gr_poly
					(pts
						(xy 0 0.9017) (xy -0.03175 0.89916) (xy -0.0635 0.889) (xy -0.09144 0.87376) (xy -0.11684 0.85344)
						(xy -0.13716 0.82804) (xy -0.1524 0.8001) (xy -0.16256 0.76835) (xy -0.1651 0.7366) (xy -0.1651 0.19685)
						(xy -0.17272 0.18923) (xy -0.17907 0.18034) (xy -0.18669 0.17145) (xy -0.19177 0.16256) (xy -0.19812 0.15367)
						(xy -0.20828 0.13335) (xy -0.21971 0.10287) (xy -0.22225 0.09271) (xy -0.22479 0.08128) (xy -0.22606 0.07112)
						(xy -0.2286 0.05969) (xy -0.2286 0.01651) (xy -0.22606 0.00508) (xy -0.22479 -0.00508) (xy -0.22225 -0.01651)
						(xy -0.21971 -0.02667) (xy -0.20828 -0.05715) (xy -0.19812 -0.07747) (xy -0.19177 -0.08636) (xy -0.18669 -0.09525)
						(xy -0.17907 -0.10414) (xy -0.17272 -0.11303) (xy -0.1651 -0.12065) (xy -0.1651 -0.7366) (xy -0.16256 -0.76835)
						(xy -0.1524 -0.8001) (xy -0.13716 -0.82804) (xy -0.11684 -0.85344) (xy -0.09144 -0.87376) (xy -0.0635 -0.889)
						(xy -0.03175 -0.89916) (xy 0 -0.9017) (xy 0.03175 -0.89916) (xy 0.0635 -0.889) (xy 0.09144 -0.87376)
						(xy 0.11684 -0.85344) (xy 0.13716 -0.82804) (xy 0.1524 -0.8001) (xy 0.16256 -0.76835) (xy 0.1651 -0.7366)
						(xy 0.1651 -0.11938) (xy 0.17272 -0.11176) (xy 0.19812 -0.0762) (xy 0.2032 -0.06604) (xy 0.20701 -0.05715)
						(xy 0.21209 -0.04699) (xy 0.2159 -0.03683) (xy 0.21844 -0.02667) (xy 0.22225 -0.01524) (xy 0.22352 -0.00508)
						(xy 0.22606 0.00508) (xy 0.22733 0.01651) (xy 0.22733 0.02667) (xy 0.2286 0.0381) (xy 0.22733 0.04953)
						(xy 0.22733 0.05969) (xy 0.22606 0.07112) (xy 0.22352 0.08128) (xy 0.22225 0.09144) (xy 0.21844 0.10287)
						(xy 0.2159 0.11303) (xy 0.21209 0.12319) (xy 0.20701 0.13335) (xy 0.2032 0.14224) (xy 0.19812 0.1524)
						(xy 0.17272 0.18796) (xy 0.1651 0.19558) (xy 0.1651 0.7366) (xy 0.16256 0.76835) (xy 0.1524 0.8001)
						(xy 0.13716 0.82804) (xy 0.11684 0.85344) (xy 0.09144 0.87376) (xy 0.0635 0.889) (xy 0.03175 0.89916)
					)
					(width 0)
					(fill yes)
				)
			)
		)
		(pad "117" smd custom
			(at 5.5499 4.106672)
			(size 0.1143 0.1143)
			(layers "F.Cu" "F.Mask" "F.Paste")
			(net "M_B_MA10")
			(options
				(clearance outline)
				(anchor circle)
			)
			(primitives
				(gr_poly
					(pts
						(xy 0 0.9017) (xy -0.03175 0.89916) (xy -0.0635 0.889) (xy -0.09144 0.87376) (xy -0.11684 0.85344)
						(xy -0.13716 0.82804) (xy -0.1524 0.8001) (xy -0.16256 0.76835) (xy -0.1651 0.7366) (xy -0.1651 -0.13462)
						(xy -0.17272 -0.14224) (xy -0.19812 -0.1778) (xy -0.2032 -0.18796) (xy -0.20701 -0.19685) (xy -0.21209 -0.20701)
						(xy -0.2159 -0.21717) (xy -0.21844 -0.22733) (xy -0.22225 -0.23876) (xy -0.22352 -0.24892) (xy -0.22606 -0.25908)
						(xy -0.22733 -0.27051) (xy -0.22733 -0.28067) (xy -0.2286 -0.2921) (xy -0.22733 -0.30353) (xy -0.22733 -0.31369)
						(xy -0.22606 -0.32512) (xy -0.22352 -0.33528) (xy -0.22225 -0.34544) (xy -0.21844 -0.35687) (xy -0.2159 -0.36703)
						(xy -0.21209 -0.37719) (xy -0.20701 -0.38735) (xy -0.2032 -0.39624) (xy -0.19812 -0.4064) (xy -0.17272 -0.44196)
						(xy -0.1651 -0.44958) (xy -0.1651 -0.7366) (xy -0.16256 -0.76835) (xy -0.1524 -0.8001) (xy -0.13716 -0.82804)
						(xy -0.11684 -0.85344) (xy -0.09144 -0.87376) (xy -0.0635 -0.889) (xy -0.03175 -0.89916) (xy 0 -0.9017)
						(xy 0.03175 -0.89916) (xy 0.0635 -0.889) (xy 0.09144 -0.87376) (xy 0.11684 -0.85344) (xy 0.13716 -0.82804)
						(xy 0.1524 -0.8001) (xy 0.16256 -0.76835) (xy 0.1651 -0.7366) (xy 0.1651 -0.44958) (xy 0.17272 -0.44196)
						(xy 0.19812 -0.4064) (xy 0.2032 -0.39624) (xy 0.20701 -0.38735) (xy 0.21209 -0.37719) (xy 0.2159 -0.36703)
						(xy 0.21844 -0.35687) (xy 0.22225 -0.34544) (xy 0.22352 -0.33528) (xy 0.22606 -0.32512) (xy 0.22733 -0.31369)
						(xy 0.22733 -0.30353) (xy 0.2286 -0.2921) (xy 0.22733 -0.28067) (xy 0.22733 -0.27051) (xy 0.22606 -0.25908)
						(xy 0.22352 -0.24892) (xy 0.22225 -0.23876) (xy 0.21844 -0.22733) (xy 0.2159 -0.21717) (xy 0.21209 -0.20701)
						(xy 0.20701 -0.19685) (xy 0.2032 -0.18796) (xy 0.19812 -0.1778) (xy 0.17272 -0.14224) (xy 0.1651 -0.13462)
						(xy 0.1651 0.7366) (xy 0.16256 0.76835) (xy 0.1524 0.8001) (xy 0.13716 0.82804) (xy 0.11684 0.85344)
						(xy 0.09144 0.87376) (xy 0.0635 0.889) (xy 0.03175 0.89916)
					)
					(width 0)
					(fill yes)
				)
			)
		)
		(pad "118" smd custom
			(at 5.849874 -4.106672)
			(size 0.1143 0.1143)
			(layers "F.Cu" "F.Mask" "F.Paste")
			(net "Net_4")
			(options
				(clearance outline)
				(anchor circle)
			)
			(primitives
				(gr_poly
					(pts
						(xy 0 0.9017) (xy -0.03175 0.89916) (xy -0.0635 0.889) (xy -0.09144 0.87376) (xy -0.11684 0.85344)
						(xy -0.13716 0.82804) (xy -0.1524 0.8001) (xy -0.16256 0.76835) (xy -0.1651 0.7366) (xy -0.1651 0.44958)
						(xy -0.17272 0.44196) (xy -0.19812 0.4064) (xy -0.2032 0.39624) (xy -0.20701 0.38735) (xy -0.21209 0.37719)
						(xy -0.2159 0.36703) (xy -0.21844 0.35687) (xy -0.22225 0.34544) (xy -0.22352 0.33528) (xy -0.22606 0.32512)
						(xy -0.22733 0.31369) (xy -0.22733 0.30353) (xy -0.2286 0.2921) (xy -0.22733 0.28067) (xy -0.22733 0.27051)
						(xy -0.22606 0.25908) (xy -0.22352 0.24892) (xy -0.22225 0.23876) (xy -0.21844 0.22733) (xy -0.2159 0.21717)
						(xy -0.21209 0.20701) (xy -0.20701 0.19685) (xy -0.2032 0.18796) (xy -0.19812 0.1778) (xy -0.17272 0.14224)
						(xy -0.1651 0.13462) (xy -0.1651 -0.7366) (xy -0.16256 -0.76835) (xy -0.1524 -0.8001) (xy -0.13716 -0.82804)
						(xy -0.11684 -0.85344) (xy -0.09144 -0.87376) (xy -0.0635 -0.889) (xy -0.03175 -0.89916) (xy 0 -0.9017)
						(xy 0.03175 -0.89916) (xy 0.0635 -0.889) (xy 0.09144 -0.87376) (xy 0.11684 -0.85344) (xy 0.13716 -0.82804)
						(xy 0.1524 -0.8001) (xy 0.16256 -0.76835) (xy 0.1651 -0.7366) (xy 0.1651 0.13462) (xy 0.17272 0.14224)
						(xy 0.19812 0.1778) (xy 0.2032 0.18796) (xy 0.20701 0.19685) (xy 0.21209 0.20701) (xy 0.2159 0.21717)
						(xy 0.21844 0.22733) (xy 0.22225 0.23876) (xy 0.22352 0.24892) (xy 0.22606 0.25908) (xy 0.22733 0.27051)
						(xy 0.22733 0.28067) (xy 0.2286 0.2921) (xy 0.22733 0.30353) (xy 0.22733 0.31369) (xy 0.22606 0.32512)
						(xy 0.22352 0.33528) (xy 0.22225 0.34544) (xy 0.21844 0.35687) (xy 0.2159 0.36703) (xy 0.21209 0.37719)
						(xy 0.20701 0.38735) (xy 0.2032 0.39624) (xy 0.19812 0.4064) (xy 0.17272 0.44196) (xy 0.1651 0.44958)
						(xy 0.1651 0.7366) (xy 0.16256 0.76835) (xy 0.1524 0.8001) (xy 0.13716 0.82804) (xy 0.11684 0.85344)
						(xy 0.09144 0.87376) (xy 0.0635 0.889) (xy 0.03175 0.89916)
					)
					(width 0)
					(fill yes)
				)
			)
		)
		(pad "119" smd custom
			(at 6.150102 4.106672)
			(size 0.1143 0.1143)
			(layers "F.Cu" "F.Mask" "F.Paste")
			(net "M_B_BS0")
			(options
				(clearance outline)
				(anchor circle)
			)
			(primitives
				(gr_poly
					(pts
						(xy 0 0.9017) (xy -0.03175 0.89916) (xy -0.0635 0.889) (xy -0.09144 0.87376) (xy -0.11684 0.85344)
						(xy -0.13716 0.82804) (xy -0.1524 0.8001) (xy -0.16256 0.76835) (xy -0.1651 0.7366) (xy -0.1651 0.11938)
						(xy -0.17272 0.11176) (xy -0.19812 0.0762) (xy -0.2032 0.06604) (xy -0.20701 0.05715) (xy -0.21209 0.04699)
						(xy -0.2159 0.03683) (xy -0.21844 0.02667) (xy -0.22225 0.01524) (xy -0.22352 0.00508) (xy -0.22606 -0.00508)
						(xy -0.22733 -0.01651) (xy -0.22733 -0.02667) (xy -0.2286 -0.0381) (xy -0.22733 -0.04953) (xy -0.22733 -0.05969)
						(xy -0.22606 -0.07112) (xy -0.22352 -0.08128) (xy -0.22225 -0.09144) (xy -0.21844 -0.10287) (xy -0.2159 -0.11303)
						(xy -0.21209 -0.12319) (xy -0.20701 -0.13335) (xy -0.2032 -0.14224) (xy -0.19812 -0.1524) (xy -0.17272 -0.18796)
						(xy -0.1651 -0.19558) (xy -0.1651 -0.7366) (xy -0.16256 -0.76835) (xy -0.1524 -0.8001) (xy -0.13716 -0.82804)
						(xy -0.11684 -0.85344) (xy -0.09144 -0.87376) (xy -0.0635 -0.889) (xy -0.03175 -0.89916) (xy 0 -0.9017)
						(xy 0.03175 -0.89916) (xy 0.0635 -0.889) (xy 0.09144 -0.87376) (xy 0.11684 -0.85344) (xy 0.13716 -0.82804)
						(xy 0.1524 -0.8001) (xy 0.16256 -0.76835) (xy 0.1651 -0.7366) (xy 0.1651 -0.19685) (xy 0.17272 -0.18923)
						(xy 0.17907 -0.18034) (xy 0.18669 -0.17145) (xy 0.19177 -0.16256) (xy 0.19812 -0.15367) (xy 0.20828 -0.13335)
						(xy 0.21971 -0.10287) (xy 0.22225 -0.09271) (xy 0.22479 -0.08128) (xy 0.22606 -0.07112) (xy 0.2286 -0.05969)
						(xy 0.2286 -0.01651) (xy 0.22606 -0.00508) (xy 0.22479 0.00508) (xy 0.22225 0.01651) (xy 0.21971 0.02667)
						(xy 0.20828 0.05715) (xy 0.19812 0.07747) (xy 0.19177 0.08636) (xy 0.18669 0.09525) (xy 0.17907 0.10414)
						(xy 0.17272 0.11303) (xy 0.1651 0.12065) (xy 0.1651 0.7366) (xy 0.16256 0.76835) (xy 0.1524 0.8001)
						(xy 0.13716 0.82804) (xy 0.11684 0.85344) (xy 0.09144 0.87376) (xy 0.0635 0.889) (xy 0.03175 0.89916)
					)
					(width 0)
					(fill yes)
				)
			)
		)
		(pad "120" smd custom
			(at 6.450076 -4.106672)
			(size 0.1143 0.1143)
			(layers "F.Cu" "F.Mask" "F.Paste")
			(net "Net_3")
			(options
				(clearance outline)
				(anchor circle)
			)
			(primitives
				(gr_poly
					(pts
						(xy 0 0.9017) (xy -0.03175 0.89916) (xy -0.0635 0.889) (xy -0.09144 0.87376) (xy -0.11684 0.85344)
						(xy -0.13716 0.82804) (xy -0.1524 0.8001) (xy -0.16256 0.76835) (xy -0.1651 0.7366) (xy -0.1651 0.19685)
						(xy -0.17272 0.18923) (xy -0.17907 0.18034) (xy -0.18669 0.17145) (xy -0.19177 0.16256) (xy -0.19812 0.15367)
						(xy -0.20828 0.13335) (xy -0.21971 0.10287) (xy -0.22225 0.09271) (xy -0.22479 0.08128) (xy -0.22606 0.07112)
						(xy -0.2286 0.05969) (xy -0.2286 0.01651) (xy -0.22606 0.00508) (xy -0.22479 -0.00508) (xy -0.22225 -0.01651)
						(xy -0.21971 -0.02667) (xy -0.20828 -0.05715) (xy -0.19812 -0.07747) (xy -0.19177 -0.08636) (xy -0.18669 -0.09525)
						(xy -0.17907 -0.10414) (xy -0.17272 -0.11303) (xy -0.1651 -0.12065) (xy -0.1651 -0.7366) (xy -0.16256 -0.76835)
						(xy -0.1524 -0.8001) (xy -0.13716 -0.82804) (xy -0.11684 -0.85344) (xy -0.09144 -0.87376) (xy -0.0635 -0.889)
						(xy -0.03175 -0.89916) (xy 0 -0.9017) (xy 0.03175 -0.89916) (xy 0.0635 -0.889) (xy 0.09144 -0.87376)
						(xy 0.11684 -0.85344) (xy 0.13716 -0.82804) (xy 0.1524 -0.8001) (xy 0.16256 -0.76835) (xy 0.1651 -0.7366)
						(xy 0.1651 -0.11938) (xy 0.17272 -0.11176) (xy 0.19812 -0.0762) (xy 0.2032 -0.06604) (xy 0.20701 -0.05715)
						(xy 0.21209 -0.04699) (xy 0.2159 -0.03683) (xy 0.21844 -0.02667) (xy 0.22225 -0.01524) (xy 0.22352 -0.00508)
						(xy 0.22606 0.00508) (xy 0.22733 0.01651) (xy 0.22733 0.02667) (xy 0.2286 0.0381) (xy 0.22733 0.04953)
						(xy 0.22733 0.05969) (xy 0.22606 0.07112) (xy 0.22352 0.08128) (xy 0.22225 0.09144) (xy 0.21844 0.10287)
						(xy 0.2159 0.11303) (xy 0.21209 0.12319) (xy 0.20701 0.13335) (xy 0.2032 0.14224) (xy 0.19812 0.1524)
						(xy 0.17272 0.18796) (xy 0.1651 0.19558) (xy 0.1651 0.7366) (xy 0.16256 0.76835) (xy 0.1524 0.8001)
						(xy 0.13716 0.82804) (xy 0.11684 0.85344) (xy 0.09144 0.87376) (xy 0.0635 0.889) (xy 0.03175 0.89916)
					)
					(width 0)
					(fill yes)
				)
			)
		)
		(pad "121" smd custom
			(at 6.75005 4.106672)
			(size 0.1143 0.1143)
			(layers "F.Cu" "F.Mask" "F.Paste")
			(net "M_B_WE#")
			(options
				(clearance outline)
				(anchor circle)
			)
			(primitives
				(gr_poly
					(pts
						(xy 0 0.9017) (xy -0.03175 0.89916) (xy -0.0635 0.889) (xy -0.09144 0.87376) (xy -0.11684 0.85344)
						(xy -0.13716 0.82804) (xy -0.1524 0.8001) (xy -0.16256 0.76835) (xy -0.1651 0.7366) (xy -0.1651 -0.13462)
						(xy -0.17272 -0.14224) (xy -0.19812 -0.1778) (xy -0.2032 -0.18796) (xy -0.20701 -0.19685) (xy -0.21209 -0.20701)
						(xy -0.2159 -0.21717) (xy -0.21844 -0.22733) (xy -0.22225 -0.23876) (xy -0.22352 -0.24892) (xy -0.22606 -0.25908)
						(xy -0.22733 -0.27051) (xy -0.22733 -0.28067) (xy -0.2286 -0.2921) (xy -0.22733 -0.30353) (xy -0.22733 -0.31369)
						(xy -0.22606 -0.32512) (xy -0.22352 -0.33528) (xy -0.22225 -0.34544) (xy -0.21844 -0.35687) (xy -0.2159 -0.36703)
						(xy -0.21209 -0.37719) (xy -0.20701 -0.38735) (xy -0.2032 -0.39624) (xy -0.19812 -0.4064) (xy -0.17272 -0.44196)
						(xy -0.1651 -0.44958) (xy -0.1651 -0.7366) (xy -0.16256 -0.76835) (xy -0.1524 -0.8001) (xy -0.13716 -0.82804)
						(xy -0.11684 -0.85344) (xy -0.09144 -0.87376) (xy -0.0635 -0.889) (xy -0.03175 -0.89916) (xy 0 -0.9017)
						(xy 0.03175 -0.89916) (xy 0.0635 -0.889) (xy 0.09144 -0.87376) (xy 0.11684 -0.85344) (xy 0.13716 -0.82804)
						(xy 0.1524 -0.8001) (xy 0.16256 -0.76835) (xy 0.1651 -0.7366) (xy 0.1651 -0.44958) (xy 0.17272 -0.44196)
						(xy 0.19812 -0.4064) (xy 0.2032 -0.39624) (xy 0.20701 -0.38735) (xy 0.21209 -0.37719) (xy 0.2159 -0.36703)
						(xy 0.21844 -0.35687) (xy 0.22225 -0.34544) (xy 0.22352 -0.33528) (xy 0.22606 -0.32512) (xy 0.22733 -0.31369)
						(xy 0.22733 -0.30353) (xy 0.2286 -0.2921) (xy 0.22733 -0.28067) (xy 0.22733 -0.27051) (xy 0.22606 -0.25908)
						(xy 0.22352 -0.24892) (xy 0.22225 -0.23876) (xy 0.21844 -0.22733) (xy 0.2159 -0.21717) (xy 0.21209 -0.20701)
						(xy 0.20701 -0.19685) (xy 0.2032 -0.18796) (xy 0.19812 -0.1778) (xy 0.17272 -0.14224) (xy 0.1651 -0.13462)
						(xy 0.1651 0.7366) (xy 0.16256 0.76835) (xy 0.1524 0.8001) (xy 0.13716 0.82804) (xy 0.11684 0.85344)
						(xy 0.09144 0.87376) (xy 0.0635 0.889) (xy 0.03175 0.89916)
					)
					(width 0)
					(fill yes)
				)
			)
		)
		(pad "122" smd custom
			(at 7.050024 -4.106672)
			(size 0.1143 0.1143)
			(layers "F.Cu" "F.Mask" "F.Paste")
			(net "M_B_RAS#")
			(options
				(clearance outline)
				(anchor circle)
			)
			(primitives
				(gr_poly
					(pts
						(xy 0 0.9017) (xy -0.03175 0.89916) (xy -0.0635 0.889) (xy -0.09144 0.87376) (xy -0.11684 0.85344)
						(xy -0.13716 0.82804) (xy -0.1524 0.8001) (xy -0.16256 0.76835) (xy -0.1651 0.7366) (xy -0.1651 0.44958)
						(xy -0.17272 0.44196) (xy -0.19812 0.4064) (xy -0.2032 0.39624) (xy -0.20701 0.38735) (xy -0.21209 0.37719)
						(xy -0.2159 0.36703) (xy -0.21844 0.35687) (xy -0.22225 0.34544) (xy -0.22352 0.33528) (xy -0.22606 0.32512)
						(xy -0.22733 0.31369) (xy -0.22733 0.30353) (xy -0.2286 0.2921) (xy -0.22733 0.28067) (xy -0.22733 0.27051)
						(xy -0.22606 0.25908) (xy -0.22352 0.24892) (xy -0.22225 0.23876) (xy -0.21844 0.22733) (xy -0.2159 0.21717)
						(xy -0.21209 0.20701) (xy -0.20701 0.19685) (xy -0.2032 0.18796) (xy -0.19812 0.1778) (xy -0.17272 0.14224)
						(xy -0.1651 0.13462) (xy -0.1651 -0.7366) (xy -0.16256 -0.76835) (xy -0.1524 -0.8001) (xy -0.13716 -0.82804)
						(xy -0.11684 -0.85344) (xy -0.09144 -0.87376) (xy -0.0635 -0.889) (xy -0.03175 -0.89916) (xy 0 -0.9017)
						(xy 0.03175 -0.89916) (xy 0.0635 -0.889) (xy 0.09144 -0.87376) (xy 0.11684 -0.85344) (xy 0.13716 -0.82804)
						(xy 0.1524 -0.8001) (xy 0.16256 -0.76835) (xy 0.1651 -0.7366) (xy 0.1651 0.13462) (xy 0.17272 0.14224)
						(xy 0.19812 0.1778) (xy 0.2032 0.18796) (xy 0.20701 0.19685) (xy 0.21209 0.20701) (xy 0.2159 0.21717)
						(xy 0.21844 0.22733) (xy 0.22225 0.23876) (xy 0.22352 0.24892) (xy 0.22606 0.25908) (xy 0.22733 0.27051)
						(xy 0.22733 0.28067) (xy 0.2286 0.2921) (xy 0.22733 0.30353) (xy 0.22733 0.31369) (xy 0.22606 0.32512)
						(xy 0.22352 0.33528) (xy 0.22225 0.34544) (xy 0.21844 0.35687) (xy 0.2159 0.36703) (xy 0.21209 0.37719)
						(xy 0.20701 0.38735) (xy 0.2032 0.39624) (xy 0.19812 0.4064) (xy 0.17272 0.44196) (xy 0.1651 0.44958)
						(xy 0.1651 0.7366) (xy 0.16256 0.76835) (xy 0.1524 0.8001) (xy 0.13716 0.82804) (xy 0.11684 0.85344)
						(xy 0.09144 0.87376) (xy 0.0635 0.889) (xy 0.03175 0.89916)
					)
					(width 0)
					(fill yes)
				)
			)
		)
		(pad "123" smd custom
			(at 7.349998 4.106672)
			(size 0.1143 0.1143)
			(layers "F.Cu" "F.Mask" "F.Paste")
			(net "PV_VDDR")
			(options
				(clearance outline)
				(anchor circle)
			)
			(primitives
				(gr_poly
					(pts
						(xy 0 0.9017) (xy -0.03175 0.89916) (xy -0.0635 0.889) (xy -0.09144 0.87376) (xy -0.11684 0.85344)
						(xy -0.13716 0.82804) (xy -0.1524 0.8001) (xy -0.16256 0.76835) (xy -0.1651 0.7366) (xy -0.1651 0.11938)
						(xy -0.17272 0.11176) (xy -0.19812 0.0762) (xy -0.2032 0.06604) (xy -0.20701 0.05715) (xy -0.21209 0.04699)
						(xy -0.2159 0.03683) (xy -0.21844 0.02667) (xy -0.22225 0.01524) (xy -0.22352 0.00508) (xy -0.22606 -0.00508)
						(xy -0.22733 -0.01651) (xy -0.22733 -0.02667) (xy -0.2286 -0.0381) (xy -0.22733 -0.04953) (xy -0.22733 -0.05969)
						(xy -0.22606 -0.07112) (xy -0.22352 -0.08128) (xy -0.22225 -0.09144) (xy -0.21844 -0.10287) (xy -0.2159 -0.11303)
						(xy -0.21209 -0.12319) (xy -0.20701 -0.13335) (xy -0.2032 -0.14224) (xy -0.19812 -0.1524) (xy -0.17272 -0.18796)
						(xy -0.1651 -0.19558) (xy -0.1651 -0.7366) (xy -0.16256 -0.76835) (xy -0.1524 -0.8001) (xy -0.13716 -0.82804)
						(xy -0.11684 -0.85344) (xy -0.09144 -0.87376) (xy -0.0635 -0.889) (xy -0.03175 -0.89916) (xy 0 -0.9017)
						(xy 0.03175 -0.89916) (xy 0.0635 -0.889) (xy 0.09144 -0.87376) (xy 0.11684 -0.85344) (xy 0.13716 -0.82804)
						(xy 0.1524 -0.8001) (xy 0.16256 -0.76835) (xy 0.1651 -0.7366) (xy 0.1651 -0.19685) (xy 0.17272 -0.18923)
						(xy 0.17907 -0.18034) (xy 0.18669 -0.17145) (xy 0.19177 -0.16256) (xy 0.19812 -0.15367) (xy 0.20828 -0.13335)
						(xy 0.21971 -0.10287) (xy 0.22225 -0.09271) (xy 0.22479 -0.08128) (xy 0.22606 -0.07112) (xy 0.2286 -0.05969)
						(xy 0.2286 -0.01651) (xy 0.22606 -0.00508) (xy 0.22479 0.00508) (xy 0.22225 0.01651) (xy 0.21971 0.02667)
						(xy 0.20828 0.05715) (xy 0.19812 0.07747) (xy 0.19177 0.08636) (xy 0.18669 0.09525) (xy 0.17907 0.10414)
						(xy 0.17272 0.11303) (xy 0.1651 0.12065) (xy 0.1651 0.7366) (xy 0.16256 0.76835) (xy 0.1524 0.8001)
						(xy 0.13716 0.82804) (xy 0.11684 0.85344) (xy 0.09144 0.87376) (xy 0.0635 0.889) (xy 0.03175 0.89916)
					)
					(width 0)
					(fill yes)
				)
			)
		)
		(pad "124" smd custom
			(at 7.649972 -4.106672)
			(size 0.1143 0.1143)
			(layers "F.Cu" "F.Mask" "F.Paste")
			(net "PV_VDDR")
			(options
				(clearance outline)
				(anchor circle)
			)
			(primitives
				(gr_poly
					(pts
						(xy 0 0.9017) (xy -0.03175 0.89916) (xy -0.0635 0.889) (xy -0.09144 0.87376) (xy -0.11684 0.85344)
						(xy -0.13716 0.82804) (xy -0.1524 0.8001) (xy -0.16256 0.76835) (xy -0.1651 0.7366) (xy -0.1651 0.19685)
						(xy -0.17272 0.18923) (xy -0.17907 0.18034) (xy -0.18669 0.17145) (xy -0.19177 0.16256) (xy -0.19812 0.15367)
						(xy -0.20828 0.13335) (xy -0.21971 0.10287) (xy -0.22225 0.09271) (xy -0.22479 0.08128) (xy -0.22606 0.07112)
						(xy -0.2286 0.05969) (xy -0.2286 0.01651) (xy -0.22606 0.00508) (xy -0.22479 -0.00508) (xy -0.22225 -0.01651)
						(xy -0.21971 -0.02667) (xy -0.20828 -0.05715) (xy -0.19812 -0.07747) (xy -0.19177 -0.08636) (xy -0.18669 -0.09525)
						(xy -0.17907 -0.10414) (xy -0.17272 -0.11303) (xy -0.1651 -0.12065) (xy -0.1651 -0.7366) (xy -0.16256 -0.76835)
						(xy -0.1524 -0.8001) (xy -0.13716 -0.82804) (xy -0.11684 -0.85344) (xy -0.09144 -0.87376) (xy -0.0635 -0.889)
						(xy -0.03175 -0.89916) (xy 0 -0.9017) (xy 0.03175 -0.89916) (xy 0.0635 -0.889) (xy 0.09144 -0.87376)
						(xy 0.11684 -0.85344) (xy 0.13716 -0.82804) (xy 0.1524 -0.8001) (xy 0.16256 -0.76835) (xy 0.1651 -0.7366)
						(xy 0.1651 -0.11938) (xy 0.17272 -0.11176) (xy 0.19812 -0.0762) (xy 0.2032 -0.06604) (xy 0.20701 -0.05715)
						(xy 0.21209 -0.04699) (xy 0.2159 -0.03683) (xy 0.21844 -0.02667) (xy 0.22225 -0.01524) (xy 0.22352 -0.00508)
						(xy 0.22606 0.00508) (xy 0.22733 0.01651) (xy 0.22733 0.02667) (xy 0.2286 0.0381) (xy 0.22733 0.04953)
						(xy 0.22733 0.05969) (xy 0.22606 0.07112) (xy 0.22352 0.08128) (xy 0.22225 0.09144) (xy 0.21844 0.10287)
						(xy 0.2159 0.11303) (xy 0.21209 0.12319) (xy 0.20701 0.13335) (xy 0.2032 0.14224) (xy 0.19812 0.1524)
						(xy 0.17272 0.18796) (xy 0.1651 0.19558) (xy 0.1651 0.7366) (xy 0.16256 0.76835) (xy 0.1524 0.8001)
						(xy 0.13716 0.82804) (xy 0.11684 0.85344) (xy 0.09144 0.87376) (xy 0.0635 0.889) (xy 0.03175 0.89916)
					)
					(width 0)
					(fill yes)
				)
			)
		)
		(pad "125" smd custom
			(at 7.949946 4.106672)
			(size 0.1143 0.1143)
			(layers "F.Cu" "F.Mask" "F.Paste")
			(net "M_B_CAS#")
			(options
				(clearance outline)
				(anchor circle)
			)
			(primitives
				(gr_poly
					(pts
						(xy 0 0.9017) (xy -0.03175 0.89916) (xy -0.0635 0.889) (xy -0.09144 0.87376) (xy -0.11684 0.85344)
						(xy -0.13716 0.82804) (xy -0.1524 0.8001) (xy -0.16256 0.76835) (xy -0.1651 0.7366) (xy -0.1651 -0.13462)
						(xy -0.17272 -0.14224) (xy -0.19812 -0.1778) (xy -0.2032 -0.18796) (xy -0.20701 -0.19685) (xy -0.21209 -0.20701)
						(xy -0.2159 -0.21717) (xy -0.21844 -0.22733) (xy -0.22225 -0.23876) (xy -0.22352 -0.24892) (xy -0.22606 -0.25908)
						(xy -0.22733 -0.27051) (xy -0.22733 -0.28067) (xy -0.2286 -0.2921) (xy -0.22733 -0.30353) (xy -0.22733 -0.31369)
						(xy -0.22606 -0.32512) (xy -0.22352 -0.33528) (xy -0.22225 -0.34544) (xy -0.21844 -0.35687) (xy -0.2159 -0.36703)
						(xy -0.21209 -0.37719) (xy -0.20701 -0.38735) (xy -0.2032 -0.39624) (xy -0.19812 -0.4064) (xy -0.17272 -0.44196)
						(xy -0.1651 -0.44958) (xy -0.1651 -0.7366) (xy -0.16256 -0.76835) (xy -0.1524 -0.8001) (xy -0.13716 -0.82804)
						(xy -0.11684 -0.85344) (xy -0.09144 -0.87376) (xy -0.0635 -0.889) (xy -0.03175 -0.89916) (xy 0 -0.9017)
						(xy 0.03175 -0.89916) (xy 0.0635 -0.889) (xy 0.09144 -0.87376) (xy 0.11684 -0.85344) (xy 0.13716 -0.82804)
						(xy 0.1524 -0.8001) (xy 0.16256 -0.76835) (xy 0.1651 -0.7366) (xy 0.1651 -0.44958) (xy 0.17272 -0.44196)
						(xy 0.19812 -0.4064) (xy 0.2032 -0.39624) (xy 0.20701 -0.38735) (xy 0.21209 -0.37719) (xy 0.2159 -0.36703)
						(xy 0.21844 -0.35687) (xy 0.22225 -0.34544) (xy 0.22352 -0.33528) (xy 0.22606 -0.32512) (xy 0.22733 -0.31369)
						(xy 0.22733 -0.30353) (xy 0.2286 -0.2921) (xy 0.22733 -0.28067) (xy 0.22733 -0.27051) (xy 0.22606 -0.25908)
						(xy 0.22352 -0.24892) (xy 0.22225 -0.23876) (xy 0.21844 -0.22733) (xy 0.2159 -0.21717) (xy 0.21209 -0.20701)
						(xy 0.20701 -0.19685) (xy 0.2032 -0.18796) (xy 0.19812 -0.1778) (xy 0.17272 -0.14224) (xy 0.1651 -0.13462)
						(xy 0.1651 0.7366) (xy 0.16256 0.76835) (xy 0.1524 0.8001) (xy 0.13716 0.82804) (xy 0.11684 0.85344)
						(xy 0.09144 0.87376) (xy 0.0635 0.889) (xy 0.03175 0.89916)
					)
					(width 0)
					(fill yes)
				)
			)
		)
		(pad "126" smd custom
			(at 8.24992 -4.106672)
			(size 0.1143 0.1143)
			(layers "F.Cu" "F.Mask" "F.Paste")
			(net "M_B_ODT2")
			(options
				(clearance outline)
				(anchor circle)
			)
			(primitives
				(gr_poly
					(pts
						(xy 0 0.9017) (xy -0.03175 0.89916) (xy -0.0635 0.889) (xy -0.09144 0.87376) (xy -0.11684 0.85344)
						(xy -0.13716 0.82804) (xy -0.1524 0.8001) (xy -0.16256 0.76835) (xy -0.1651 0.7366) (xy -0.1651 0.44958)
						(xy -0.17272 0.44196) (xy -0.19812 0.4064) (xy -0.2032 0.39624) (xy -0.20701 0.38735) (xy -0.21209 0.37719)
						(xy -0.2159 0.36703) (xy -0.21844 0.35687) (xy -0.22225 0.34544) (xy -0.22352 0.33528) (xy -0.22606 0.32512)
						(xy -0.22733 0.31369) (xy -0.22733 0.30353) (xy -0.2286 0.2921) (xy -0.22733 0.28067) (xy -0.22733 0.27051)
						(xy -0.22606 0.25908) (xy -0.22352 0.24892) (xy -0.22225 0.23876) (xy -0.21844 0.22733) (xy -0.2159 0.21717)
						(xy -0.21209 0.20701) (xy -0.20701 0.19685) (xy -0.2032 0.18796) (xy -0.19812 0.1778) (xy -0.17272 0.14224)
						(xy -0.1651 0.13462) (xy -0.1651 -0.7366) (xy -0.16256 -0.76835) (xy -0.1524 -0.8001) (xy -0.13716 -0.82804)
						(xy -0.11684 -0.85344) (xy -0.09144 -0.87376) (xy -0.0635 -0.889) (xy -0.03175 -0.89916) (xy 0 -0.9017)
						(xy 0.03175 -0.89916) (xy 0.0635 -0.889) (xy 0.09144 -0.87376) (xy 0.11684 -0.85344) (xy 0.13716 -0.82804)
						(xy 0.1524 -0.8001) (xy 0.16256 -0.76835) (xy 0.1651 -0.7366) (xy 0.1651 0.13462) (xy 0.17272 0.14224)
						(xy 0.19812 0.1778) (xy 0.2032 0.18796) (xy 0.20701 0.19685) (xy 0.21209 0.20701) (xy 0.2159 0.21717)
						(xy 0.21844 0.22733) (xy 0.22225 0.23876) (xy 0.22352 0.24892) (xy 0.22606 0.25908) (xy 0.22733 0.27051)
						(xy 0.22733 0.28067) (xy 0.2286 0.2921) (xy 0.22733 0.30353) (xy 0.22733 0.31369) (xy 0.22606 0.32512)
						(xy 0.22352 0.33528) (xy 0.22225 0.34544) (xy 0.21844 0.35687) (xy 0.2159 0.36703) (xy 0.21209 0.37719)
						(xy 0.20701 0.38735) (xy 0.2032 0.39624) (xy 0.19812 0.4064) (xy 0.17272 0.44196) (xy 0.1651 0.44958)
						(xy 0.1651 0.7366) (xy 0.16256 0.76835) (xy 0.1524 0.8001) (xy 0.13716 0.82804) (xy 0.11684 0.85344)
						(xy 0.09144 0.87376) (xy 0.0635 0.889) (xy 0.03175 0.89916)
					)
					(width 0)
					(fill yes)
				)
			)
		)
		(pad "127" smd custom
			(at 8.549894 4.106672)
			(size 0.1143 0.1143)
			(layers "F.Cu" "F.Mask" "F.Paste")
			(net "M_B_CS_N2")
			(options
				(clearance outline)
				(anchor circle)
			)
			(primitives
				(gr_poly
					(pts
						(xy 0 0.9017) (xy -0.03175 0.89916) (xy -0.0635 0.889) (xy -0.09144 0.87376) (xy -0.11684 0.85344)
						(xy -0.13716 0.82804) (xy -0.1524 0.8001) (xy -0.16256 0.76835) (xy -0.1651 0.7366) (xy -0.1651 0.11938)
						(xy -0.17272 0.11176) (xy -0.19812 0.0762) (xy -0.2032 0.06604) (xy -0.20701 0.05715) (xy -0.21209 0.04699)
						(xy -0.2159 0.03683) (xy -0.21844 0.02667) (xy -0.22225 0.01524) (xy -0.22352 0.00508) (xy -0.22606 -0.00508)
						(xy -0.22733 -0.01651) (xy -0.22733 -0.02667) (xy -0.2286 -0.0381) (xy -0.22733 -0.04953) (xy -0.22733 -0.05969)
						(xy -0.22606 -0.07112) (xy -0.22352 -0.08128) (xy -0.22225 -0.09144) (xy -0.21844 -0.10287) (xy -0.2159 -0.11303)
						(xy -0.21209 -0.12319) (xy -0.20701 -0.13335) (xy -0.2032 -0.14224) (xy -0.19812 -0.1524) (xy -0.17272 -0.18796)
						(xy -0.1651 -0.19558) (xy -0.1651 -0.7366) (xy -0.16256 -0.76835) (xy -0.1524 -0.8001) (xy -0.13716 -0.82804)
						(xy -0.11684 -0.85344) (xy -0.09144 -0.87376) (xy -0.0635 -0.889) (xy -0.03175 -0.89916) (xy 0 -0.9017)
						(xy 0.03175 -0.89916) (xy 0.0635 -0.889) (xy 0.09144 -0.87376) (xy 0.11684 -0.85344) (xy 0.13716 -0.82804)
						(xy 0.1524 -0.8001) (xy 0.16256 -0.76835) (xy 0.1651 -0.7366) (xy 0.1651 -0.19685) (xy 0.17272 -0.18923)
						(xy 0.17907 -0.18034) (xy 0.18669 -0.17145) (xy 0.19177 -0.16256) (xy 0.19812 -0.15367) (xy 0.20828 -0.13335)
						(xy 0.21971 -0.10287) (xy 0.22225 -0.09271) (xy 0.22479 -0.08128) (xy 0.22606 -0.07112) (xy 0.2286 -0.05969)
						(xy 0.2286 -0.01651) (xy 0.22606 -0.00508) (xy 0.22479 0.00508) (xy 0.22225 0.01651) (xy 0.21971 0.02667)
						(xy 0.20828 0.05715) (xy 0.19812 0.07747) (xy 0.19177 0.08636) (xy 0.18669 0.09525) (xy 0.17907 0.10414)
						(xy 0.17272 0.11303) (xy 0.1651 0.12065) (xy 0.1651 0.7366) (xy 0.16256 0.76835) (xy 0.1524 0.8001)
						(xy 0.13716 0.82804) (xy 0.11684 0.85344) (xy 0.09144 0.87376) (xy 0.0635 0.889) (xy 0.03175 0.89916)
					)
					(width 0)
					(fill yes)
				)
			)
		)
		(pad "128" smd custom
			(at 8.850122 -4.106672)
			(size 0.1143 0.1143)
			(layers "F.Cu" "F.Mask" "F.Paste")
			(net "M_B_ODT3")
			(options
				(clearance outline)
				(anchor circle)
			)
			(primitives
				(gr_poly
					(pts
						(xy 0 0.9017) (xy -0.03175 0.89916) (xy -0.0635 0.889) (xy -0.09144 0.87376) (xy -0.11684 0.85344)
						(xy -0.13716 0.82804) (xy -0.1524 0.8001) (xy -0.16256 0.76835) (xy -0.1651 0.7366) (xy -0.1651 0.19685)
						(xy -0.17272 0.18923) (xy -0.17907 0.18034) (xy -0.18669 0.17145) (xy -0.19177 0.16256) (xy -0.19812 0.15367)
						(xy -0.20828 0.13335) (xy -0.21971 0.10287) (xy -0.22225 0.09271) (xy -0.22479 0.08128) (xy -0.22606 0.07112)
						(xy -0.2286 0.05969) (xy -0.2286 0.01651) (xy -0.22606 0.00508) (xy -0.22479 -0.00508) (xy -0.22225 -0.01651)
						(xy -0.21971 -0.02667) (xy -0.20828 -0.05715) (xy -0.19812 -0.07747) (xy -0.19177 -0.08636) (xy -0.18669 -0.09525)
						(xy -0.17907 -0.10414) (xy -0.17272 -0.11303) (xy -0.1651 -0.12065) (xy -0.1651 -0.7366) (xy -0.16256 -0.76835)
						(xy -0.1524 -0.8001) (xy -0.13716 -0.82804) (xy -0.11684 -0.85344) (xy -0.09144 -0.87376) (xy -0.0635 -0.889)
						(xy -0.03175 -0.89916) (xy 0 -0.9017) (xy 0.03175 -0.89916) (xy 0.0635 -0.889) (xy 0.09144 -0.87376)
						(xy 0.11684 -0.85344) (xy 0.13716 -0.82804) (xy 0.1524 -0.8001) (xy 0.16256 -0.76835) (xy 0.1651 -0.7366)
						(xy 0.1651 -0.11938) (xy 0.17272 -0.11176) (xy 0.19812 -0.0762) (xy 0.2032 -0.06604) (xy 0.20701 -0.05715)
						(xy 0.21209 -0.04699) (xy 0.2159 -0.03683) (xy 0.21844 -0.02667) (xy 0.22225 -0.01524) (xy 0.22352 -0.00508)
						(xy 0.22606 0.00508) (xy 0.22733 0.01651) (xy 0.22733 0.02667) (xy 0.2286 0.0381) (xy 0.22733 0.04953)
						(xy 0.22733 0.05969) (xy 0.22606 0.07112) (xy 0.22352 0.08128) (xy 0.22225 0.09144) (xy 0.21844 0.10287)
						(xy 0.2159 0.11303) (xy 0.21209 0.12319) (xy 0.20701 0.13335) (xy 0.2032 0.14224) (xy 0.19812 0.1524)
						(xy 0.17272 0.18796) (xy 0.1651 0.19558) (xy 0.1651 0.7366) (xy 0.16256 0.76835) (xy 0.1524 0.8001)
						(xy 0.13716 0.82804) (xy 0.11684 0.85344) (xy 0.09144 0.87376) (xy 0.0635 0.889) (xy 0.03175 0.89916)
					)
					(width 0)
					(fill yes)
				)
			)
		)
		(pad "129" smd custom
			(at 9.150096 4.106672)
			(size 0.1143 0.1143)
			(layers "F.Cu" "F.Mask" "F.Paste")
			(net "M_B_CS_N3")
			(options
				(clearance outline)
				(anchor circle)
			)
			(primitives
				(gr_poly
					(pts
						(xy 0 0.9017) (xy -0.03175 0.89916) (xy -0.0635 0.889) (xy -0.09144 0.87376) (xy -0.11684 0.85344)
						(xy -0.13716 0.82804) (xy -0.1524 0.8001) (xy -0.16256 0.76835) (xy -0.1651 0.7366) (xy -0.1651 -0.13462)
						(xy -0.17272 -0.14224) (xy -0.19812 -0.1778) (xy -0.2032 -0.18796) (xy -0.20701 -0.19685) (xy -0.21209 -0.20701)
						(xy -0.2159 -0.21717) (xy -0.21844 -0.22733) (xy -0.22225 -0.23876) (xy -0.22352 -0.24892) (xy -0.22606 -0.25908)
						(xy -0.22733 -0.27051) (xy -0.22733 -0.28067) (xy -0.2286 -0.2921) (xy -0.22733 -0.30353) (xy -0.22733 -0.31369)
						(xy -0.22606 -0.32512) (xy -0.22352 -0.33528) (xy -0.22225 -0.34544) (xy -0.21844 -0.35687) (xy -0.2159 -0.36703)
						(xy -0.21209 -0.37719) (xy -0.20701 -0.38735) (xy -0.2032 -0.39624) (xy -0.19812 -0.4064) (xy -0.17272 -0.44196)
						(xy -0.1651 -0.44958) (xy -0.1651 -0.7366) (xy -0.16256 -0.76835) (xy -0.1524 -0.8001) (xy -0.13716 -0.82804)
						(xy -0.11684 -0.85344) (xy -0.09144 -0.87376) (xy -0.0635 -0.889) (xy -0.03175 -0.89916) (xy 0 -0.9017)
						(xy 0.03175 -0.89916) (xy 0.0635 -0.889) (xy 0.09144 -0.87376) (xy 0.11684 -0.85344) (xy 0.13716 -0.82804)
						(xy 0.1524 -0.8001) (xy 0.16256 -0.76835) (xy 0.1651 -0.7366) (xy 0.1651 -0.44958) (xy 0.17272 -0.44196)
						(xy 0.19812 -0.4064) (xy 0.2032 -0.39624) (xy 0.20701 -0.38735) (xy 0.21209 -0.37719) (xy 0.2159 -0.36703)
						(xy 0.21844 -0.35687) (xy 0.22225 -0.34544) (xy 0.22352 -0.33528) (xy 0.22606 -0.32512) (xy 0.22733 -0.31369)
						(xy 0.22733 -0.30353) (xy 0.2286 -0.2921) (xy 0.22733 -0.28067) (xy 0.22733 -0.27051) (xy 0.22606 -0.25908)
						(xy 0.22352 -0.24892) (xy 0.22225 -0.23876) (xy 0.21844 -0.22733) (xy 0.2159 -0.21717) (xy 0.21209 -0.20701)
						(xy 0.20701 -0.19685) (xy 0.2032 -0.18796) (xy 0.19812 -0.1778) (xy 0.17272 -0.14224) (xy 0.1651 -0.13462)
						(xy 0.1651 0.7366) (xy 0.16256 0.76835) (xy 0.1524 0.8001) (xy 0.13716 0.82804) (xy 0.11684 0.85344)
						(xy 0.09144 0.87376) (xy 0.0635 0.889) (xy 0.03175 0.89916)
					)
					(width 0)
					(fill yes)
				)
			)
		)
		(pad "130" smd custom
			(at 9.45007 -4.106672)
			(size 0.1143 0.1143)
			(layers "F.Cu" "F.Mask" "F.Paste")
			(net "M_B_MA13")
			(options
				(clearance outline)
				(anchor circle)
			)
			(primitives
				(gr_poly
					(pts
						(xy 0 0.9017) (xy -0.03175 0.89916) (xy -0.0635 0.889) (xy -0.09144 0.87376) (xy -0.11684 0.85344)
						(xy -0.13716 0.82804) (xy -0.1524 0.8001) (xy -0.16256 0.76835) (xy -0.1651 0.7366) (xy -0.1651 0.44958)
						(xy -0.17272 0.44196) (xy -0.19812 0.4064) (xy -0.2032 0.39624) (xy -0.20701 0.38735) (xy -0.21209 0.37719)
						(xy -0.2159 0.36703) (xy -0.21844 0.35687) (xy -0.22225 0.34544) (xy -0.22352 0.33528) (xy -0.22606 0.32512)
						(xy -0.22733 0.31369) (xy -0.22733 0.30353) (xy -0.2286 0.2921) (xy -0.22733 0.28067) (xy -0.22733 0.27051)
						(xy -0.22606 0.25908) (xy -0.22352 0.24892) (xy -0.22225 0.23876) (xy -0.21844 0.22733) (xy -0.2159 0.21717)
						(xy -0.21209 0.20701) (xy -0.20701 0.19685) (xy -0.2032 0.18796) (xy -0.19812 0.1778) (xy -0.17272 0.14224)
						(xy -0.1651 0.13462) (xy -0.1651 -0.7366) (xy -0.16256 -0.76835) (xy -0.1524 -0.8001) (xy -0.13716 -0.82804)
						(xy -0.11684 -0.85344) (xy -0.09144 -0.87376) (xy -0.0635 -0.889) (xy -0.03175 -0.89916) (xy 0 -0.9017)
						(xy 0.03175 -0.89916) (xy 0.0635 -0.889) (xy 0.09144 -0.87376) (xy 0.11684 -0.85344) (xy 0.13716 -0.82804)
						(xy 0.1524 -0.8001) (xy 0.16256 -0.76835) (xy 0.1651 -0.7366) (xy 0.1651 0.13462) (xy 0.17272 0.14224)
						(xy 0.19812 0.1778) (xy 0.2032 0.18796) (xy 0.20701 0.19685) (xy 0.21209 0.20701) (xy 0.2159 0.21717)
						(xy 0.21844 0.22733) (xy 0.22225 0.23876) (xy 0.22352 0.24892) (xy 0.22606 0.25908) (xy 0.22733 0.27051)
						(xy 0.22733 0.28067) (xy 0.2286 0.2921) (xy 0.22733 0.30353) (xy 0.22733 0.31369) (xy 0.22606 0.32512)
						(xy 0.22352 0.33528) (xy 0.22225 0.34544) (xy 0.21844 0.35687) (xy 0.2159 0.36703) (xy 0.21209 0.37719)
						(xy 0.20701 0.38735) (xy 0.2032 0.39624) (xy 0.19812 0.4064) (xy 0.17272 0.44196) (xy 0.1651 0.44958)
						(xy 0.1651 0.7366) (xy 0.16256 0.76835) (xy 0.1524 0.8001) (xy 0.13716 0.82804) (xy 0.11684 0.85344)
						(xy 0.09144 0.87376) (xy 0.0635 0.889) (xy 0.03175 0.89916)
					)
					(width 0)
					(fill yes)
				)
			)
		)
		(pad "131" smd custom
			(at 9.750044 4.106672)
			(size 0.1143 0.1143)
			(layers "F.Cu" "F.Mask" "F.Paste")
			(net "PV_VDDR")
			(options
				(clearance outline)
				(anchor circle)
			)
			(primitives
				(gr_poly
					(pts
						(xy 0 0.9017) (xy -0.03175 0.89916) (xy -0.0635 0.889) (xy -0.09144 0.87376) (xy -0.11684 0.85344)
						(xy -0.13716 0.82804) (xy -0.1524 0.8001) (xy -0.16256 0.76835) (xy -0.1651 0.7366) (xy -0.1651 0.11938)
						(xy -0.17272 0.11176) (xy -0.19812 0.0762) (xy -0.2032 0.06604) (xy -0.20701 0.05715) (xy -0.21209 0.04699)
						(xy -0.2159 0.03683) (xy -0.21844 0.02667) (xy -0.22225 0.01524) (xy -0.22352 0.00508) (xy -0.22606 -0.00508)
						(xy -0.22733 -0.01651) (xy -0.22733 -0.02667) (xy -0.2286 -0.0381) (xy -0.22733 -0.04953) (xy -0.22733 -0.05969)
						(xy -0.22606 -0.07112) (xy -0.22352 -0.08128) (xy -0.22225 -0.09144) (xy -0.21844 -0.10287) (xy -0.2159 -0.11303)
						(xy -0.21209 -0.12319) (xy -0.20701 -0.13335) (xy -0.2032 -0.14224) (xy -0.19812 -0.1524) (xy -0.17272 -0.18796)
						(xy -0.1651 -0.19558) (xy -0.1651 -0.7366) (xy -0.16256 -0.76835) (xy -0.1524 -0.8001) (xy -0.13716 -0.82804)
						(xy -0.11684 -0.85344) (xy -0.09144 -0.87376) (xy -0.0635 -0.889) (xy -0.03175 -0.89916) (xy 0 -0.9017)
						(xy 0.03175 -0.89916) (xy 0.0635 -0.889) (xy 0.09144 -0.87376) (xy 0.11684 -0.85344) (xy 0.13716 -0.82804)
						(xy 0.1524 -0.8001) (xy 0.16256 -0.76835) (xy 0.1651 -0.7366) (xy 0.1651 -0.19685) (xy 0.17272 -0.18923)
						(xy 0.17907 -0.18034) (xy 0.18669 -0.17145) (xy 0.19177 -0.16256) (xy 0.19812 -0.15367) (xy 0.20828 -0.13335)
						(xy 0.21971 -0.10287) (xy 0.22225 -0.09271) (xy 0.22479 -0.08128) (xy 0.22606 -0.07112) (xy 0.2286 -0.05969)
						(xy 0.2286 -0.01651) (xy 0.22606 -0.00508) (xy 0.22479 0.00508) (xy 0.22225 0.01651) (xy 0.21971 0.02667)
						(xy 0.20828 0.05715) (xy 0.19812 0.07747) (xy 0.19177 0.08636) (xy 0.18669 0.09525) (xy 0.17907 0.10414)
						(xy 0.17272 0.11303) (xy 0.1651 0.12065) (xy 0.1651 0.7366) (xy 0.16256 0.76835) (xy 0.1524 0.8001)
						(xy 0.13716 0.82804) (xy 0.11684 0.85344) (xy 0.09144 0.87376) (xy 0.0635 0.889) (xy 0.03175 0.89916)
					)
					(width 0)
					(fill yes)
				)
			)
		)
		(pad "132" smd custom
			(at 10.050018 -4.106672)
			(size 0.1143 0.1143)
			(layers "F.Cu" "F.Mask" "F.Paste")
			(net "PV_VDDR")
			(options
				(clearance outline)
				(anchor circle)
			)
			(primitives
				(gr_poly
					(pts
						(xy 0 0.9017) (xy -0.03175 0.89916) (xy -0.0635 0.889) (xy -0.09144 0.87376) (xy -0.11684 0.85344)
						(xy -0.13716 0.82804) (xy -0.1524 0.8001) (xy -0.16256 0.76835) (xy -0.1651 0.7366) (xy -0.1651 0.19685)
						(xy -0.17272 0.18923) (xy -0.17907 0.18034) (xy -0.18669 0.17145) (xy -0.19177 0.16256) (xy -0.19812 0.15367)
						(xy -0.20828 0.13335) (xy -0.21971 0.10287) (xy -0.22225 0.09271) (xy -0.22479 0.08128) (xy -0.22606 0.07112)
						(xy -0.2286 0.05969) (xy -0.2286 0.01651) (xy -0.22606 0.00508) (xy -0.22479 -0.00508) (xy -0.22225 -0.01651)
						(xy -0.21971 -0.02667) (xy -0.20828 -0.05715) (xy -0.19812 -0.07747) (xy -0.19177 -0.08636) (xy -0.18669 -0.09525)
						(xy -0.17907 -0.10414) (xy -0.17272 -0.11303) (xy -0.1651 -0.12065) (xy -0.1651 -0.7366) (xy -0.16256 -0.76835)
						(xy -0.1524 -0.8001) (xy -0.13716 -0.82804) (xy -0.11684 -0.85344) (xy -0.09144 -0.87376) (xy -0.0635 -0.889)
						(xy -0.03175 -0.89916) (xy 0 -0.9017) (xy 0.03175 -0.89916) (xy 0.0635 -0.889) (xy 0.09144 -0.87376)
						(xy 0.11684 -0.85344) (xy 0.13716 -0.82804) (xy 0.1524 -0.8001) (xy 0.16256 -0.76835) (xy 0.1651 -0.7366)
						(xy 0.1651 -0.11938) (xy 0.17272 -0.11176) (xy 0.19812 -0.0762) (xy 0.2032 -0.06604) (xy 0.20701 -0.05715)
						(xy 0.21209 -0.04699) (xy 0.2159 -0.03683) (xy 0.21844 -0.02667) (xy 0.22225 -0.01524) (xy 0.22352 -0.00508)
						(xy 0.22606 0.00508) (xy 0.22733 0.01651) (xy 0.22733 0.02667) (xy 0.2286 0.0381) (xy 0.22733 0.04953)
						(xy 0.22733 0.05969) (xy 0.22606 0.07112) (xy 0.22352 0.08128) (xy 0.22225 0.09144) (xy 0.21844 0.10287)
						(xy 0.2159 0.11303) (xy 0.21209 0.12319) (xy 0.20701 0.13335) (xy 0.2032 0.14224) (xy 0.19812 0.1524)
						(xy 0.17272 0.18796) (xy 0.1651 0.19558) (xy 0.1651 0.7366) (xy 0.16256 0.76835) (xy 0.1524 0.8001)
						(xy 0.13716 0.82804) (xy 0.11684 0.85344) (xy 0.09144 0.87376) (xy 0.0635 0.889) (xy 0.03175 0.89916)
					)
					(width 0)
					(fill yes)
				)
			)
		)
		(pad "133" smd custom
			(at 10.349992 4.106672)
			(size 0.1143 0.1143)
			(layers "F.Cu" "F.Mask" "F.Paste")
			(net "M_B_DQ36")
			(options
				(clearance outline)
				(anchor circle)
			)
			(primitives
				(gr_poly
					(pts
						(xy 0 0.9017) (xy -0.03175 0.89916) (xy -0.0635 0.889) (xy -0.09144 0.87376) (xy -0.11684 0.85344)
						(xy -0.13716 0.82804) (xy -0.1524 0.8001) (xy -0.16256 0.76835) (xy -0.1651 0.7366) (xy -0.1651 -0.13462)
						(xy -0.17272 -0.14224) (xy -0.19812 -0.1778) (xy -0.2032 -0.18796) (xy -0.20701 -0.19685) (xy -0.21209 -0.20701)
						(xy -0.2159 -0.21717) (xy -0.21844 -0.22733) (xy -0.22225 -0.23876) (xy -0.22352 -0.24892) (xy -0.22606 -0.25908)
						(xy -0.22733 -0.27051) (xy -0.22733 -0.28067) (xy -0.2286 -0.2921) (xy -0.22733 -0.30353) (xy -0.22733 -0.31369)
						(xy -0.22606 -0.32512) (xy -0.22352 -0.33528) (xy -0.22225 -0.34544) (xy -0.21844 -0.35687) (xy -0.2159 -0.36703)
						(xy -0.21209 -0.37719) (xy -0.20701 -0.38735) (xy -0.2032 -0.39624) (xy -0.19812 -0.4064) (xy -0.17272 -0.44196)
						(xy -0.1651 -0.44958) (xy -0.1651 -0.7366) (xy -0.16256 -0.76835) (xy -0.1524 -0.8001) (xy -0.13716 -0.82804)
						(xy -0.11684 -0.85344) (xy -0.09144 -0.87376) (xy -0.0635 -0.889) (xy -0.03175 -0.89916) (xy 0 -0.9017)
						(xy 0.03175 -0.89916) (xy 0.0635 -0.889) (xy 0.09144 -0.87376) (xy 0.11684 -0.85344) (xy 0.13716 -0.82804)
						(xy 0.1524 -0.8001) (xy 0.16256 -0.76835) (xy 0.1651 -0.7366) (xy 0.1651 -0.44958) (xy 0.17272 -0.44196)
						(xy 0.19812 -0.4064) (xy 0.2032 -0.39624) (xy 0.20701 -0.38735) (xy 0.21209 -0.37719) (xy 0.2159 -0.36703)
						(xy 0.21844 -0.35687) (xy 0.22225 -0.34544) (xy 0.22352 -0.33528) (xy 0.22606 -0.32512) (xy 0.22733 -0.31369)
						(xy 0.22733 -0.30353) (xy 0.2286 -0.2921) (xy 0.22733 -0.28067) (xy 0.22733 -0.27051) (xy 0.22606 -0.25908)
						(xy 0.22352 -0.24892) (xy 0.22225 -0.23876) (xy 0.21844 -0.22733) (xy 0.2159 -0.21717) (xy 0.21209 -0.20701)
						(xy 0.20701 -0.19685) (xy 0.2032 -0.18796) (xy 0.19812 -0.1778) (xy 0.17272 -0.14224) (xy 0.1651 -0.13462)
						(xy 0.1651 0.7366) (xy 0.16256 0.76835) (xy 0.1524 0.8001) (xy 0.13716 0.82804) (xy 0.11684 0.85344)
						(xy 0.09144 0.87376) (xy 0.0635 0.889) (xy 0.03175 0.89916)
					)
					(width 0)
					(fill yes)
				)
			)
		)
		(pad "134" smd custom
			(at 10.649966 -4.106672)
			(size 0.1143 0.1143)
			(layers "F.Cu" "F.Mask" "F.Paste")
			(net "M_B_DQ32")
			(options
				(clearance outline)
				(anchor circle)
			)
			(primitives
				(gr_poly
					(pts
						(xy 0 0.9017) (xy -0.03175 0.89916) (xy -0.0635 0.889) (xy -0.09144 0.87376) (xy -0.11684 0.85344)
						(xy -0.13716 0.82804) (xy -0.1524 0.8001) (xy -0.16256 0.76835) (xy -0.1651 0.7366) (xy -0.1651 0.44958)
						(xy -0.17272 0.44196) (xy -0.19812 0.4064) (xy -0.2032 0.39624) (xy -0.20701 0.38735) (xy -0.21209 0.37719)
						(xy -0.2159 0.36703) (xy -0.21844 0.35687) (xy -0.22225 0.34544) (xy -0.22352 0.33528) (xy -0.22606 0.32512)
						(xy -0.22733 0.31369) (xy -0.22733 0.30353) (xy -0.2286 0.2921) (xy -0.22733 0.28067) (xy -0.22733 0.27051)
						(xy -0.22606 0.25908) (xy -0.22352 0.24892) (xy -0.22225 0.23876) (xy -0.21844 0.22733) (xy -0.2159 0.21717)
						(xy -0.21209 0.20701) (xy -0.20701 0.19685) (xy -0.2032 0.18796) (xy -0.19812 0.1778) (xy -0.17272 0.14224)
						(xy -0.1651 0.13462) (xy -0.1651 -0.7366) (xy -0.16256 -0.76835) (xy -0.1524 -0.8001) (xy -0.13716 -0.82804)
						(xy -0.11684 -0.85344) (xy -0.09144 -0.87376) (xy -0.0635 -0.889) (xy -0.03175 -0.89916) (xy 0 -0.9017)
						(xy 0.03175 -0.89916) (xy 0.0635 -0.889) (xy 0.09144 -0.87376) (xy 0.11684 -0.85344) (xy 0.13716 -0.82804)
						(xy 0.1524 -0.8001) (xy 0.16256 -0.76835) (xy 0.1651 -0.7366) (xy 0.1651 0.13462) (xy 0.17272 0.14224)
						(xy 0.19812 0.1778) (xy 0.2032 0.18796) (xy 0.20701 0.19685) (xy 0.21209 0.20701) (xy 0.2159 0.21717)
						(xy 0.21844 0.22733) (xy 0.22225 0.23876) (xy 0.22352 0.24892) (xy 0.22606 0.25908) (xy 0.22733 0.27051)
						(xy 0.22733 0.28067) (xy 0.2286 0.2921) (xy 0.22733 0.30353) (xy 0.22733 0.31369) (xy 0.22606 0.32512)
						(xy 0.22352 0.33528) (xy 0.22225 0.34544) (xy 0.21844 0.35687) (xy 0.2159 0.36703) (xy 0.21209 0.37719)
						(xy 0.20701 0.38735) (xy 0.2032 0.39624) (xy 0.19812 0.4064) (xy 0.17272 0.44196) (xy 0.1651 0.44958)
						(xy 0.1651 0.7366) (xy 0.16256 0.76835) (xy 0.1524 0.8001) (xy 0.13716 0.82804) (xy 0.11684 0.85344)
						(xy 0.09144 0.87376) (xy 0.0635 0.889) (xy 0.03175 0.89916)
					)
					(width 0)
					(fill yes)
				)
			)
		)
		(pad "135" smd custom
			(at 10.94994 4.106672)
			(size 0.1143 0.1143)
			(layers "F.Cu" "F.Mask" "F.Paste")
			(net "M_B_DQ37")
			(options
				(clearance outline)
				(anchor circle)
			)
			(primitives
				(gr_poly
					(pts
						(xy 0 0.9017) (xy -0.03175 0.89916) (xy -0.0635 0.889) (xy -0.09144 0.87376) (xy -0.11684 0.85344)
						(xy -0.13716 0.82804) (xy -0.1524 0.8001) (xy -0.16256 0.76835) (xy -0.1651 0.7366) (xy -0.1651 0.11938)
						(xy -0.17272 0.11176) (xy -0.19812 0.0762) (xy -0.2032 0.06604) (xy -0.20701 0.05715) (xy -0.21209 0.04699)
						(xy -0.2159 0.03683) (xy -0.21844 0.02667) (xy -0.22225 0.01524) (xy -0.22352 0.00508) (xy -0.22606 -0.00508)
						(xy -0.22733 -0.01651) (xy -0.22733 -0.02667) (xy -0.2286 -0.0381) (xy -0.22733 -0.04953) (xy -0.22733 -0.05969)
						(xy -0.22606 -0.07112) (xy -0.22352 -0.08128) (xy -0.22225 -0.09144) (xy -0.21844 -0.10287) (xy -0.2159 -0.11303)
						(xy -0.21209 -0.12319) (xy -0.20701 -0.13335) (xy -0.2032 -0.14224) (xy -0.19812 -0.1524) (xy -0.17272 -0.18796)
						(xy -0.1651 -0.19558) (xy -0.1651 -0.7366) (xy -0.16256 -0.76835) (xy -0.1524 -0.8001) (xy -0.13716 -0.82804)
						(xy -0.11684 -0.85344) (xy -0.09144 -0.87376) (xy -0.0635 -0.889) (xy -0.03175 -0.89916) (xy 0 -0.9017)
						(xy 0.03175 -0.89916) (xy 0.0635 -0.889) (xy 0.09144 -0.87376) (xy 0.11684 -0.85344) (xy 0.13716 -0.82804)
						(xy 0.1524 -0.8001) (xy 0.16256 -0.76835) (xy 0.1651 -0.7366) (xy 0.1651 -0.19685) (xy 0.17272 -0.18923)
						(xy 0.17907 -0.18034) (xy 0.18669 -0.17145) (xy 0.19177 -0.16256) (xy 0.19812 -0.15367) (xy 0.20828 -0.13335)
						(xy 0.21971 -0.10287) (xy 0.22225 -0.09271) (xy 0.22479 -0.08128) (xy 0.22606 -0.07112) (xy 0.2286 -0.05969)
						(xy 0.2286 -0.01651) (xy 0.22606 -0.00508) (xy 0.22479 0.00508) (xy 0.22225 0.01651) (xy 0.21971 0.02667)
						(xy 0.20828 0.05715) (xy 0.19812 0.07747) (xy 0.19177 0.08636) (xy 0.18669 0.09525) (xy 0.17907 0.10414)
						(xy 0.17272 0.11303) (xy 0.1651 0.12065) (xy 0.1651 0.7366) (xy 0.16256 0.76835) (xy 0.1524 0.8001)
						(xy 0.13716 0.82804) (xy 0.11684 0.85344) (xy 0.09144 0.87376) (xy 0.0635 0.889) (xy 0.03175 0.89916)
					)
					(width 0)
					(fill yes)
				)
			)
		)
		(pad "136" smd custom
			(at 11.249914 -4.106672)
			(size 0.1143 0.1143)
			(layers "F.Cu" "F.Mask" "F.Paste")
			(net "M_B_DQ33")
			(options
				(clearance outline)
				(anchor circle)
			)
			(primitives
				(gr_poly
					(pts
						(xy 0 0.9017) (xy -0.03175 0.89916) (xy -0.0635 0.889) (xy -0.09144 0.87376) (xy -0.11684 0.85344)
						(xy -0.13716 0.82804) (xy -0.1524 0.8001) (xy -0.16256 0.76835) (xy -0.1651 0.7366) (xy -0.1651 0.19685)
						(xy -0.17272 0.18923) (xy -0.17907 0.18034) (xy -0.18669 0.17145) (xy -0.19177 0.16256) (xy -0.19812 0.15367)
						(xy -0.20828 0.13335) (xy -0.21971 0.10287) (xy -0.22225 0.09271) (xy -0.22479 0.08128) (xy -0.22606 0.07112)
						(xy -0.2286 0.05969) (xy -0.2286 0.01651) (xy -0.22606 0.00508) (xy -0.22479 -0.00508) (xy -0.22225 -0.01651)
						(xy -0.21971 -0.02667) (xy -0.20828 -0.05715) (xy -0.19812 -0.07747) (xy -0.19177 -0.08636) (xy -0.18669 -0.09525)
						(xy -0.17907 -0.10414) (xy -0.17272 -0.11303) (xy -0.1651 -0.12065) (xy -0.1651 -0.7366) (xy -0.16256 -0.76835)
						(xy -0.1524 -0.8001) (xy -0.13716 -0.82804) (xy -0.11684 -0.85344) (xy -0.09144 -0.87376) (xy -0.0635 -0.889)
						(xy -0.03175 -0.89916) (xy 0 -0.9017) (xy 0.03175 -0.89916) (xy 0.0635 -0.889) (xy 0.09144 -0.87376)
						(xy 0.11684 -0.85344) (xy 0.13716 -0.82804) (xy 0.1524 -0.8001) (xy 0.16256 -0.76835) (xy 0.1651 -0.7366)
						(xy 0.1651 -0.11938) (xy 0.17272 -0.11176) (xy 0.19812 -0.0762) (xy 0.2032 -0.06604) (xy 0.20701 -0.05715)
						(xy 0.21209 -0.04699) (xy 0.2159 -0.03683) (xy 0.21844 -0.02667) (xy 0.22225 -0.01524) (xy 0.22352 -0.00508)
						(xy 0.22606 0.00508) (xy 0.22733 0.01651) (xy 0.22733 0.02667) (xy 0.2286 0.0381) (xy 0.22733 0.04953)
						(xy 0.22733 0.05969) (xy 0.22606 0.07112) (xy 0.22352 0.08128) (xy 0.22225 0.09144) (xy 0.21844 0.10287)
						(xy 0.2159 0.11303) (xy 0.21209 0.12319) (xy 0.20701 0.13335) (xy 0.2032 0.14224) (xy 0.19812 0.1524)
						(xy 0.17272 0.18796) (xy 0.1651 0.19558) (xy 0.1651 0.7366) (xy 0.16256 0.76835) (xy 0.1524 0.8001)
						(xy 0.13716 0.82804) (xy 0.11684 0.85344) (xy 0.09144 0.87376) (xy 0.0635 0.889) (xy 0.03175 0.89916)
					)
					(width 0)
					(fill yes)
				)
			)
		)
		(pad "137" smd custom
			(at 11.549888 4.106672)
			(size 0.1143 0.1143)
			(layers "F.Cu" "F.Mask" "F.Paste")
			(net "GND")
			(options
				(clearance outline)
				(anchor circle)
			)
			(primitives
				(gr_poly
					(pts
						(xy 0 0.9017) (xy -0.03175 0.89916) (xy -0.0635 0.889) (xy -0.09144 0.87376) (xy -0.11684 0.85344)
						(xy -0.13716 0.82804) (xy -0.1524 0.8001) (xy -0.16256 0.76835) (xy -0.1651 0.7366) (xy -0.1651 -0.13462)
						(xy -0.17272 -0.14224) (xy -0.19812 -0.1778) (xy -0.2032 -0.18796) (xy -0.20701 -0.19685) (xy -0.21209 -0.20701)
						(xy -0.2159 -0.21717) (xy -0.21844 -0.22733) (xy -0.22225 -0.23876) (xy -0.22352 -0.24892) (xy -0.22606 -0.25908)
						(xy -0.22733 -0.27051) (xy -0.22733 -0.28067) (xy -0.2286 -0.2921) (xy -0.22733 -0.30353) (xy -0.22733 -0.31369)
						(xy -0.22606 -0.32512) (xy -0.22352 -0.33528) (xy -0.22225 -0.34544) (xy -0.21844 -0.35687) (xy -0.2159 -0.36703)
						(xy -0.21209 -0.37719) (xy -0.20701 -0.38735) (xy -0.2032 -0.39624) (xy -0.19812 -0.4064) (xy -0.17272 -0.44196)
						(xy -0.1651 -0.44958) (xy -0.1651 -0.7366) (xy -0.16256 -0.76835) (xy -0.1524 -0.8001) (xy -0.13716 -0.82804)
						(xy -0.11684 -0.85344) (xy -0.09144 -0.87376) (xy -0.0635 -0.889) (xy -0.03175 -0.89916) (xy 0 -0.9017)
						(xy 0.03175 -0.89916) (xy 0.0635 -0.889) (xy 0.09144 -0.87376) (xy 0.11684 -0.85344) (xy 0.13716 -0.82804)
						(xy 0.1524 -0.8001) (xy 0.16256 -0.76835) (xy 0.1651 -0.7366) (xy 0.1651 -0.44958) (xy 0.17272 -0.44196)
						(xy 0.19812 -0.4064) (xy 0.2032 -0.39624) (xy 0.20701 -0.38735) (xy 0.21209 -0.37719) (xy 0.2159 -0.36703)
						(xy 0.21844 -0.35687) (xy 0.22225 -0.34544) (xy 0.22352 -0.33528) (xy 0.22606 -0.32512) (xy 0.22733 -0.31369)
						(xy 0.22733 -0.30353) (xy 0.2286 -0.2921) (xy 0.22733 -0.28067) (xy 0.22733 -0.27051) (xy 0.22606 -0.25908)
						(xy 0.22352 -0.24892) (xy 0.22225 -0.23876) (xy 0.21844 -0.22733) (xy 0.2159 -0.21717) (xy 0.21209 -0.20701)
						(xy 0.20701 -0.19685) (xy 0.2032 -0.18796) (xy 0.19812 -0.1778) (xy 0.17272 -0.14224) (xy 0.1651 -0.13462)
						(xy 0.1651 0.7366) (xy 0.16256 0.76835) (xy 0.1524 0.8001) (xy 0.13716 0.82804) (xy 0.11684 0.85344)
						(xy 0.09144 0.87376) (xy 0.0635 0.889) (xy 0.03175 0.89916)
					)
					(width 0)
					(fill yes)
				)
			)
		)
		(pad "138" smd custom
			(at 11.850116 -4.106672)
			(size 0.1143 0.1143)
			(layers "F.Cu" "F.Mask" "F.Paste")
			(net "GND")
			(options
				(clearance outline)
				(anchor circle)
			)
			(primitives
				(gr_poly
					(pts
						(xy 0 0.9017) (xy -0.03175 0.89916) (xy -0.0635 0.889) (xy -0.09144 0.87376) (xy -0.11684 0.85344)
						(xy -0.13716 0.82804) (xy -0.1524 0.8001) (xy -0.16256 0.76835) (xy -0.1651 0.7366) (xy -0.1651 0.44958)
						(xy -0.17272 0.44196) (xy -0.19812 0.4064) (xy -0.2032 0.39624) (xy -0.20701 0.38735) (xy -0.21209 0.37719)
						(xy -0.2159 0.36703) (xy -0.21844 0.35687) (xy -0.22225 0.34544) (xy -0.22352 0.33528) (xy -0.22606 0.32512)
						(xy -0.22733 0.31369) (xy -0.22733 0.30353) (xy -0.2286 0.2921) (xy -0.22733 0.28067) (xy -0.22733 0.27051)
						(xy -0.22606 0.25908) (xy -0.22352 0.24892) (xy -0.22225 0.23876) (xy -0.21844 0.22733) (xy -0.2159 0.21717)
						(xy -0.21209 0.20701) (xy -0.20701 0.19685) (xy -0.2032 0.18796) (xy -0.19812 0.1778) (xy -0.17272 0.14224)
						(xy -0.1651 0.13462) (xy -0.1651 -0.7366) (xy -0.16256 -0.76835) (xy -0.1524 -0.8001) (xy -0.13716 -0.82804)
						(xy -0.11684 -0.85344) (xy -0.09144 -0.87376) (xy -0.0635 -0.889) (xy -0.03175 -0.89916) (xy 0 -0.9017)
						(xy 0.03175 -0.89916) (xy 0.0635 -0.889) (xy 0.09144 -0.87376) (xy 0.11684 -0.85344) (xy 0.13716 -0.82804)
						(xy 0.1524 -0.8001) (xy 0.16256 -0.76835) (xy 0.1651 -0.7366) (xy 0.1651 0.13462) (xy 0.17272 0.14224)
						(xy 0.19812 0.1778) (xy 0.2032 0.18796) (xy 0.20701 0.19685) (xy 0.21209 0.20701) (xy 0.2159 0.21717)
						(xy 0.21844 0.22733) (xy 0.22225 0.23876) (xy 0.22352 0.24892) (xy 0.22606 0.25908) (xy 0.22733 0.27051)
						(xy 0.22733 0.28067) (xy 0.2286 0.2921) (xy 0.22733 0.30353) (xy 0.22733 0.31369) (xy 0.22606 0.32512)
						(xy 0.22352 0.33528) (xy 0.22225 0.34544) (xy 0.21844 0.35687) (xy 0.2159 0.36703) (xy 0.21209 0.37719)
						(xy 0.20701 0.38735) (xy 0.2032 0.39624) (xy 0.19812 0.4064) (xy 0.17272 0.44196) (xy 0.1651 0.44958)
						(xy 0.1651 0.7366) (xy 0.16256 0.76835) (xy 0.1524 0.8001) (xy 0.13716 0.82804) (xy 0.11684 0.85344)
						(xy 0.09144 0.87376) (xy 0.0635 0.889) (xy 0.03175 0.89916)
					)
					(width 0)
					(fill yes)
				)
			)
		)
		(pad "139" smd custom
			(at 12.15009 4.106672)
			(size 0.1143 0.1143)
			(layers "F.Cu" "F.Mask" "F.Paste")
			(net "M_B_DQS_DN4")
			(options
				(clearance outline)
				(anchor circle)
			)
			(primitives
				(gr_poly
					(pts
						(xy 0 0.9017) (xy -0.03175 0.89916) (xy -0.0635 0.889) (xy -0.09144 0.87376) (xy -0.11684 0.85344)
						(xy -0.13716 0.82804) (xy -0.1524 0.8001) (xy -0.16256 0.76835) (xy -0.1651 0.7366) (xy -0.1651 0.11938)
						(xy -0.17272 0.11176) (xy -0.19812 0.0762) (xy -0.2032 0.06604) (xy -0.20701 0.05715) (xy -0.21209 0.04699)
						(xy -0.2159 0.03683) (xy -0.21844 0.02667) (xy -0.22225 0.01524) (xy -0.22352 0.00508) (xy -0.22606 -0.00508)
						(xy -0.22733 -0.01651) (xy -0.22733 -0.02667) (xy -0.2286 -0.0381) (xy -0.22733 -0.04953) (xy -0.22733 -0.05969)
						(xy -0.22606 -0.07112) (xy -0.22352 -0.08128) (xy -0.22225 -0.09144) (xy -0.21844 -0.10287) (xy -0.2159 -0.11303)
						(xy -0.21209 -0.12319) (xy -0.20701 -0.13335) (xy -0.2032 -0.14224) (xy -0.19812 -0.1524) (xy -0.17272 -0.18796)
						(xy -0.1651 -0.19558) (xy -0.1651 -0.7366) (xy -0.16256 -0.76835) (xy -0.1524 -0.8001) (xy -0.13716 -0.82804)
						(xy -0.11684 -0.85344) (xy -0.09144 -0.87376) (xy -0.0635 -0.889) (xy -0.03175 -0.89916) (xy 0 -0.9017)
						(xy 0.03175 -0.89916) (xy 0.0635 -0.889) (xy 0.09144 -0.87376) (xy 0.11684 -0.85344) (xy 0.13716 -0.82804)
						(xy 0.1524 -0.8001) (xy 0.16256 -0.76835) (xy 0.1651 -0.7366) (xy 0.1651 -0.19685) (xy 0.17272 -0.18923)
						(xy 0.17907 -0.18034) (xy 0.18669 -0.17145) (xy 0.19177 -0.16256) (xy 0.19812 -0.15367) (xy 0.20828 -0.13335)
						(xy 0.21971 -0.10287) (xy 0.22225 -0.09271) (xy 0.22479 -0.08128) (xy 0.22606 -0.07112) (xy 0.2286 -0.05969)
						(xy 0.2286 -0.01651) (xy 0.22606 -0.00508) (xy 0.22479 0.00508) (xy 0.22225 0.01651) (xy 0.21971 0.02667)
						(xy 0.20828 0.05715) (xy 0.19812 0.07747) (xy 0.19177 0.08636) (xy 0.18669 0.09525) (xy 0.17907 0.10414)
						(xy 0.17272 0.11303) (xy 0.1651 0.12065) (xy 0.1651 0.7366) (xy 0.16256 0.76835) (xy 0.1524 0.8001)
						(xy 0.13716 0.82804) (xy 0.11684 0.85344) (xy 0.09144 0.87376) (xy 0.0635 0.889) (xy 0.03175 0.89916)
					)
					(width 0)
					(fill yes)
				)
			)
		)
		(pad "140" smd custom
			(at 12.450064 -4.106672)
			(size 0.1143 0.1143)
			(layers "F.Cu" "F.Mask" "F.Paste")
			(net "GND")
			(options
				(clearance outline)
				(anchor circle)
			)
			(primitives
				(gr_poly
					(pts
						(xy 0 0.9017) (xy -0.03175 0.89916) (xy -0.0635 0.889) (xy -0.09144 0.87376) (xy -0.11684 0.85344)
						(xy -0.13716 0.82804) (xy -0.1524 0.8001) (xy -0.16256 0.76835) (xy -0.1651 0.7366) (xy -0.1651 0.19685)
						(xy -0.17272 0.18923) (xy -0.17907 0.18034) (xy -0.18669 0.17145) (xy -0.19177 0.16256) (xy -0.19812 0.15367)
						(xy -0.20828 0.13335) (xy -0.21971 0.10287) (xy -0.22225 0.09271) (xy -0.22479 0.08128) (xy -0.22606 0.07112)
						(xy -0.2286 0.05969) (xy -0.2286 0.01651) (xy -0.22606 0.00508) (xy -0.22479 -0.00508) (xy -0.22225 -0.01651)
						(xy -0.21971 -0.02667) (xy -0.20828 -0.05715) (xy -0.19812 -0.07747) (xy -0.19177 -0.08636) (xy -0.18669 -0.09525)
						(xy -0.17907 -0.10414) (xy -0.17272 -0.11303) (xy -0.1651 -0.12065) (xy -0.1651 -0.7366) (xy -0.16256 -0.76835)
						(xy -0.1524 -0.8001) (xy -0.13716 -0.82804) (xy -0.11684 -0.85344) (xy -0.09144 -0.87376) (xy -0.0635 -0.889)
						(xy -0.03175 -0.89916) (xy 0 -0.9017) (xy 0.03175 -0.89916) (xy 0.0635 -0.889) (xy 0.09144 -0.87376)
						(xy 0.11684 -0.85344) (xy 0.13716 -0.82804) (xy 0.1524 -0.8001) (xy 0.16256 -0.76835) (xy 0.1651 -0.7366)
						(xy 0.1651 -0.11938) (xy 0.17272 -0.11176) (xy 0.19812 -0.0762) (xy 0.2032 -0.06604) (xy 0.20701 -0.05715)
						(xy 0.21209 -0.04699) (xy 0.2159 -0.03683) (xy 0.21844 -0.02667) (xy 0.22225 -0.01524) (xy 0.22352 -0.00508)
						(xy 0.22606 0.00508) (xy 0.22733 0.01651) (xy 0.22733 0.02667) (xy 0.2286 0.0381) (xy 0.22733 0.04953)
						(xy 0.22733 0.05969) (xy 0.22606 0.07112) (xy 0.22352 0.08128) (xy 0.22225 0.09144) (xy 0.21844 0.10287)
						(xy 0.2159 0.11303) (xy 0.21209 0.12319) (xy 0.20701 0.13335) (xy 0.2032 0.14224) (xy 0.19812 0.1524)
						(xy 0.17272 0.18796) (xy 0.1651 0.19558) (xy 0.1651 0.7366) (xy 0.16256 0.76835) (xy 0.1524 0.8001)
						(xy 0.13716 0.82804) (xy 0.11684 0.85344) (xy 0.09144 0.87376) (xy 0.0635 0.889) (xy 0.03175 0.89916)
					)
					(width 0)
					(fill yes)
				)
			)
		)
		(pad "141" smd custom
			(at 12.750038 4.106672)
			(size 0.1143 0.1143)
			(layers "F.Cu" "F.Mask" "F.Paste")
			(net "M_B_DQS_DP4")
			(options
				(clearance outline)
				(anchor circle)
			)
			(primitives
				(gr_poly
					(pts
						(xy 0 0.9017) (xy -0.03175 0.89916) (xy -0.0635 0.889) (xy -0.09144 0.87376) (xy -0.11684 0.85344)
						(xy -0.13716 0.82804) (xy -0.1524 0.8001) (xy -0.16256 0.76835) (xy -0.1651 0.7366) (xy -0.1651 -0.13462)
						(xy -0.17272 -0.14224) (xy -0.19812 -0.1778) (xy -0.2032 -0.18796) (xy -0.20701 -0.19685) (xy -0.21209 -0.20701)
						(xy -0.2159 -0.21717) (xy -0.21844 -0.22733) (xy -0.22225 -0.23876) (xy -0.22352 -0.24892) (xy -0.22606 -0.25908)
						(xy -0.22733 -0.27051) (xy -0.22733 -0.28067) (xy -0.2286 -0.2921) (xy -0.22733 -0.30353) (xy -0.22733 -0.31369)
						(xy -0.22606 -0.32512) (xy -0.22352 -0.33528) (xy -0.22225 -0.34544) (xy -0.21844 -0.35687) (xy -0.2159 -0.36703)
						(xy -0.21209 -0.37719) (xy -0.20701 -0.38735) (xy -0.2032 -0.39624) (xy -0.19812 -0.4064) (xy -0.17272 -0.44196)
						(xy -0.1651 -0.44958) (xy -0.1651 -0.7366) (xy -0.16256 -0.76835) (xy -0.1524 -0.8001) (xy -0.13716 -0.82804)
						(xy -0.11684 -0.85344) (xy -0.09144 -0.87376) (xy -0.0635 -0.889) (xy -0.03175 -0.89916) (xy 0 -0.9017)
						(xy 0.03175 -0.89916) (xy 0.0635 -0.889) (xy 0.09144 -0.87376) (xy 0.11684 -0.85344) (xy 0.13716 -0.82804)
						(xy 0.1524 -0.8001) (xy 0.16256 -0.76835) (xy 0.1651 -0.7366) (xy 0.1651 -0.44958) (xy 0.17272 -0.44196)
						(xy 0.19812 -0.4064) (xy 0.2032 -0.39624) (xy 0.20701 -0.38735) (xy 0.21209 -0.37719) (xy 0.2159 -0.36703)
						(xy 0.21844 -0.35687) (xy 0.22225 -0.34544) (xy 0.22352 -0.33528) (xy 0.22606 -0.32512) (xy 0.22733 -0.31369)
						(xy 0.22733 -0.30353) (xy 0.2286 -0.2921) (xy 0.22733 -0.28067) (xy 0.22733 -0.27051) (xy 0.22606 -0.25908)
						(xy 0.22352 -0.24892) (xy 0.22225 -0.23876) (xy 0.21844 -0.22733) (xy 0.2159 -0.21717) (xy 0.21209 -0.20701)
						(xy 0.20701 -0.19685) (xy 0.2032 -0.18796) (xy 0.19812 -0.1778) (xy 0.17272 -0.14224) (xy 0.1651 -0.13462)
						(xy 0.1651 0.7366) (xy 0.16256 0.76835) (xy 0.1524 0.8001) (xy 0.13716 0.82804) (xy 0.11684 0.85344)
						(xy 0.09144 0.87376) (xy 0.0635 0.889) (xy 0.03175 0.89916)
					)
					(width 0)
					(fill yes)
				)
			)
		)
		(pad "142" smd custom
			(at 13.050012 -4.106672)
			(size 0.1143 0.1143)
			(layers "F.Cu" "F.Mask" "F.Paste")
			(net "M_B_DQ34")
			(options
				(clearance outline)
				(anchor circle)
			)
			(primitives
				(gr_poly
					(pts
						(xy 0 0.9017) (xy -0.03175 0.89916) (xy -0.0635 0.889) (xy -0.09144 0.87376) (xy -0.11684 0.85344)
						(xy -0.13716 0.82804) (xy -0.1524 0.8001) (xy -0.16256 0.76835) (xy -0.1651 0.7366) (xy -0.1651 0.44958)
						(xy -0.17272 0.44196) (xy -0.19812 0.4064) (xy -0.2032 0.39624) (xy -0.20701 0.38735) (xy -0.21209 0.37719)
						(xy -0.2159 0.36703) (xy -0.21844 0.35687) (xy -0.22225 0.34544) (xy -0.22352 0.33528) (xy -0.22606 0.32512)
						(xy -0.22733 0.31369) (xy -0.22733 0.30353) (xy -0.2286 0.2921) (xy -0.22733 0.28067) (xy -0.22733 0.27051)
						(xy -0.22606 0.25908) (xy -0.22352 0.24892) (xy -0.22225 0.23876) (xy -0.21844 0.22733) (xy -0.2159 0.21717)
						(xy -0.21209 0.20701) (xy -0.20701 0.19685) (xy -0.2032 0.18796) (xy -0.19812 0.1778) (xy -0.17272 0.14224)
						(xy -0.1651 0.13462) (xy -0.1651 -0.7366) (xy -0.16256 -0.76835) (xy -0.1524 -0.8001) (xy -0.13716 -0.82804)
						(xy -0.11684 -0.85344) (xy -0.09144 -0.87376) (xy -0.0635 -0.889) (xy -0.03175 -0.89916) (xy 0 -0.9017)
						(xy 0.03175 -0.89916) (xy 0.0635 -0.889) (xy 0.09144 -0.87376) (xy 0.11684 -0.85344) (xy 0.13716 -0.82804)
						(xy 0.1524 -0.8001) (xy 0.16256 -0.76835) (xy 0.1651 -0.7366) (xy 0.1651 0.13462) (xy 0.17272 0.14224)
						(xy 0.19812 0.1778) (xy 0.2032 0.18796) (xy 0.20701 0.19685) (xy 0.21209 0.20701) (xy 0.2159 0.21717)
						(xy 0.21844 0.22733) (xy 0.22225 0.23876) (xy 0.22352 0.24892) (xy 0.22606 0.25908) (xy 0.22733 0.27051)
						(xy 0.22733 0.28067) (xy 0.2286 0.2921) (xy 0.22733 0.30353) (xy 0.22733 0.31369) (xy 0.22606 0.32512)
						(xy 0.22352 0.33528) (xy 0.22225 0.34544) (xy 0.21844 0.35687) (xy 0.2159 0.36703) (xy 0.21209 0.37719)
						(xy 0.20701 0.38735) (xy 0.2032 0.39624) (xy 0.19812 0.4064) (xy 0.17272 0.44196) (xy 0.1651 0.44958)
						(xy 0.1651 0.7366) (xy 0.16256 0.76835) (xy 0.1524 0.8001) (xy 0.13716 0.82804) (xy 0.11684 0.85344)
						(xy 0.09144 0.87376) (xy 0.0635 0.889) (xy 0.03175 0.89916)
					)
					(width 0)
					(fill yes)
				)
			)
		)
		(pad "143" smd custom
			(at 13.349986 4.106672)
			(size 0.1143 0.1143)
			(layers "F.Cu" "F.Mask" "F.Paste")
			(net "GND")
			(options
				(clearance outline)
				(anchor circle)
			)
			(primitives
				(gr_poly
					(pts
						(xy 0 0.9017) (xy -0.03175 0.89916) (xy -0.0635 0.889) (xy -0.09144 0.87376) (xy -0.11684 0.85344)
						(xy -0.13716 0.82804) (xy -0.1524 0.8001) (xy -0.16256 0.76835) (xy -0.1651 0.7366) (xy -0.1651 0.11938)
						(xy -0.17272 0.11176) (xy -0.19812 0.0762) (xy -0.2032 0.06604) (xy -0.20701 0.05715) (xy -0.21209 0.04699)
						(xy -0.2159 0.03683) (xy -0.21844 0.02667) (xy -0.22225 0.01524) (xy -0.22352 0.00508) (xy -0.22606 -0.00508)
						(xy -0.22733 -0.01651) (xy -0.22733 -0.02667) (xy -0.2286 -0.0381) (xy -0.22733 -0.04953) (xy -0.22733 -0.05969)
						(xy -0.22606 -0.07112) (xy -0.22352 -0.08128) (xy -0.22225 -0.09144) (xy -0.21844 -0.10287) (xy -0.2159 -0.11303)
						(xy -0.21209 -0.12319) (xy -0.20701 -0.13335) (xy -0.2032 -0.14224) (xy -0.19812 -0.1524) (xy -0.17272 -0.18796)
						(xy -0.1651 -0.19558) (xy -0.1651 -0.7366) (xy -0.16256 -0.76835) (xy -0.1524 -0.8001) (xy -0.13716 -0.82804)
						(xy -0.11684 -0.85344) (xy -0.09144 -0.87376) (xy -0.0635 -0.889) (xy -0.03175 -0.89916) (xy 0 -0.9017)
						(xy 0.03175 -0.89916) (xy 0.0635 -0.889) (xy 0.09144 -0.87376) (xy 0.11684 -0.85344) (xy 0.13716 -0.82804)
						(xy 0.1524 -0.8001) (xy 0.16256 -0.76835) (xy 0.1651 -0.7366) (xy 0.1651 -0.19685) (xy 0.17272 -0.18923)
						(xy 0.17907 -0.18034) (xy 0.18669 -0.17145) (xy 0.19177 -0.16256) (xy 0.19812 -0.15367) (xy 0.20828 -0.13335)
						(xy 0.21971 -0.10287) (xy 0.22225 -0.09271) (xy 0.22479 -0.08128) (xy 0.22606 -0.07112) (xy 0.2286 -0.05969)
						(xy 0.2286 -0.01651) (xy 0.22606 -0.00508) (xy 0.22479 0.00508) (xy 0.22225 0.01651) (xy 0.21971 0.02667)
						(xy 0.20828 0.05715) (xy 0.19812 0.07747) (xy 0.19177 0.08636) (xy 0.18669 0.09525) (xy 0.17907 0.10414)
						(xy 0.17272 0.11303) (xy 0.1651 0.12065) (xy 0.1651 0.7366) (xy 0.16256 0.76835) (xy 0.1524 0.8001)
						(xy 0.13716 0.82804) (xy 0.11684 0.85344) (xy 0.09144 0.87376) (xy 0.0635 0.889) (xy 0.03175 0.89916)
					)
					(width 0)
					(fill yes)
				)
			)
		)
		(pad "144" smd custom
			(at 13.64996 -4.106672)
			(size 0.1143 0.1143)
			(layers "F.Cu" "F.Mask" "F.Paste")
			(net "M_B_DQ35")
			(options
				(clearance outline)
				(anchor circle)
			)
			(primitives
				(gr_poly
					(pts
						(xy 0 0.9017) (xy -0.03175 0.89916) (xy -0.0635 0.889) (xy -0.09144 0.87376) (xy -0.11684 0.85344)
						(xy -0.13716 0.82804) (xy -0.1524 0.8001) (xy -0.16256 0.76835) (xy -0.1651 0.7366) (xy -0.1651 0.19685)
						(xy -0.17272 0.18923) (xy -0.17907 0.18034) (xy -0.18669 0.17145) (xy -0.19177 0.16256) (xy -0.19812 0.15367)
						(xy -0.20828 0.13335) (xy -0.21971 0.10287) (xy -0.22225 0.09271) (xy -0.22479 0.08128) (xy -0.22606 0.07112)
						(xy -0.2286 0.05969) (xy -0.2286 0.01651) (xy -0.22606 0.00508) (xy -0.22479 -0.00508) (xy -0.22225 -0.01651)
						(xy -0.21971 -0.02667) (xy -0.20828 -0.05715) (xy -0.19812 -0.07747) (xy -0.19177 -0.08636) (xy -0.18669 -0.09525)
						(xy -0.17907 -0.10414) (xy -0.17272 -0.11303) (xy -0.1651 -0.12065) (xy -0.1651 -0.7366) (xy -0.16256 -0.76835)
						(xy -0.1524 -0.8001) (xy -0.13716 -0.82804) (xy -0.11684 -0.85344) (xy -0.09144 -0.87376) (xy -0.0635 -0.889)
						(xy -0.03175 -0.89916) (xy 0 -0.9017) (xy 0.03175 -0.89916) (xy 0.0635 -0.889) (xy 0.09144 -0.87376)
						(xy 0.11684 -0.85344) (xy 0.13716 -0.82804) (xy 0.1524 -0.8001) (xy 0.16256 -0.76835) (xy 0.1651 -0.7366)
						(xy 0.1651 -0.11938) (xy 0.17272 -0.11176) (xy 0.19812 -0.0762) (xy 0.2032 -0.06604) (xy 0.20701 -0.05715)
						(xy 0.21209 -0.04699) (xy 0.2159 -0.03683) (xy 0.21844 -0.02667) (xy 0.22225 -0.01524) (xy 0.22352 -0.00508)
						(xy 0.22606 0.00508) (xy 0.22733 0.01651) (xy 0.22733 0.02667) (xy 0.2286 0.0381) (xy 0.22733 0.04953)
						(xy 0.22733 0.05969) (xy 0.22606 0.07112) (xy 0.22352 0.08128) (xy 0.22225 0.09144) (xy 0.21844 0.10287)
						(xy 0.2159 0.11303) (xy 0.21209 0.12319) (xy 0.20701 0.13335) (xy 0.2032 0.14224) (xy 0.19812 0.1524)
						(xy 0.17272 0.18796) (xy 0.1651 0.19558) (xy 0.1651 0.7366) (xy 0.16256 0.76835) (xy 0.1524 0.8001)
						(xy 0.13716 0.82804) (xy 0.11684 0.85344) (xy 0.09144 0.87376) (xy 0.0635 0.889) (xy 0.03175 0.89916)
					)
					(width 0)
					(fill yes)
				)
			)
		)
		(pad "145" smd custom
			(at 13.949934 4.106672)
			(size 0.1143 0.1143)
			(layers "F.Cu" "F.Mask" "F.Paste")
			(net "M_B_DQ38")
			(options
				(clearance outline)
				(anchor circle)
			)
			(primitives
				(gr_poly
					(pts
						(xy 0 0.9017) (xy -0.03175 0.89916) (xy -0.0635 0.889) (xy -0.09144 0.87376) (xy -0.11684 0.85344)
						(xy -0.13716 0.82804) (xy -0.1524 0.8001) (xy -0.16256 0.76835) (xy -0.1651 0.7366) (xy -0.1651 -0.13462)
						(xy -0.17272 -0.14224) (xy -0.19812 -0.1778) (xy -0.2032 -0.18796) (xy -0.20701 -0.19685) (xy -0.21209 -0.20701)
						(xy -0.2159 -0.21717) (xy -0.21844 -0.22733) (xy -0.22225 -0.23876) (xy -0.22352 -0.24892) (xy -0.22606 -0.25908)
						(xy -0.22733 -0.27051) (xy -0.22733 -0.28067) (xy -0.2286 -0.2921) (xy -0.22733 -0.30353) (xy -0.22733 -0.31369)
						(xy -0.22606 -0.32512) (xy -0.22352 -0.33528) (xy -0.22225 -0.34544) (xy -0.21844 -0.35687) (xy -0.2159 -0.36703)
						(xy -0.21209 -0.37719) (xy -0.20701 -0.38735) (xy -0.2032 -0.39624) (xy -0.19812 -0.4064) (xy -0.17272 -0.44196)
						(xy -0.1651 -0.44958) (xy -0.1651 -0.7366) (xy -0.16256 -0.76835) (xy -0.1524 -0.8001) (xy -0.13716 -0.82804)
						(xy -0.11684 -0.85344) (xy -0.09144 -0.87376) (xy -0.0635 -0.889) (xy -0.03175 -0.89916) (xy 0 -0.9017)
						(xy 0.03175 -0.89916) (xy 0.0635 -0.889) (xy 0.09144 -0.87376) (xy 0.11684 -0.85344) (xy 0.13716 -0.82804)
						(xy 0.1524 -0.8001) (xy 0.16256 -0.76835) (xy 0.1651 -0.7366) (xy 0.1651 -0.44958) (xy 0.17272 -0.44196)
						(xy 0.19812 -0.4064) (xy 0.2032 -0.39624) (xy 0.20701 -0.38735) (xy 0.21209 -0.37719) (xy 0.2159 -0.36703)
						(xy 0.21844 -0.35687) (xy 0.22225 -0.34544) (xy 0.22352 -0.33528) (xy 0.22606 -0.32512) (xy 0.22733 -0.31369)
						(xy 0.22733 -0.30353) (xy 0.2286 -0.2921) (xy 0.22733 -0.28067) (xy 0.22733 -0.27051) (xy 0.22606 -0.25908)
						(xy 0.22352 -0.24892) (xy 0.22225 -0.23876) (xy 0.21844 -0.22733) (xy 0.2159 -0.21717) (xy 0.21209 -0.20701)
						(xy 0.20701 -0.19685) (xy 0.2032 -0.18796) (xy 0.19812 -0.1778) (xy 0.17272 -0.14224) (xy 0.1651 -0.13462)
						(xy 0.1651 0.7366) (xy 0.16256 0.76835) (xy 0.1524 0.8001) (xy 0.13716 0.82804) (xy 0.11684 0.85344)
						(xy 0.09144 0.87376) (xy 0.0635 0.889) (xy 0.03175 0.89916)
					)
					(width 0)
					(fill yes)
				)
			)
		)
		(pad "146" smd custom
			(at 14.249908 -4.106672)
			(size 0.1143 0.1143)
			(layers "F.Cu" "F.Mask" "F.Paste")
			(net "GND")
			(options
				(clearance outline)
				(anchor circle)
			)
			(primitives
				(gr_poly
					(pts
						(xy 0 0.9017) (xy -0.03175 0.89916) (xy -0.0635 0.889) (xy -0.09144 0.87376) (xy -0.11684 0.85344)
						(xy -0.13716 0.82804) (xy -0.1524 0.8001) (xy -0.16256 0.76835) (xy -0.1651 0.7366) (xy -0.1651 0.44958)
						(xy -0.17272 0.44196) (xy -0.19812 0.4064) (xy -0.2032 0.39624) (xy -0.20701 0.38735) (xy -0.21209 0.37719)
						(xy -0.2159 0.36703) (xy -0.21844 0.35687) (xy -0.22225 0.34544) (xy -0.22352 0.33528) (xy -0.22606 0.32512)
						(xy -0.22733 0.31369) (xy -0.22733 0.30353) (xy -0.2286 0.2921) (xy -0.22733 0.28067) (xy -0.22733 0.27051)
						(xy -0.22606 0.25908) (xy -0.22352 0.24892) (xy -0.22225 0.23876) (xy -0.21844 0.22733) (xy -0.2159 0.21717)
						(xy -0.21209 0.20701) (xy -0.20701 0.19685) (xy -0.2032 0.18796) (xy -0.19812 0.1778) (xy -0.17272 0.14224)
						(xy -0.1651 0.13462) (xy -0.1651 -0.7366) (xy -0.16256 -0.76835) (xy -0.1524 -0.8001) (xy -0.13716 -0.82804)
						(xy -0.11684 -0.85344) (xy -0.09144 -0.87376) (xy -0.0635 -0.889) (xy -0.03175 -0.89916) (xy 0 -0.9017)
						(xy 0.03175 -0.89916) (xy 0.0635 -0.889) (xy 0.09144 -0.87376) (xy 0.11684 -0.85344) (xy 0.13716 -0.82804)
						(xy 0.1524 -0.8001) (xy 0.16256 -0.76835) (xy 0.1651 -0.7366) (xy 0.1651 0.13462) (xy 0.17272 0.14224)
						(xy 0.19812 0.1778) (xy 0.2032 0.18796) (xy 0.20701 0.19685) (xy 0.21209 0.20701) (xy 0.2159 0.21717)
						(xy 0.21844 0.22733) (xy 0.22225 0.23876) (xy 0.22352 0.24892) (xy 0.22606 0.25908) (xy 0.22733 0.27051)
						(xy 0.22733 0.28067) (xy 0.2286 0.2921) (xy 0.22733 0.30353) (xy 0.22733 0.31369) (xy 0.22606 0.32512)
						(xy 0.22352 0.33528) (xy 0.22225 0.34544) (xy 0.21844 0.35687) (xy 0.2159 0.36703) (xy 0.21209 0.37719)
						(xy 0.20701 0.38735) (xy 0.2032 0.39624) (xy 0.19812 0.4064) (xy 0.17272 0.44196) (xy 0.1651 0.44958)
						(xy 0.1651 0.7366) (xy 0.16256 0.76835) (xy 0.1524 0.8001) (xy 0.13716 0.82804) (xy 0.11684 0.85344)
						(xy 0.09144 0.87376) (xy 0.0635 0.889) (xy 0.03175 0.89916)
					)
					(width 0)
					(fill yes)
				)
			)
		)
		(pad "147" smd custom
			(at 14.549882 4.106672)
			(size 0.1143 0.1143)
			(layers "F.Cu" "F.Mask" "F.Paste")
			(net "M_B_DQ39")
			(options
				(clearance outline)
				(anchor circle)
			)
			(primitives
				(gr_poly
					(pts
						(xy 0 0.9017) (xy -0.03175 0.89916) (xy -0.0635 0.889) (xy -0.09144 0.87376) (xy -0.11684 0.85344)
						(xy -0.13716 0.82804) (xy -0.1524 0.8001) (xy -0.16256 0.76835) (xy -0.1651 0.7366) (xy -0.1651 0.11938)
						(xy -0.17272 0.11176) (xy -0.19812 0.0762) (xy -0.2032 0.06604) (xy -0.20701 0.05715) (xy -0.21209 0.04699)
						(xy -0.2159 0.03683) (xy -0.21844 0.02667) (xy -0.22225 0.01524) (xy -0.22352 0.00508) (xy -0.22606 -0.00508)
						(xy -0.22733 -0.01651) (xy -0.22733 -0.02667) (xy -0.2286 -0.0381) (xy -0.22733 -0.04953) (xy -0.22733 -0.05969)
						(xy -0.22606 -0.07112) (xy -0.22352 -0.08128) (xy -0.22225 -0.09144) (xy -0.21844 -0.10287) (xy -0.2159 -0.11303)
						(xy -0.21209 -0.12319) (xy -0.20701 -0.13335) (xy -0.2032 -0.14224) (xy -0.19812 -0.1524) (xy -0.17272 -0.18796)
						(xy -0.1651 -0.19558) (xy -0.1651 -0.7366) (xy -0.16256 -0.76835) (xy -0.1524 -0.8001) (xy -0.13716 -0.82804)
						(xy -0.11684 -0.85344) (xy -0.09144 -0.87376) (xy -0.0635 -0.889) (xy -0.03175 -0.89916) (xy 0 -0.9017)
						(xy 0.03175 -0.89916) (xy 0.0635 -0.889) (xy 0.09144 -0.87376) (xy 0.11684 -0.85344) (xy 0.13716 -0.82804)
						(xy 0.1524 -0.8001) (xy 0.16256 -0.76835) (xy 0.1651 -0.7366) (xy 0.1651 -0.19685) (xy 0.17272 -0.18923)
						(xy 0.17907 -0.18034) (xy 0.18669 -0.17145) (xy 0.19177 -0.16256) (xy 0.19812 -0.15367) (xy 0.20828 -0.13335)
						(xy 0.21971 -0.10287) (xy 0.22225 -0.09271) (xy 0.22479 -0.08128) (xy 0.22606 -0.07112) (xy 0.2286 -0.05969)
						(xy 0.2286 -0.01651) (xy 0.22606 -0.00508) (xy 0.22479 0.00508) (xy 0.22225 0.01651) (xy 0.21971 0.02667)
						(xy 0.20828 0.05715) (xy 0.19812 0.07747) (xy 0.19177 0.08636) (xy 0.18669 0.09525) (xy 0.17907 0.10414)
						(xy 0.17272 0.11303) (xy 0.1651 0.12065) (xy 0.1651 0.7366) (xy 0.16256 0.76835) (xy 0.1524 0.8001)
						(xy 0.13716 0.82804) (xy 0.11684 0.85344) (xy 0.09144 0.87376) (xy 0.0635 0.889) (xy 0.03175 0.89916)
					)
					(width 0)
					(fill yes)
				)
			)
		)
		(pad "148" smd custom
			(at 14.85011 -4.106672)
			(size 0.1143 0.1143)
			(layers "F.Cu" "F.Mask" "F.Paste")
			(net "M_B_DQ40")
			(options
				(clearance outline)
				(anchor circle)
			)
			(primitives
				(gr_poly
					(pts
						(xy 0 0.9017) (xy -0.03175 0.89916) (xy -0.0635 0.889) (xy -0.09144 0.87376) (xy -0.11684 0.85344)
						(xy -0.13716 0.82804) (xy -0.1524 0.8001) (xy -0.16256 0.76835) (xy -0.1651 0.7366) (xy -0.1651 0.19685)
						(xy -0.17272 0.18923) (xy -0.17907 0.18034) (xy -0.18669 0.17145) (xy -0.19177 0.16256) (xy -0.19812 0.15367)
						(xy -0.20828 0.13335) (xy -0.21971 0.10287) (xy -0.22225 0.09271) (xy -0.22479 0.08128) (xy -0.22606 0.07112)
						(xy -0.2286 0.05969) (xy -0.2286 0.01651) (xy -0.22606 0.00508) (xy -0.22479 -0.00508) (xy -0.22225 -0.01651)
						(xy -0.21971 -0.02667) (xy -0.20828 -0.05715) (xy -0.19812 -0.07747) (xy -0.19177 -0.08636) (xy -0.18669 -0.09525)
						(xy -0.17907 -0.10414) (xy -0.17272 -0.11303) (xy -0.1651 -0.12065) (xy -0.1651 -0.7366) (xy -0.16256 -0.76835)
						(xy -0.1524 -0.8001) (xy -0.13716 -0.82804) (xy -0.11684 -0.85344) (xy -0.09144 -0.87376) (xy -0.0635 -0.889)
						(xy -0.03175 -0.89916) (xy 0 -0.9017) (xy 0.03175 -0.89916) (xy 0.0635 -0.889) (xy 0.09144 -0.87376)
						(xy 0.11684 -0.85344) (xy 0.13716 -0.82804) (xy 0.1524 -0.8001) (xy 0.16256 -0.76835) (xy 0.1651 -0.7366)
						(xy 0.1651 -0.11938) (xy 0.17272 -0.11176) (xy 0.19812 -0.0762) (xy 0.2032 -0.06604) (xy 0.20701 -0.05715)
						(xy 0.21209 -0.04699) (xy 0.2159 -0.03683) (xy 0.21844 -0.02667) (xy 0.22225 -0.01524) (xy 0.22352 -0.00508)
						(xy 0.22606 0.00508) (xy 0.22733 0.01651) (xy 0.22733 0.02667) (xy 0.2286 0.0381) (xy 0.22733 0.04953)
						(xy 0.22733 0.05969) (xy 0.22606 0.07112) (xy 0.22352 0.08128) (xy 0.22225 0.09144) (xy 0.21844 0.10287)
						(xy 0.2159 0.11303) (xy 0.21209 0.12319) (xy 0.20701 0.13335) (xy 0.2032 0.14224) (xy 0.19812 0.1524)
						(xy 0.17272 0.18796) (xy 0.1651 0.19558) (xy 0.1651 0.7366) (xy 0.16256 0.76835) (xy 0.1524 0.8001)
						(xy 0.13716 0.82804) (xy 0.11684 0.85344) (xy 0.09144 0.87376) (xy 0.0635 0.889) (xy 0.03175 0.89916)
					)
					(width 0)
					(fill yes)
				)
			)
		)
		(pad "149" smd custom
			(at 15.150084 4.106672)
			(size 0.1143 0.1143)
			(layers "F.Cu" "F.Mask" "F.Paste")
			(net "GND")
			(options
				(clearance outline)
				(anchor circle)
			)
			(primitives
				(gr_poly
					(pts
						(xy 0 0.9017) (xy -0.03175 0.89916) (xy -0.0635 0.889) (xy -0.09144 0.87376) (xy -0.11684 0.85344)
						(xy -0.13716 0.82804) (xy -0.1524 0.8001) (xy -0.16256 0.76835) (xy -0.1651 0.7366) (xy -0.1651 -0.13462)
						(xy -0.17272 -0.14224) (xy -0.19812 -0.1778) (xy -0.2032 -0.18796) (xy -0.20701 -0.19685) (xy -0.21209 -0.20701)
						(xy -0.2159 -0.21717) (xy -0.21844 -0.22733) (xy -0.22225 -0.23876) (xy -0.22352 -0.24892) (xy -0.22606 -0.25908)
						(xy -0.22733 -0.27051) (xy -0.22733 -0.28067) (xy -0.2286 -0.2921) (xy -0.22733 -0.30353) (xy -0.22733 -0.31369)
						(xy -0.22606 -0.32512) (xy -0.22352 -0.33528) (xy -0.22225 -0.34544) (xy -0.21844 -0.35687) (xy -0.2159 -0.36703)
						(xy -0.21209 -0.37719) (xy -0.20701 -0.38735) (xy -0.2032 -0.39624) (xy -0.19812 -0.4064) (xy -0.17272 -0.44196)
						(xy -0.1651 -0.44958) (xy -0.1651 -0.7366) (xy -0.16256 -0.76835) (xy -0.1524 -0.8001) (xy -0.13716 -0.82804)
						(xy -0.11684 -0.85344) (xy -0.09144 -0.87376) (xy -0.0635 -0.889) (xy -0.03175 -0.89916) (xy 0 -0.9017)
						(xy 0.03175 -0.89916) (xy 0.0635 -0.889) (xy 0.09144 -0.87376) (xy 0.11684 -0.85344) (xy 0.13716 -0.82804)
						(xy 0.1524 -0.8001) (xy 0.16256 -0.76835) (xy 0.1651 -0.7366) (xy 0.1651 -0.44958) (xy 0.17272 -0.44196)
						(xy 0.19812 -0.4064) (xy 0.2032 -0.39624) (xy 0.20701 -0.38735) (xy 0.21209 -0.37719) (xy 0.2159 -0.36703)
						(xy 0.21844 -0.35687) (xy 0.22225 -0.34544) (xy 0.22352 -0.33528) (xy 0.22606 -0.32512) (xy 0.22733 -0.31369)
						(xy 0.22733 -0.30353) (xy 0.2286 -0.2921) (xy 0.22733 -0.28067) (xy 0.22733 -0.27051) (xy 0.22606 -0.25908)
						(xy 0.22352 -0.24892) (xy 0.22225 -0.23876) (xy 0.21844 -0.22733) (xy 0.2159 -0.21717) (xy 0.21209 -0.20701)
						(xy 0.20701 -0.19685) (xy 0.2032 -0.18796) (xy 0.19812 -0.1778) (xy 0.17272 -0.14224) (xy 0.1651 -0.13462)
						(xy 0.1651 0.7366) (xy 0.16256 0.76835) (xy 0.1524 0.8001) (xy 0.13716 0.82804) (xy 0.11684 0.85344)
						(xy 0.09144 0.87376) (xy 0.0635 0.889) (xy 0.03175 0.89916)
					)
					(width 0)
					(fill yes)
				)
			)
		)
		(pad "150" smd custom
			(at 15.450058 -4.106672)
			(size 0.1143 0.1143)
			(layers "F.Cu" "F.Mask" "F.Paste")
			(net "M_B_DQ41")
			(options
				(clearance outline)
				(anchor circle)
			)
			(primitives
				(gr_poly
					(pts
						(xy 0 0.9017) (xy -0.03175 0.89916) (xy -0.0635 0.889) (xy -0.09144 0.87376) (xy -0.11684 0.85344)
						(xy -0.13716 0.82804) (xy -0.1524 0.8001) (xy -0.16256 0.76835) (xy -0.1651 0.7366) (xy -0.1651 0.44958)
						(xy -0.17272 0.44196) (xy -0.19812 0.4064) (xy -0.2032 0.39624) (xy -0.20701 0.38735) (xy -0.21209 0.37719)
						(xy -0.2159 0.36703) (xy -0.21844 0.35687) (xy -0.22225 0.34544) (xy -0.22352 0.33528) (xy -0.22606 0.32512)
						(xy -0.22733 0.31369) (xy -0.22733 0.30353) (xy -0.2286 0.2921) (xy -0.22733 0.28067) (xy -0.22733 0.27051)
						(xy -0.22606 0.25908) (xy -0.22352 0.24892) (xy -0.22225 0.23876) (xy -0.21844 0.22733) (xy -0.2159 0.21717)
						(xy -0.21209 0.20701) (xy -0.20701 0.19685) (xy -0.2032 0.18796) (xy -0.19812 0.1778) (xy -0.17272 0.14224)
						(xy -0.1651 0.13462) (xy -0.1651 -0.7366) (xy -0.16256 -0.76835) (xy -0.1524 -0.8001) (xy -0.13716 -0.82804)
						(xy -0.11684 -0.85344) (xy -0.09144 -0.87376) (xy -0.0635 -0.889) (xy -0.03175 -0.89916) (xy 0 -0.9017)
						(xy 0.03175 -0.89916) (xy 0.0635 -0.889) (xy 0.09144 -0.87376) (xy 0.11684 -0.85344) (xy 0.13716 -0.82804)
						(xy 0.1524 -0.8001) (xy 0.16256 -0.76835) (xy 0.1651 -0.7366) (xy 0.1651 0.13462) (xy 0.17272 0.14224)
						(xy 0.19812 0.1778) (xy 0.2032 0.18796) (xy 0.20701 0.19685) (xy 0.21209 0.20701) (xy 0.2159 0.21717)
						(xy 0.21844 0.22733) (xy 0.22225 0.23876) (xy 0.22352 0.24892) (xy 0.22606 0.25908) (xy 0.22733 0.27051)
						(xy 0.22733 0.28067) (xy 0.2286 0.2921) (xy 0.22733 0.30353) (xy 0.22733 0.31369) (xy 0.22606 0.32512)
						(xy 0.22352 0.33528) (xy 0.22225 0.34544) (xy 0.21844 0.35687) (xy 0.2159 0.36703) (xy 0.21209 0.37719)
						(xy 0.20701 0.38735) (xy 0.2032 0.39624) (xy 0.19812 0.4064) (xy 0.17272 0.44196) (xy 0.1651 0.44958)
						(xy 0.1651 0.7366) (xy 0.16256 0.76835) (xy 0.1524 0.8001) (xy 0.13716 0.82804) (xy 0.11684 0.85344)
						(xy 0.09144 0.87376) (xy 0.0635 0.889) (xy 0.03175 0.89916)
					)
					(width 0)
					(fill yes)
				)
			)
		)
		(pad "151" smd custom
			(at 15.750032 4.106672)
			(size 0.1143 0.1143)
			(layers "F.Cu" "F.Mask" "F.Paste")
			(net "M_B_DQ44")
			(options
				(clearance outline)
				(anchor circle)
			)
			(primitives
				(gr_poly
					(pts
						(xy 0 0.9017) (xy -0.03175 0.89916) (xy -0.0635 0.889) (xy -0.09144 0.87376) (xy -0.11684 0.85344)
						(xy -0.13716 0.82804) (xy -0.1524 0.8001) (xy -0.16256 0.76835) (xy -0.1651 0.7366) (xy -0.1651 0.11938)
						(xy -0.17272 0.11176) (xy -0.19812 0.0762) (xy -0.2032 0.06604) (xy -0.20701 0.05715) (xy -0.21209 0.04699)
						(xy -0.2159 0.03683) (xy -0.21844 0.02667) (xy -0.22225 0.01524) (xy -0.22352 0.00508) (xy -0.22606 -0.00508)
						(xy -0.22733 -0.01651) (xy -0.22733 -0.02667) (xy -0.2286 -0.0381) (xy -0.22733 -0.04953) (xy -0.22733 -0.05969)
						(xy -0.22606 -0.07112) (xy -0.22352 -0.08128) (xy -0.22225 -0.09144) (xy -0.21844 -0.10287) (xy -0.2159 -0.11303)
						(xy -0.21209 -0.12319) (xy -0.20701 -0.13335) (xy -0.2032 -0.14224) (xy -0.19812 -0.1524) (xy -0.17272 -0.18796)
						(xy -0.1651 -0.19558) (xy -0.1651 -0.7366) (xy -0.16256 -0.76835) (xy -0.1524 -0.8001) (xy -0.13716 -0.82804)
						(xy -0.11684 -0.85344) (xy -0.09144 -0.87376) (xy -0.0635 -0.889) (xy -0.03175 -0.89916) (xy 0 -0.9017)
						(xy 0.03175 -0.89916) (xy 0.0635 -0.889) (xy 0.09144 -0.87376) (xy 0.11684 -0.85344) (xy 0.13716 -0.82804)
						(xy 0.1524 -0.8001) (xy 0.16256 -0.76835) (xy 0.1651 -0.7366) (xy 0.1651 -0.19685) (xy 0.17272 -0.18923)
						(xy 0.17907 -0.18034) (xy 0.18669 -0.17145) (xy 0.19177 -0.16256) (xy 0.19812 -0.15367) (xy 0.20828 -0.13335)
						(xy 0.21971 -0.10287) (xy 0.22225 -0.09271) (xy 0.22479 -0.08128) (xy 0.22606 -0.07112) (xy 0.2286 -0.05969)
						(xy 0.2286 -0.01651) (xy 0.22606 -0.00508) (xy 0.22479 0.00508) (xy 0.22225 0.01651) (xy 0.21971 0.02667)
						(xy 0.20828 0.05715) (xy 0.19812 0.07747) (xy 0.19177 0.08636) (xy 0.18669 0.09525) (xy 0.17907 0.10414)
						(xy 0.17272 0.11303) (xy 0.1651 0.12065) (xy 0.1651 0.7366) (xy 0.16256 0.76835) (xy 0.1524 0.8001)
						(xy 0.13716 0.82804) (xy 0.11684 0.85344) (xy 0.09144 0.87376) (xy 0.0635 0.889) (xy 0.03175 0.89916)
					)
					(width 0)
					(fill yes)
				)
			)
		)
		(pad "152" smd custom
			(at 16.050006 -4.106672)
			(size 0.1143 0.1143)
			(layers "F.Cu" "F.Mask" "F.Paste")
			(net "GND")
			(options
				(clearance outline)
				(anchor circle)
			)
			(primitives
				(gr_poly
					(pts
						(xy 0 0.9017) (xy -0.03175 0.89916) (xy -0.0635 0.889) (xy -0.09144 0.87376) (xy -0.11684 0.85344)
						(xy -0.13716 0.82804) (xy -0.1524 0.8001) (xy -0.16256 0.76835) (xy -0.1651 0.7366) (xy -0.1651 0.19685)
						(xy -0.17272 0.18923) (xy -0.17907 0.18034) (xy -0.18669 0.17145) (xy -0.19177 0.16256) (xy -0.19812 0.15367)
						(xy -0.20828 0.13335) (xy -0.21971 0.10287) (xy -0.22225 0.09271) (xy -0.22479 0.08128) (xy -0.22606 0.07112)
						(xy -0.2286 0.05969) (xy -0.2286 0.01651) (xy -0.22606 0.00508) (xy -0.22479 -0.00508) (xy -0.22225 -0.01651)
						(xy -0.21971 -0.02667) (xy -0.20828 -0.05715) (xy -0.19812 -0.07747) (xy -0.19177 -0.08636) (xy -0.18669 -0.09525)
						(xy -0.17907 -0.10414) (xy -0.17272 -0.11303) (xy -0.1651 -0.12065) (xy -0.1651 -0.7366) (xy -0.16256 -0.76835)
						(xy -0.1524 -0.8001) (xy -0.13716 -0.82804) (xy -0.11684 -0.85344) (xy -0.09144 -0.87376) (xy -0.0635 -0.889)
						(xy -0.03175 -0.89916) (xy 0 -0.9017) (xy 0.03175 -0.89916) (xy 0.0635 -0.889) (xy 0.09144 -0.87376)
						(xy 0.11684 -0.85344) (xy 0.13716 -0.82804) (xy 0.1524 -0.8001) (xy 0.16256 -0.76835) (xy 0.1651 -0.7366)
						(xy 0.1651 -0.11938) (xy 0.17272 -0.11176) (xy 0.19812 -0.0762) (xy 0.2032 -0.06604) (xy 0.20701 -0.05715)
						(xy 0.21209 -0.04699) (xy 0.2159 -0.03683) (xy 0.21844 -0.02667) (xy 0.22225 -0.01524) (xy 0.22352 -0.00508)
						(xy 0.22606 0.00508) (xy 0.22733 0.01651) (xy 0.22733 0.02667) (xy 0.2286 0.0381) (xy 0.22733 0.04953)
						(xy 0.22733 0.05969) (xy 0.22606 0.07112) (xy 0.22352 0.08128) (xy 0.22225 0.09144) (xy 0.21844 0.10287)
						(xy 0.2159 0.11303) (xy 0.21209 0.12319) (xy 0.20701 0.13335) (xy 0.2032 0.14224) (xy 0.19812 0.1524)
						(xy 0.17272 0.18796) (xy 0.1651 0.19558) (xy 0.1651 0.7366) (xy 0.16256 0.76835) (xy 0.1524 0.8001)
						(xy 0.13716 0.82804) (xy 0.11684 0.85344) (xy 0.09144 0.87376) (xy 0.0635 0.889) (xy 0.03175 0.89916)
					)
					(width 0)
					(fill yes)
				)
			)
		)
		(pad "153" smd custom
			(at 16.34998 4.106672)
			(size 0.1143 0.1143)
			(layers "F.Cu" "F.Mask" "F.Paste")
			(net "M_B_DQ45")
			(options
				(clearance outline)
				(anchor circle)
			)
			(primitives
				(gr_poly
					(pts
						(xy 0 0.9017) (xy -0.03175 0.89916) (xy -0.0635 0.889) (xy -0.09144 0.87376) (xy -0.11684 0.85344)
						(xy -0.13716 0.82804) (xy -0.1524 0.8001) (xy -0.16256 0.76835) (xy -0.1651 0.7366) (xy -0.1651 -0.13462)
						(xy -0.17272 -0.14224) (xy -0.19812 -0.1778) (xy -0.2032 -0.18796) (xy -0.20701 -0.19685) (xy -0.21209 -0.20701)
						(xy -0.2159 -0.21717) (xy -0.21844 -0.22733) (xy -0.22225 -0.23876) (xy -0.22352 -0.24892) (xy -0.22606 -0.25908)
						(xy -0.22733 -0.27051) (xy -0.22733 -0.28067) (xy -0.2286 -0.2921) (xy -0.22733 -0.30353) (xy -0.22733 -0.31369)
						(xy -0.22606 -0.32512) (xy -0.22352 -0.33528) (xy -0.22225 -0.34544) (xy -0.21844 -0.35687) (xy -0.2159 -0.36703)
						(xy -0.21209 -0.37719) (xy -0.20701 -0.38735) (xy -0.2032 -0.39624) (xy -0.19812 -0.4064) (xy -0.17272 -0.44196)
						(xy -0.1651 -0.44958) (xy -0.1651 -0.7366) (xy -0.16256 -0.76835) (xy -0.1524 -0.8001) (xy -0.13716 -0.82804)
						(xy -0.11684 -0.85344) (xy -0.09144 -0.87376) (xy -0.0635 -0.889) (xy -0.03175 -0.89916) (xy 0 -0.9017)
						(xy 0.03175 -0.89916) (xy 0.0635 -0.889) (xy 0.09144 -0.87376) (xy 0.11684 -0.85344) (xy 0.13716 -0.82804)
						(xy 0.1524 -0.8001) (xy 0.16256 -0.76835) (xy 0.1651 -0.7366) (xy 0.1651 -0.44958) (xy 0.17272 -0.44196)
						(xy 0.19812 -0.4064) (xy 0.2032 -0.39624) (xy 0.20701 -0.38735) (xy 0.21209 -0.37719) (xy 0.2159 -0.36703)
						(xy 0.21844 -0.35687) (xy 0.22225 -0.34544) (xy 0.22352 -0.33528) (xy 0.22606 -0.32512) (xy 0.22733 -0.31369)
						(xy 0.22733 -0.30353) (xy 0.2286 -0.2921) (xy 0.22733 -0.28067) (xy 0.22733 -0.27051) (xy 0.22606 -0.25908)
						(xy 0.22352 -0.24892) (xy 0.22225 -0.23876) (xy 0.21844 -0.22733) (xy 0.2159 -0.21717) (xy 0.21209 -0.20701)
						(xy 0.20701 -0.19685) (xy 0.2032 -0.18796) (xy 0.19812 -0.1778) (xy 0.17272 -0.14224) (xy 0.1651 -0.13462)
						(xy 0.1651 0.7366) (xy 0.16256 0.76835) (xy 0.1524 0.8001) (xy 0.13716 0.82804) (xy 0.11684 0.85344)
						(xy 0.09144 0.87376) (xy 0.0635 0.889) (xy 0.03175 0.89916)
					)
					(width 0)
					(fill yes)
				)
			)
		)
		(pad "154" smd custom
			(at 16.649954 -4.106672)
			(size 0.1143 0.1143)
			(layers "F.Cu" "F.Mask" "F.Paste")
			(net "M_B_DQS_DN5")
			(options
				(clearance outline)
				(anchor circle)
			)
			(primitives
				(gr_poly
					(pts
						(xy 0 0.9017) (xy -0.03175 0.89916) (xy -0.0635 0.889) (xy -0.09144 0.87376) (xy -0.11684 0.85344)
						(xy -0.13716 0.82804) (xy -0.1524 0.8001) (xy -0.16256 0.76835) (xy -0.1651 0.7366) (xy -0.1651 0.44958)
						(xy -0.17272 0.44196) (xy -0.19812 0.4064) (xy -0.2032 0.39624) (xy -0.20701 0.38735) (xy -0.21209 0.37719)
						(xy -0.2159 0.36703) (xy -0.21844 0.35687) (xy -0.22225 0.34544) (xy -0.22352 0.33528) (xy -0.22606 0.32512)
						(xy -0.22733 0.31369) (xy -0.22733 0.30353) (xy -0.2286 0.2921) (xy -0.22733 0.28067) (xy -0.22733 0.27051)
						(xy -0.22606 0.25908) (xy -0.22352 0.24892) (xy -0.22225 0.23876) (xy -0.21844 0.22733) (xy -0.2159 0.21717)
						(xy -0.21209 0.20701) (xy -0.20701 0.19685) (xy -0.2032 0.18796) (xy -0.19812 0.1778) (xy -0.17272 0.14224)
						(xy -0.1651 0.13462) (xy -0.1651 -0.7366) (xy -0.16256 -0.76835) (xy -0.1524 -0.8001) (xy -0.13716 -0.82804)
						(xy -0.11684 -0.85344) (xy -0.09144 -0.87376) (xy -0.0635 -0.889) (xy -0.03175 -0.89916) (xy 0 -0.9017)
						(xy 0.03175 -0.89916) (xy 0.0635 -0.889) (xy 0.09144 -0.87376) (xy 0.11684 -0.85344) (xy 0.13716 -0.82804)
						(xy 0.1524 -0.8001) (xy 0.16256 -0.76835) (xy 0.1651 -0.7366) (xy 0.1651 0.13462) (xy 0.17272 0.14224)
						(xy 0.19812 0.1778) (xy 0.2032 0.18796) (xy 0.20701 0.19685) (xy 0.21209 0.20701) (xy 0.2159 0.21717)
						(xy 0.21844 0.22733) (xy 0.22225 0.23876) (xy 0.22352 0.24892) (xy 0.22606 0.25908) (xy 0.22733 0.27051)
						(xy 0.22733 0.28067) (xy 0.2286 0.2921) (xy 0.22733 0.30353) (xy 0.22733 0.31369) (xy 0.22606 0.32512)
						(xy 0.22352 0.33528) (xy 0.22225 0.34544) (xy 0.21844 0.35687) (xy 0.2159 0.36703) (xy 0.21209 0.37719)
						(xy 0.20701 0.38735) (xy 0.2032 0.39624) (xy 0.19812 0.4064) (xy 0.17272 0.44196) (xy 0.1651 0.44958)
						(xy 0.1651 0.7366) (xy 0.16256 0.76835) (xy 0.1524 0.8001) (xy 0.13716 0.82804) (xy 0.11684 0.85344)
						(xy 0.09144 0.87376) (xy 0.0635 0.889) (xy 0.03175 0.89916)
					)
					(width 0)
					(fill yes)
				)
			)
		)
		(pad "155" smd custom
			(at 16.949928 4.106672)
			(size 0.1143 0.1143)
			(layers "F.Cu" "F.Mask" "F.Paste")
			(net "GND")
			(options
				(clearance outline)
				(anchor circle)
			)
			(primitives
				(gr_poly
					(pts
						(xy 0 0.9017) (xy -0.03175 0.89916) (xy -0.0635 0.889) (xy -0.09144 0.87376) (xy -0.11684 0.85344)
						(xy -0.13716 0.82804) (xy -0.1524 0.8001) (xy -0.16256 0.76835) (xy -0.1651 0.7366) (xy -0.1651 0.11938)
						(xy -0.17272 0.11176) (xy -0.19812 0.0762) (xy -0.2032 0.06604) (xy -0.20701 0.05715) (xy -0.21209 0.04699)
						(xy -0.2159 0.03683) (xy -0.21844 0.02667) (xy -0.22225 0.01524) (xy -0.22352 0.00508) (xy -0.22606 -0.00508)
						(xy -0.22733 -0.01651) (xy -0.22733 -0.02667) (xy -0.2286 -0.0381) (xy -0.22733 -0.04953) (xy -0.22733 -0.05969)
						(xy -0.22606 -0.07112) (xy -0.22352 -0.08128) (xy -0.22225 -0.09144) (xy -0.21844 -0.10287) (xy -0.2159 -0.11303)
						(xy -0.21209 -0.12319) (xy -0.20701 -0.13335) (xy -0.2032 -0.14224) (xy -0.19812 -0.1524) (xy -0.17272 -0.18796)
						(xy -0.1651 -0.19558) (xy -0.1651 -0.7366) (xy -0.16256 -0.76835) (xy -0.1524 -0.8001) (xy -0.13716 -0.82804)
						(xy -0.11684 -0.85344) (xy -0.09144 -0.87376) (xy -0.0635 -0.889) (xy -0.03175 -0.89916) (xy 0 -0.9017)
						(xy 0.03175 -0.89916) (xy 0.0635 -0.889) (xy 0.09144 -0.87376) (xy 0.11684 -0.85344) (xy 0.13716 -0.82804)
						(xy 0.1524 -0.8001) (xy 0.16256 -0.76835) (xy 0.1651 -0.7366) (xy 0.1651 -0.19685) (xy 0.17272 -0.18923)
						(xy 0.17907 -0.18034) (xy 0.18669 -0.17145) (xy 0.19177 -0.16256) (xy 0.19812 -0.15367) (xy 0.20828 -0.13335)
						(xy 0.21971 -0.10287) (xy 0.22225 -0.09271) (xy 0.22479 -0.08128) (xy 0.22606 -0.07112) (xy 0.2286 -0.05969)
						(xy 0.2286 -0.01651) (xy 0.22606 -0.00508) (xy 0.22479 0.00508) (xy 0.22225 0.01651) (xy 0.21971 0.02667)
						(xy 0.20828 0.05715) (xy 0.19812 0.07747) (xy 0.19177 0.08636) (xy 0.18669 0.09525) (xy 0.17907 0.10414)
						(xy 0.17272 0.11303) (xy 0.1651 0.12065) (xy 0.1651 0.7366) (xy 0.16256 0.76835) (xy 0.1524 0.8001)
						(xy 0.13716 0.82804) (xy 0.11684 0.85344) (xy 0.09144 0.87376) (xy 0.0635 0.889) (xy 0.03175 0.89916)
					)
					(width 0)
					(fill yes)
				)
			)
		)
		(pad "156" smd custom
			(at 17.249902 -4.106672)
			(size 0.1143 0.1143)
			(layers "F.Cu" "F.Mask" "F.Paste")
			(net "M_B_DQS_DP5")
			(options
				(clearance outline)
				(anchor circle)
			)
			(primitives
				(gr_poly
					(pts
						(xy 0 0.9017) (xy -0.03175 0.89916) (xy -0.0635 0.889) (xy -0.09144 0.87376) (xy -0.11684 0.85344)
						(xy -0.13716 0.82804) (xy -0.1524 0.8001) (xy -0.16256 0.76835) (xy -0.1651 0.7366) (xy -0.1651 0.19685)
						(xy -0.17272 0.18923) (xy -0.17907 0.18034) (xy -0.18669 0.17145) (xy -0.19177 0.16256) (xy -0.19812 0.15367)
						(xy -0.20828 0.13335) (xy -0.21971 0.10287) (xy -0.22225 0.09271) (xy -0.22479 0.08128) (xy -0.22606 0.07112)
						(xy -0.2286 0.05969) (xy -0.2286 0.01651) (xy -0.22606 0.00508) (xy -0.22479 -0.00508) (xy -0.22225 -0.01651)
						(xy -0.21971 -0.02667) (xy -0.20828 -0.05715) (xy -0.19812 -0.07747) (xy -0.19177 -0.08636) (xy -0.18669 -0.09525)
						(xy -0.17907 -0.10414) (xy -0.17272 -0.11303) (xy -0.1651 -0.12065) (xy -0.1651 -0.7366) (xy -0.16256 -0.76835)
						(xy -0.1524 -0.8001) (xy -0.13716 -0.82804) (xy -0.11684 -0.85344) (xy -0.09144 -0.87376) (xy -0.0635 -0.889)
						(xy -0.03175 -0.89916) (xy 0 -0.9017) (xy 0.03175 -0.89916) (xy 0.0635 -0.889) (xy 0.09144 -0.87376)
						(xy 0.11684 -0.85344) (xy 0.13716 -0.82804) (xy 0.1524 -0.8001) (xy 0.16256 -0.76835) (xy 0.1651 -0.7366)
						(xy 0.1651 -0.11938) (xy 0.17272 -0.11176) (xy 0.19812 -0.0762) (xy 0.2032 -0.06604) (xy 0.20701 -0.05715)
						(xy 0.21209 -0.04699) (xy 0.2159 -0.03683) (xy 0.21844 -0.02667) (xy 0.22225 -0.01524) (xy 0.22352 -0.00508)
						(xy 0.22606 0.00508) (xy 0.22733 0.01651) (xy 0.22733 0.02667) (xy 0.2286 0.0381) (xy 0.22733 0.04953)
						(xy 0.22733 0.05969) (xy 0.22606 0.07112) (xy 0.22352 0.08128) (xy 0.22225 0.09144) (xy 0.21844 0.10287)
						(xy 0.2159 0.11303) (xy 0.21209 0.12319) (xy 0.20701 0.13335) (xy 0.2032 0.14224) (xy 0.19812 0.1524)
						(xy 0.17272 0.18796) (xy 0.1651 0.19558) (xy 0.1651 0.7366) (xy 0.16256 0.76835) (xy 0.1524 0.8001)
						(xy 0.13716 0.82804) (xy 0.11684 0.85344) (xy 0.09144 0.87376) (xy 0.0635 0.889) (xy 0.03175 0.89916)
					)
					(width 0)
					(fill yes)
				)
			)
		)
		(pad "157" smd custom
			(at 17.549876 4.106672)
			(size 0.1143 0.1143)
			(layers "F.Cu" "F.Mask" "F.Paste")
			(net "GND")
			(options
				(clearance outline)
				(anchor circle)
			)
			(primitives
				(gr_poly
					(pts
						(xy 0 0.9017) (xy -0.03175 0.89916) (xy -0.0635 0.889) (xy -0.09144 0.87376) (xy -0.11684 0.85344)
						(xy -0.13716 0.82804) (xy -0.1524 0.8001) (xy -0.16256 0.76835) (xy -0.1651 0.7366) (xy -0.1651 -0.13462)
						(xy -0.17272 -0.14224) (xy -0.19812 -0.1778) (xy -0.2032 -0.18796) (xy -0.20701 -0.19685) (xy -0.21209 -0.20701)
						(xy -0.2159 -0.21717) (xy -0.21844 -0.22733) (xy -0.22225 -0.23876) (xy -0.22352 -0.24892) (xy -0.22606 -0.25908)
						(xy -0.22733 -0.27051) (xy -0.22733 -0.28067) (xy -0.2286 -0.2921) (xy -0.22733 -0.30353) (xy -0.22733 -0.31369)
						(xy -0.22606 -0.32512) (xy -0.22352 -0.33528) (xy -0.22225 -0.34544) (xy -0.21844 -0.35687) (xy -0.2159 -0.36703)
						(xy -0.21209 -0.37719) (xy -0.20701 -0.38735) (xy -0.2032 -0.39624) (xy -0.19812 -0.4064) (xy -0.17272 -0.44196)
						(xy -0.1651 -0.44958) (xy -0.1651 -0.7366) (xy -0.16256 -0.76835) (xy -0.1524 -0.8001) (xy -0.13716 -0.82804)
						(xy -0.11684 -0.85344) (xy -0.09144 -0.87376) (xy -0.0635 -0.889) (xy -0.03175 -0.89916) (xy 0 -0.9017)
						(xy 0.03175 -0.89916) (xy 0.0635 -0.889) (xy 0.09144 -0.87376) (xy 0.11684 -0.85344) (xy 0.13716 -0.82804)
						(xy 0.1524 -0.8001) (xy 0.16256 -0.76835) (xy 0.1651 -0.7366) (xy 0.1651 -0.44958) (xy 0.17272 -0.44196)
						(xy 0.19812 -0.4064) (xy 0.2032 -0.39624) (xy 0.20701 -0.38735) (xy 0.21209 -0.37719) (xy 0.2159 -0.36703)
						(xy 0.21844 -0.35687) (xy 0.22225 -0.34544) (xy 0.22352 -0.33528) (xy 0.22606 -0.32512) (xy 0.22733 -0.31369)
						(xy 0.22733 -0.30353) (xy 0.2286 -0.2921) (xy 0.22733 -0.28067) (xy 0.22733 -0.27051) (xy 0.22606 -0.25908)
						(xy 0.22352 -0.24892) (xy 0.22225 -0.23876) (xy 0.21844 -0.22733) (xy 0.2159 -0.21717) (xy 0.21209 -0.20701)
						(xy 0.20701 -0.19685) (xy 0.2032 -0.18796) (xy 0.19812 -0.1778) (xy 0.17272 -0.14224) (xy 0.1651 -0.13462)
						(xy 0.1651 0.7366) (xy 0.16256 0.76835) (xy 0.1524 0.8001) (xy 0.13716 0.82804) (xy 0.11684 0.85344)
						(xy 0.09144 0.87376) (xy 0.0635 0.889) (xy 0.03175 0.89916)
					)
					(width 0)
					(fill yes)
				)
			)
		)
		(pad "158" smd custom
			(at 17.850104 -4.106672)
			(size 0.1143 0.1143)
			(layers "F.Cu" "F.Mask" "F.Paste")
			(net "GND")
			(options
				(clearance outline)
				(anchor circle)
			)
			(primitives
				(gr_poly
					(pts
						(xy 0 0.9017) (xy -0.03175 0.89916) (xy -0.0635 0.889) (xy -0.09144 0.87376) (xy -0.11684 0.85344)
						(xy -0.13716 0.82804) (xy -0.1524 0.8001) (xy -0.16256 0.76835) (xy -0.1651 0.7366) (xy -0.1651 0.44958)
						(xy -0.17272 0.44196) (xy -0.19812 0.4064) (xy -0.2032 0.39624) (xy -0.20701 0.38735) (xy -0.21209 0.37719)
						(xy -0.2159 0.36703) (xy -0.21844 0.35687) (xy -0.22225 0.34544) (xy -0.22352 0.33528) (xy -0.22606 0.32512)
						(xy -0.22733 0.31369) (xy -0.22733 0.30353) (xy -0.2286 0.2921) (xy -0.22733 0.28067) (xy -0.22733 0.27051)
						(xy -0.22606 0.25908) (xy -0.22352 0.24892) (xy -0.22225 0.23876) (xy -0.21844 0.22733) (xy -0.2159 0.21717)
						(xy -0.21209 0.20701) (xy -0.20701 0.19685) (xy -0.2032 0.18796) (xy -0.19812 0.1778) (xy -0.17272 0.14224)
						(xy -0.1651 0.13462) (xy -0.1651 -0.7366) (xy -0.16256 -0.76835) (xy -0.1524 -0.8001) (xy -0.13716 -0.82804)
						(xy -0.11684 -0.85344) (xy -0.09144 -0.87376) (xy -0.0635 -0.889) (xy -0.03175 -0.89916) (xy 0 -0.9017)
						(xy 0.03175 -0.89916) (xy 0.0635 -0.889) (xy 0.09144 -0.87376) (xy 0.11684 -0.85344) (xy 0.13716 -0.82804)
						(xy 0.1524 -0.8001) (xy 0.16256 -0.76835) (xy 0.1651 -0.7366) (xy 0.1651 0.13462) (xy 0.17272 0.14224)
						(xy 0.19812 0.1778) (xy 0.2032 0.18796) (xy 0.20701 0.19685) (xy 0.21209 0.20701) (xy 0.2159 0.21717)
						(xy 0.21844 0.22733) (xy 0.22225 0.23876) (xy 0.22352 0.24892) (xy 0.22606 0.25908) (xy 0.22733 0.27051)
						(xy 0.22733 0.28067) (xy 0.2286 0.2921) (xy 0.22733 0.30353) (xy 0.22733 0.31369) (xy 0.22606 0.32512)
						(xy 0.22352 0.33528) (xy 0.22225 0.34544) (xy 0.21844 0.35687) (xy 0.2159 0.36703) (xy 0.21209 0.37719)
						(xy 0.20701 0.38735) (xy 0.2032 0.39624) (xy 0.19812 0.4064) (xy 0.17272 0.44196) (xy 0.1651 0.44958)
						(xy 0.1651 0.7366) (xy 0.16256 0.76835) (xy 0.1524 0.8001) (xy 0.13716 0.82804) (xy 0.11684 0.85344)
						(xy 0.09144 0.87376) (xy 0.0635 0.889) (xy 0.03175 0.89916)
					)
					(width 0)
					(fill yes)
				)
			)
		)
		(pad "159" smd custom
			(at 18.150078 4.106672)
			(size 0.1143 0.1143)
			(layers "F.Cu" "F.Mask" "F.Paste")
			(net "M_B_DQ46")
			(options
				(clearance outline)
				(anchor circle)
			)
			(primitives
				(gr_poly
					(pts
						(xy 0 0.9017) (xy -0.03175 0.89916) (xy -0.0635 0.889) (xy -0.09144 0.87376) (xy -0.11684 0.85344)
						(xy -0.13716 0.82804) (xy -0.1524 0.8001) (xy -0.16256 0.76835) (xy -0.1651 0.7366) (xy -0.1651 0.11938)
						(xy -0.17272 0.11176) (xy -0.19812 0.0762) (xy -0.2032 0.06604) (xy -0.20701 0.05715) (xy -0.21209 0.04699)
						(xy -0.2159 0.03683) (xy -0.21844 0.02667) (xy -0.22225 0.01524) (xy -0.22352 0.00508) (xy -0.22606 -0.00508)
						(xy -0.22733 -0.01651) (xy -0.22733 -0.02667) (xy -0.2286 -0.0381) (xy -0.22733 -0.04953) (xy -0.22733 -0.05969)
						(xy -0.22606 -0.07112) (xy -0.22352 -0.08128) (xy -0.22225 -0.09144) (xy -0.21844 -0.10287) (xy -0.2159 -0.11303)
						(xy -0.21209 -0.12319) (xy -0.20701 -0.13335) (xy -0.2032 -0.14224) (xy -0.19812 -0.1524) (xy -0.17272 -0.18796)
						(xy -0.1651 -0.19558) (xy -0.1651 -0.7366) (xy -0.16256 -0.76835) (xy -0.1524 -0.8001) (xy -0.13716 -0.82804)
						(xy -0.11684 -0.85344) (xy -0.09144 -0.87376) (xy -0.0635 -0.889) (xy -0.03175 -0.89916) (xy 0 -0.9017)
						(xy 0.03175 -0.89916) (xy 0.0635 -0.889) (xy 0.09144 -0.87376) (xy 0.11684 -0.85344) (xy 0.13716 -0.82804)
						(xy 0.1524 -0.8001) (xy 0.16256 -0.76835) (xy 0.1651 -0.7366) (xy 0.1651 -0.19685) (xy 0.17272 -0.18923)
						(xy 0.17907 -0.18034) (xy 0.18669 -0.17145) (xy 0.19177 -0.16256) (xy 0.19812 -0.15367) (xy 0.20828 -0.13335)
						(xy 0.21971 -0.10287) (xy 0.22225 -0.09271) (xy 0.22479 -0.08128) (xy 0.22606 -0.07112) (xy 0.2286 -0.05969)
						(xy 0.2286 -0.01651) (xy 0.22606 -0.00508) (xy 0.22479 0.00508) (xy 0.22225 0.01651) (xy 0.21971 0.02667)
						(xy 0.20828 0.05715) (xy 0.19812 0.07747) (xy 0.19177 0.08636) (xy 0.18669 0.09525) (xy 0.17907 0.10414)
						(xy 0.17272 0.11303) (xy 0.1651 0.12065) (xy 0.1651 0.7366) (xy 0.16256 0.76835) (xy 0.1524 0.8001)
						(xy 0.13716 0.82804) (xy 0.11684 0.85344) (xy 0.09144 0.87376) (xy 0.0635 0.889) (xy 0.03175 0.89916)
					)
					(width 0)
					(fill yes)
				)
			)
		)
		(pad "160" smd custom
			(at 18.450052 -4.106672)
			(size 0.1143 0.1143)
			(layers "F.Cu" "F.Mask" "F.Paste")
			(net "M_B_DQ42")
			(options
				(clearance outline)
				(anchor circle)
			)
			(primitives
				(gr_poly
					(pts
						(xy 0 0.9017) (xy -0.03175 0.89916) (xy -0.0635 0.889) (xy -0.09144 0.87376) (xy -0.11684 0.85344)
						(xy -0.13716 0.82804) (xy -0.1524 0.8001) (xy -0.16256 0.76835) (xy -0.1651 0.7366) (xy -0.1651 0.19685)
						(xy -0.17272 0.18923) (xy -0.17907 0.18034) (xy -0.18669 0.17145) (xy -0.19177 0.16256) (xy -0.19812 0.15367)
						(xy -0.20828 0.13335) (xy -0.21971 0.10287) (xy -0.22225 0.09271) (xy -0.22479 0.08128) (xy -0.22606 0.07112)
						(xy -0.2286 0.05969) (xy -0.2286 0.01651) (xy -0.22606 0.00508) (xy -0.22479 -0.00508) (xy -0.22225 -0.01651)
						(xy -0.21971 -0.02667) (xy -0.20828 -0.05715) (xy -0.19812 -0.07747) (xy -0.19177 -0.08636) (xy -0.18669 -0.09525)
						(xy -0.17907 -0.10414) (xy -0.17272 -0.11303) (xy -0.1651 -0.12065) (xy -0.1651 -0.7366) (xy -0.16256 -0.76835)
						(xy -0.1524 -0.8001) (xy -0.13716 -0.82804) (xy -0.11684 -0.85344) (xy -0.09144 -0.87376) (xy -0.0635 -0.889)
						(xy -0.03175 -0.89916) (xy 0 -0.9017) (xy 0.03175 -0.89916) (xy 0.0635 -0.889) (xy 0.09144 -0.87376)
						(xy 0.11684 -0.85344) (xy 0.13716 -0.82804) (xy 0.1524 -0.8001) (xy 0.16256 -0.76835) (xy 0.1651 -0.7366)
						(xy 0.1651 -0.11938) (xy 0.17272 -0.11176) (xy 0.19812 -0.0762) (xy 0.2032 -0.06604) (xy 0.20701 -0.05715)
						(xy 0.21209 -0.04699) (xy 0.2159 -0.03683) (xy 0.21844 -0.02667) (xy 0.22225 -0.01524) (xy 0.22352 -0.00508)
						(xy 0.22606 0.00508) (xy 0.22733 0.01651) (xy 0.22733 0.02667) (xy 0.2286 0.0381) (xy 0.22733 0.04953)
						(xy 0.22733 0.05969) (xy 0.22606 0.07112) (xy 0.22352 0.08128) (xy 0.22225 0.09144) (xy 0.21844 0.10287)
						(xy 0.2159 0.11303) (xy 0.21209 0.12319) (xy 0.20701 0.13335) (xy 0.2032 0.14224) (xy 0.19812 0.1524)
						(xy 0.17272 0.18796) (xy 0.1651 0.19558) (xy 0.1651 0.7366) (xy 0.16256 0.76835) (xy 0.1524 0.8001)
						(xy 0.13716 0.82804) (xy 0.11684 0.85344) (xy 0.09144 0.87376) (xy 0.0635 0.889) (xy 0.03175 0.89916)
					)
					(width 0)
					(fill yes)
				)
			)
		)
		(pad "161" smd custom
			(at 18.750026 4.106672)
			(size 0.1143 0.1143)
			(layers "F.Cu" "F.Mask" "F.Paste")
			(net "M_B_DQ47")
			(options
				(clearance outline)
				(anchor circle)
			)
			(primitives
				(gr_poly
					(pts
						(xy 0 0.9017) (xy -0.03175 0.89916) (xy -0.0635 0.889) (xy -0.09144 0.87376) (xy -0.11684 0.85344)
						(xy -0.13716 0.82804) (xy -0.1524 0.8001) (xy -0.16256 0.76835) (xy -0.1651 0.7366) (xy -0.1651 -0.13462)
						(xy -0.17272 -0.14224) (xy -0.19812 -0.1778) (xy -0.2032 -0.18796) (xy -0.20701 -0.19685) (xy -0.21209 -0.20701)
						(xy -0.2159 -0.21717) (xy -0.21844 -0.22733) (xy -0.22225 -0.23876) (xy -0.22352 -0.24892) (xy -0.22606 -0.25908)
						(xy -0.22733 -0.27051) (xy -0.22733 -0.28067) (xy -0.2286 -0.2921) (xy -0.22733 -0.30353) (xy -0.22733 -0.31369)
						(xy -0.22606 -0.32512) (xy -0.22352 -0.33528) (xy -0.22225 -0.34544) (xy -0.21844 -0.35687) (xy -0.2159 -0.36703)
						(xy -0.21209 -0.37719) (xy -0.20701 -0.38735) (xy -0.2032 -0.39624) (xy -0.19812 -0.4064) (xy -0.17272 -0.44196)
						(xy -0.1651 -0.44958) (xy -0.1651 -0.7366) (xy -0.16256 -0.76835) (xy -0.1524 -0.8001) (xy -0.13716 -0.82804)
						(xy -0.11684 -0.85344) (xy -0.09144 -0.87376) (xy -0.0635 -0.889) (xy -0.03175 -0.89916) (xy 0 -0.9017)
						(xy 0.03175 -0.89916) (xy 0.0635 -0.889) (xy 0.09144 -0.87376) (xy 0.11684 -0.85344) (xy 0.13716 -0.82804)
						(xy 0.1524 -0.8001) (xy 0.16256 -0.76835) (xy 0.1651 -0.7366) (xy 0.1651 -0.44958) (xy 0.17272 -0.44196)
						(xy 0.19812 -0.4064) (xy 0.2032 -0.39624) (xy 0.20701 -0.38735) (xy 0.21209 -0.37719) (xy 0.2159 -0.36703)
						(xy 0.21844 -0.35687) (xy 0.22225 -0.34544) (xy 0.22352 -0.33528) (xy 0.22606 -0.32512) (xy 0.22733 -0.31369)
						(xy 0.22733 -0.30353) (xy 0.2286 -0.2921) (xy 0.22733 -0.28067) (xy 0.22733 -0.27051) (xy 0.22606 -0.25908)
						(xy 0.22352 -0.24892) (xy 0.22225 -0.23876) (xy 0.21844 -0.22733) (xy 0.2159 -0.21717) (xy 0.21209 -0.20701)
						(xy 0.20701 -0.19685) (xy 0.2032 -0.18796) (xy 0.19812 -0.1778) (xy 0.17272 -0.14224) (xy 0.1651 -0.13462)
						(xy 0.1651 0.7366) (xy 0.16256 0.76835) (xy 0.1524 0.8001) (xy 0.13716 0.82804) (xy 0.11684 0.85344)
						(xy 0.09144 0.87376) (xy 0.0635 0.889) (xy 0.03175 0.89916)
					)
					(width 0)
					(fill yes)
				)
			)
		)
		(pad "162" smd custom
			(at 19.05 -4.106672)
			(size 0.1143 0.1143)
			(layers "F.Cu" "F.Mask" "F.Paste")
			(net "M_B_DQ43")
			(options
				(clearance outline)
				(anchor circle)
			)
			(primitives
				(gr_poly
					(pts
						(xy 0 0.9017) (xy -0.03175 0.89916) (xy -0.0635 0.889) (xy -0.09144 0.87376) (xy -0.11684 0.85344)
						(xy -0.13716 0.82804) (xy -0.1524 0.8001) (xy -0.16256 0.76835) (xy -0.1651 0.7366) (xy -0.1651 0.44958)
						(xy -0.17272 0.44196) (xy -0.19812 0.4064) (xy -0.2032 0.39624) (xy -0.20701 0.38735) (xy -0.21209 0.37719)
						(xy -0.2159 0.36703) (xy -0.21844 0.35687) (xy -0.22225 0.34544) (xy -0.22352 0.33528) (xy -0.22606 0.32512)
						(xy -0.22733 0.31369) (xy -0.22733 0.30353) (xy -0.2286 0.2921) (xy -0.22733 0.28067) (xy -0.22733 0.27051)
						(xy -0.22606 0.25908) (xy -0.22352 0.24892) (xy -0.22225 0.23876) (xy -0.21844 0.22733) (xy -0.2159 0.21717)
						(xy -0.21209 0.20701) (xy -0.20701 0.19685) (xy -0.2032 0.18796) (xy -0.19812 0.1778) (xy -0.17272 0.14224)
						(xy -0.1651 0.13462) (xy -0.1651 -0.7366) (xy -0.16256 -0.76835) (xy -0.1524 -0.8001) (xy -0.13716 -0.82804)
						(xy -0.11684 -0.85344) (xy -0.09144 -0.87376) (xy -0.0635 -0.889) (xy -0.03175 -0.89916) (xy 0 -0.9017)
						(xy 0.03175 -0.89916) (xy 0.0635 -0.889) (xy 0.09144 -0.87376) (xy 0.11684 -0.85344) (xy 0.13716 -0.82804)
						(xy 0.1524 -0.8001) (xy 0.16256 -0.76835) (xy 0.1651 -0.7366) (xy 0.1651 0.13462) (xy 0.17272 0.14224)
						(xy 0.19812 0.1778) (xy 0.2032 0.18796) (xy 0.20701 0.19685) (xy 0.21209 0.20701) (xy 0.2159 0.21717)
						(xy 0.21844 0.22733) (xy 0.22225 0.23876) (xy 0.22352 0.24892) (xy 0.22606 0.25908) (xy 0.22733 0.27051)
						(xy 0.22733 0.28067) (xy 0.2286 0.2921) (xy 0.22733 0.30353) (xy 0.22733 0.31369) (xy 0.22606 0.32512)
						(xy 0.22352 0.33528) (xy 0.22225 0.34544) (xy 0.21844 0.35687) (xy 0.2159 0.36703) (xy 0.21209 0.37719)
						(xy 0.20701 0.38735) (xy 0.2032 0.39624) (xy 0.19812 0.4064) (xy 0.17272 0.44196) (xy 0.1651 0.44958)
						(xy 0.1651 0.7366) (xy 0.16256 0.76835) (xy 0.1524 0.8001) (xy 0.13716 0.82804) (xy 0.11684 0.85344)
						(xy 0.09144 0.87376) (xy 0.0635 0.889) (xy 0.03175 0.89916)
					)
					(width 0)
					(fill yes)
				)
			)
		)
		(pad "163" smd custom
			(at 19.349974 4.106672)
			(size 0.1143 0.1143)
			(layers "F.Cu" "F.Mask" "F.Paste")
			(net "GND")
			(options
				(clearance outline)
				(anchor circle)
			)
			(primitives
				(gr_poly
					(pts
						(xy 0 0.9017) (xy -0.03175 0.89916) (xy -0.0635 0.889) (xy -0.09144 0.87376) (xy -0.11684 0.85344)
						(xy -0.13716 0.82804) (xy -0.1524 0.8001) (xy -0.16256 0.76835) (xy -0.1651 0.7366) (xy -0.1651 0.11938)
						(xy -0.17272 0.11176) (xy -0.19812 0.0762) (xy -0.2032 0.06604) (xy -0.20701 0.05715) (xy -0.21209 0.04699)
						(xy -0.2159 0.03683) (xy -0.21844 0.02667) (xy -0.22225 0.01524) (xy -0.22352 0.00508) (xy -0.22606 -0.00508)
						(xy -0.22733 -0.01651) (xy -0.22733 -0.02667) (xy -0.2286 -0.0381) (xy -0.22733 -0.04953) (xy -0.22733 -0.05969)
						(xy -0.22606 -0.07112) (xy -0.22352 -0.08128) (xy -0.22225 -0.09144) (xy -0.21844 -0.10287) (xy -0.2159 -0.11303)
						(xy -0.21209 -0.12319) (xy -0.20701 -0.13335) (xy -0.2032 -0.14224) (xy -0.19812 -0.1524) (xy -0.17272 -0.18796)
						(xy -0.1651 -0.19558) (xy -0.1651 -0.7366) (xy -0.16256 -0.76835) (xy -0.1524 -0.8001) (xy -0.13716 -0.82804)
						(xy -0.11684 -0.85344) (xy -0.09144 -0.87376) (xy -0.0635 -0.889) (xy -0.03175 -0.89916) (xy 0 -0.9017)
						(xy 0.03175 -0.89916) (xy 0.0635 -0.889) (xy 0.09144 -0.87376) (xy 0.11684 -0.85344) (xy 0.13716 -0.82804)
						(xy 0.1524 -0.8001) (xy 0.16256 -0.76835) (xy 0.1651 -0.7366) (xy 0.1651 -0.19685) (xy 0.17272 -0.18923)
						(xy 0.17907 -0.18034) (xy 0.18669 -0.17145) (xy 0.19177 -0.16256) (xy 0.19812 -0.15367) (xy 0.20828 -0.13335)
						(xy 0.21971 -0.10287) (xy 0.22225 -0.09271) (xy 0.22479 -0.08128) (xy 0.22606 -0.07112) (xy 0.2286 -0.05969)
						(xy 0.2286 -0.01651) (xy 0.22606 -0.00508) (xy 0.22479 0.00508) (xy 0.22225 0.01651) (xy 0.21971 0.02667)
						(xy 0.20828 0.05715) (xy 0.19812 0.07747) (xy 0.19177 0.08636) (xy 0.18669 0.09525) (xy 0.17907 0.10414)
						(xy 0.17272 0.11303) (xy 0.1651 0.12065) (xy 0.1651 0.7366) (xy 0.16256 0.76835) (xy 0.1524 0.8001)
						(xy 0.13716 0.82804) (xy 0.11684 0.85344) (xy 0.09144 0.87376) (xy 0.0635 0.889) (xy 0.03175 0.89916)
					)
					(width 0)
					(fill yes)
				)
			)
		)
		(pad "164" smd custom
			(at 19.649948 -4.106672)
			(size 0.1143 0.1143)
			(layers "F.Cu" "F.Mask" "F.Paste")
			(net "GND")
			(options
				(clearance outline)
				(anchor circle)
			)
			(primitives
				(gr_poly
					(pts
						(xy 0 0.9017) (xy -0.03175 0.89916) (xy -0.0635 0.889) (xy -0.09144 0.87376) (xy -0.11684 0.85344)
						(xy -0.13716 0.82804) (xy -0.1524 0.8001) (xy -0.16256 0.76835) (xy -0.1651 0.7366) (xy -0.1651 0.19685)
						(xy -0.17272 0.18923) (xy -0.17907 0.18034) (xy -0.18669 0.17145) (xy -0.19177 0.16256) (xy -0.19812 0.15367)
						(xy -0.20828 0.13335) (xy -0.21971 0.10287) (xy -0.22225 0.09271) (xy -0.22479 0.08128) (xy -0.22606 0.07112)
						(xy -0.2286 0.05969) (xy -0.2286 0.01651) (xy -0.22606 0.00508) (xy -0.22479 -0.00508) (xy -0.22225 -0.01651)
						(xy -0.21971 -0.02667) (xy -0.20828 -0.05715) (xy -0.19812 -0.07747) (xy -0.19177 -0.08636) (xy -0.18669 -0.09525)
						(xy -0.17907 -0.10414) (xy -0.17272 -0.11303) (xy -0.1651 -0.12065) (xy -0.1651 -0.7366) (xy -0.16256 -0.76835)
						(xy -0.1524 -0.8001) (xy -0.13716 -0.82804) (xy -0.11684 -0.85344) (xy -0.09144 -0.87376) (xy -0.0635 -0.889)
						(xy -0.03175 -0.89916) (xy 0 -0.9017) (xy 0.03175 -0.89916) (xy 0.0635 -0.889) (xy 0.09144 -0.87376)
						(xy 0.11684 -0.85344) (xy 0.13716 -0.82804) (xy 0.1524 -0.8001) (xy 0.16256 -0.76835) (xy 0.1651 -0.7366)
						(xy 0.1651 -0.11938) (xy 0.17272 -0.11176) (xy 0.19812 -0.0762) (xy 0.2032 -0.06604) (xy 0.20701 -0.05715)
						(xy 0.21209 -0.04699) (xy 0.2159 -0.03683) (xy 0.21844 -0.02667) (xy 0.22225 -0.01524) (xy 0.22352 -0.00508)
						(xy 0.22606 0.00508) (xy 0.22733 0.01651) (xy 0.22733 0.02667) (xy 0.2286 0.0381) (xy 0.22733 0.04953)
						(xy 0.22733 0.05969) (xy 0.22606 0.07112) (xy 0.22352 0.08128) (xy 0.22225 0.09144) (xy 0.21844 0.10287)
						(xy 0.2159 0.11303) (xy 0.21209 0.12319) (xy 0.20701 0.13335) (xy 0.2032 0.14224) (xy 0.19812 0.1524)
						(xy 0.17272 0.18796) (xy 0.1651 0.19558) (xy 0.1651 0.7366) (xy 0.16256 0.76835) (xy 0.1524 0.8001)
						(xy 0.13716 0.82804) (xy 0.11684 0.85344) (xy 0.09144 0.87376) (xy 0.0635 0.889) (xy 0.03175 0.89916)
					)
					(width 0)
					(fill yes)
				)
			)
		)
		(pad "165" smd custom
			(at 19.949922 4.106672)
			(size 0.1143 0.1143)
			(layers "F.Cu" "F.Mask" "F.Paste")
			(net "M_B_DQ52")
			(options
				(clearance outline)
				(anchor circle)
			)
			(primitives
				(gr_poly
					(pts
						(xy 0 0.9017) (xy -0.03175 0.89916) (xy -0.0635 0.889) (xy -0.09144 0.87376) (xy -0.11684 0.85344)
						(xy -0.13716 0.82804) (xy -0.1524 0.8001) (xy -0.16256 0.76835) (xy -0.1651 0.7366) (xy -0.1651 -0.13462)
						(xy -0.17272 -0.14224) (xy -0.19812 -0.1778) (xy -0.2032 -0.18796) (xy -0.20701 -0.19685) (xy -0.21209 -0.20701)
						(xy -0.2159 -0.21717) (xy -0.21844 -0.22733) (xy -0.22225 -0.23876) (xy -0.22352 -0.24892) (xy -0.22606 -0.25908)
						(xy -0.22733 -0.27051) (xy -0.22733 -0.28067) (xy -0.2286 -0.2921) (xy -0.22733 -0.30353) (xy -0.22733 -0.31369)
						(xy -0.22606 -0.32512) (xy -0.22352 -0.33528) (xy -0.22225 -0.34544) (xy -0.21844 -0.35687) (xy -0.2159 -0.36703)
						(xy -0.21209 -0.37719) (xy -0.20701 -0.38735) (xy -0.2032 -0.39624) (xy -0.19812 -0.4064) (xy -0.17272 -0.44196)
						(xy -0.1651 -0.44958) (xy -0.1651 -0.7366) (xy -0.16256 -0.76835) (xy -0.1524 -0.8001) (xy -0.13716 -0.82804)
						(xy -0.11684 -0.85344) (xy -0.09144 -0.87376) (xy -0.0635 -0.889) (xy -0.03175 -0.89916) (xy 0 -0.9017)
						(xy 0.03175 -0.89916) (xy 0.0635 -0.889) (xy 0.09144 -0.87376) (xy 0.11684 -0.85344) (xy 0.13716 -0.82804)
						(xy 0.1524 -0.8001) (xy 0.16256 -0.76835) (xy 0.1651 -0.7366) (xy 0.1651 -0.44958) (xy 0.17272 -0.44196)
						(xy 0.19812 -0.4064) (xy 0.2032 -0.39624) (xy 0.20701 -0.38735) (xy 0.21209 -0.37719) (xy 0.2159 -0.36703)
						(xy 0.21844 -0.35687) (xy 0.22225 -0.34544) (xy 0.22352 -0.33528) (xy 0.22606 -0.32512) (xy 0.22733 -0.31369)
						(xy 0.22733 -0.30353) (xy 0.2286 -0.2921) (xy 0.22733 -0.28067) (xy 0.22733 -0.27051) (xy 0.22606 -0.25908)
						(xy 0.22352 -0.24892) (xy 0.22225 -0.23876) (xy 0.21844 -0.22733) (xy 0.2159 -0.21717) (xy 0.21209 -0.20701)
						(xy 0.20701 -0.19685) (xy 0.2032 -0.18796) (xy 0.19812 -0.1778) (xy 0.17272 -0.14224) (xy 0.1651 -0.13462)
						(xy 0.1651 0.7366) (xy 0.16256 0.76835) (xy 0.1524 0.8001) (xy 0.13716 0.82804) (xy 0.11684 0.85344)
						(xy 0.09144 0.87376) (xy 0.0635 0.889) (xy 0.03175 0.89916)
					)
					(width 0)
					(fill yes)
				)
			)
		)
		(pad "166" smd custom
			(at 20.249896 -4.106672)
			(size 0.1143 0.1143)
			(layers "F.Cu" "F.Mask" "F.Paste")
			(net "M_B_DQ48")
			(options
				(clearance outline)
				(anchor circle)
			)
			(primitives
				(gr_poly
					(pts
						(xy 0 0.9017) (xy -0.03175 0.89916) (xy -0.0635 0.889) (xy -0.09144 0.87376) (xy -0.11684 0.85344)
						(xy -0.13716 0.82804) (xy -0.1524 0.8001) (xy -0.16256 0.76835) (xy -0.1651 0.7366) (xy -0.1651 0.44958)
						(xy -0.17272 0.44196) (xy -0.19812 0.4064) (xy -0.2032 0.39624) (xy -0.20701 0.38735) (xy -0.21209 0.37719)
						(xy -0.2159 0.36703) (xy -0.21844 0.35687) (xy -0.22225 0.34544) (xy -0.22352 0.33528) (xy -0.22606 0.32512)
						(xy -0.22733 0.31369) (xy -0.22733 0.30353) (xy -0.2286 0.2921) (xy -0.22733 0.28067) (xy -0.22733 0.27051)
						(xy -0.22606 0.25908) (xy -0.22352 0.24892) (xy -0.22225 0.23876) (xy -0.21844 0.22733) (xy -0.2159 0.21717)
						(xy -0.21209 0.20701) (xy -0.20701 0.19685) (xy -0.2032 0.18796) (xy -0.19812 0.1778) (xy -0.17272 0.14224)
						(xy -0.1651 0.13462) (xy -0.1651 -0.7366) (xy -0.16256 -0.76835) (xy -0.1524 -0.8001) (xy -0.13716 -0.82804)
						(xy -0.11684 -0.85344) (xy -0.09144 -0.87376) (xy -0.0635 -0.889) (xy -0.03175 -0.89916) (xy 0 -0.9017)
						(xy 0.03175 -0.89916) (xy 0.0635 -0.889) (xy 0.09144 -0.87376) (xy 0.11684 -0.85344) (xy 0.13716 -0.82804)
						(xy 0.1524 -0.8001) (xy 0.16256 -0.76835) (xy 0.1651 -0.7366) (xy 0.1651 0.13462) (xy 0.17272 0.14224)
						(xy 0.19812 0.1778) (xy 0.2032 0.18796) (xy 0.20701 0.19685) (xy 0.21209 0.20701) (xy 0.2159 0.21717)
						(xy 0.21844 0.22733) (xy 0.22225 0.23876) (xy 0.22352 0.24892) (xy 0.22606 0.25908) (xy 0.22733 0.27051)
						(xy 0.22733 0.28067) (xy 0.2286 0.2921) (xy 0.22733 0.30353) (xy 0.22733 0.31369) (xy 0.22606 0.32512)
						(xy 0.22352 0.33528) (xy 0.22225 0.34544) (xy 0.21844 0.35687) (xy 0.2159 0.36703) (xy 0.21209 0.37719)
						(xy 0.20701 0.38735) (xy 0.2032 0.39624) (xy 0.19812 0.4064) (xy 0.17272 0.44196) (xy 0.1651 0.44958)
						(xy 0.1651 0.7366) (xy 0.16256 0.76835) (xy 0.1524 0.8001) (xy 0.13716 0.82804) (xy 0.11684 0.85344)
						(xy 0.09144 0.87376) (xy 0.0635 0.889) (xy 0.03175 0.89916)
					)
					(width 0)
					(fill yes)
				)
			)
		)
		(pad "167" smd custom
			(at 20.550124 4.106672)
			(size 0.1143 0.1143)
			(layers "F.Cu" "F.Mask" "F.Paste")
			(net "M_B_DQ53")
			(options
				(clearance outline)
				(anchor circle)
			)
			(primitives
				(gr_poly
					(pts
						(xy 0 0.9017) (xy -0.03175 0.89916) (xy -0.0635 0.889) (xy -0.09144 0.87376) (xy -0.11684 0.85344)
						(xy -0.13716 0.82804) (xy -0.1524 0.8001) (xy -0.16256 0.76835) (xy -0.1651 0.7366) (xy -0.1651 0.11938)
						(xy -0.17272 0.11176) (xy -0.19812 0.0762) (xy -0.2032 0.06604) (xy -0.20701 0.05715) (xy -0.21209 0.04699)
						(xy -0.2159 0.03683) (xy -0.21844 0.02667) (xy -0.22225 0.01524) (xy -0.22352 0.00508) (xy -0.22606 -0.00508)
						(xy -0.22733 -0.01651) (xy -0.22733 -0.02667) (xy -0.2286 -0.0381) (xy -0.22733 -0.04953) (xy -0.22733 -0.05969)
						(xy -0.22606 -0.07112) (xy -0.22352 -0.08128) (xy -0.22225 -0.09144) (xy -0.21844 -0.10287) (xy -0.2159 -0.11303)
						(xy -0.21209 -0.12319) (xy -0.20701 -0.13335) (xy -0.2032 -0.14224) (xy -0.19812 -0.1524) (xy -0.17272 -0.18796)
						(xy -0.1651 -0.19558) (xy -0.1651 -0.7366) (xy -0.16256 -0.76835) (xy -0.1524 -0.8001) (xy -0.13716 -0.82804)
						(xy -0.11684 -0.85344) (xy -0.09144 -0.87376) (xy -0.0635 -0.889) (xy -0.03175 -0.89916) (xy 0 -0.9017)
						(xy 0.03175 -0.89916) (xy 0.0635 -0.889) (xy 0.09144 -0.87376) (xy 0.11684 -0.85344) (xy 0.13716 -0.82804)
						(xy 0.1524 -0.8001) (xy 0.16256 -0.76835) (xy 0.1651 -0.7366) (xy 0.1651 -0.19685) (xy 0.17272 -0.18923)
						(xy 0.17907 -0.18034) (xy 0.18669 -0.17145) (xy 0.19177 -0.16256) (xy 0.19812 -0.15367) (xy 0.20828 -0.13335)
						(xy 0.21971 -0.10287) (xy 0.22225 -0.09271) (xy 0.22479 -0.08128) (xy 0.22606 -0.07112) (xy 0.2286 -0.05969)
						(xy 0.2286 -0.01651) (xy 0.22606 -0.00508) (xy 0.22479 0.00508) (xy 0.22225 0.01651) (xy 0.21971 0.02667)
						(xy 0.20828 0.05715) (xy 0.19812 0.07747) (xy 0.19177 0.08636) (xy 0.18669 0.09525) (xy 0.17907 0.10414)
						(xy 0.17272 0.11303) (xy 0.1651 0.12065) (xy 0.1651 0.7366) (xy 0.16256 0.76835) (xy 0.1524 0.8001)
						(xy 0.13716 0.82804) (xy 0.11684 0.85344) (xy 0.09144 0.87376) (xy 0.0635 0.889) (xy 0.03175 0.89916)
					)
					(width 0)
					(fill yes)
				)
			)
		)
		(pad "168" smd custom
			(at 20.850098 -4.106672)
			(size 0.1143 0.1143)
			(layers "F.Cu" "F.Mask" "F.Paste")
			(net "M_B_DQ49")
			(options
				(clearance outline)
				(anchor circle)
			)
			(primitives
				(gr_poly
					(pts
						(xy 0 0.9017) (xy -0.03175 0.89916) (xy -0.0635 0.889) (xy -0.09144 0.87376) (xy -0.11684 0.85344)
						(xy -0.13716 0.82804) (xy -0.1524 0.8001) (xy -0.16256 0.76835) (xy -0.1651 0.7366) (xy -0.1651 0.19685)
						(xy -0.17272 0.18923) (xy -0.17907 0.18034) (xy -0.18669 0.17145) (xy -0.19177 0.16256) (xy -0.19812 0.15367)
						(xy -0.20828 0.13335) (xy -0.21971 0.10287) (xy -0.22225 0.09271) (xy -0.22479 0.08128) (xy -0.22606 0.07112)
						(xy -0.2286 0.05969) (xy -0.2286 0.01651) (xy -0.22606 0.00508) (xy -0.22479 -0.00508) (xy -0.22225 -0.01651)
						(xy -0.21971 -0.02667) (xy -0.20828 -0.05715) (xy -0.19812 -0.07747) (xy -0.19177 -0.08636) (xy -0.18669 -0.09525)
						(xy -0.17907 -0.10414) (xy -0.17272 -0.11303) (xy -0.1651 -0.12065) (xy -0.1651 -0.7366) (xy -0.16256 -0.76835)
						(xy -0.1524 -0.8001) (xy -0.13716 -0.82804) (xy -0.11684 -0.85344) (xy -0.09144 -0.87376) (xy -0.0635 -0.889)
						(xy -0.03175 -0.89916) (xy 0 -0.9017) (xy 0.03175 -0.89916) (xy 0.0635 -0.889) (xy 0.09144 -0.87376)
						(xy 0.11684 -0.85344) (xy 0.13716 -0.82804) (xy 0.1524 -0.8001) (xy 0.16256 -0.76835) (xy 0.1651 -0.7366)
						(xy 0.1651 -0.11938) (xy 0.17272 -0.11176) (xy 0.19812 -0.0762) (xy 0.2032 -0.06604) (xy 0.20701 -0.05715)
						(xy 0.21209 -0.04699) (xy 0.2159 -0.03683) (xy 0.21844 -0.02667) (xy 0.22225 -0.01524) (xy 0.22352 -0.00508)
						(xy 0.22606 0.00508) (xy 0.22733 0.01651) (xy 0.22733 0.02667) (xy 0.2286 0.0381) (xy 0.22733 0.04953)
						(xy 0.22733 0.05969) (xy 0.22606 0.07112) (xy 0.22352 0.08128) (xy 0.22225 0.09144) (xy 0.21844 0.10287)
						(xy 0.2159 0.11303) (xy 0.21209 0.12319) (xy 0.20701 0.13335) (xy 0.2032 0.14224) (xy 0.19812 0.1524)
						(xy 0.17272 0.18796) (xy 0.1651 0.19558) (xy 0.1651 0.7366) (xy 0.16256 0.76835) (xy 0.1524 0.8001)
						(xy 0.13716 0.82804) (xy 0.11684 0.85344) (xy 0.09144 0.87376) (xy 0.0635 0.889) (xy 0.03175 0.89916)
					)
					(width 0)
					(fill yes)
				)
			)
		)
		(pad "169" smd custom
			(at 21.150072 4.106672)
			(size 0.1143 0.1143)
			(layers "F.Cu" "F.Mask" "F.Paste")
			(net "GND")
			(options
				(clearance outline)
				(anchor circle)
			)
			(primitives
				(gr_poly
					(pts
						(xy 0 0.9017) (xy -0.03175 0.89916) (xy -0.0635 0.889) (xy -0.09144 0.87376) (xy -0.11684 0.85344)
						(xy -0.13716 0.82804) (xy -0.1524 0.8001) (xy -0.16256 0.76835) (xy -0.1651 0.7366) (xy -0.1651 -0.13462)
						(xy -0.17272 -0.14224) (xy -0.19812 -0.1778) (xy -0.2032 -0.18796) (xy -0.20701 -0.19685) (xy -0.21209 -0.20701)
						(xy -0.2159 -0.21717) (xy -0.21844 -0.22733) (xy -0.22225 -0.23876) (xy -0.22352 -0.24892) (xy -0.22606 -0.25908)
						(xy -0.22733 -0.27051) (xy -0.22733 -0.28067) (xy -0.2286 -0.2921) (xy -0.22733 -0.30353) (xy -0.22733 -0.31369)
						(xy -0.22606 -0.32512) (xy -0.22352 -0.33528) (xy -0.22225 -0.34544) (xy -0.21844 -0.35687) (xy -0.2159 -0.36703)
						(xy -0.21209 -0.37719) (xy -0.20701 -0.38735) (xy -0.2032 -0.39624) (xy -0.19812 -0.4064) (xy -0.17272 -0.44196)
						(xy -0.1651 -0.44958) (xy -0.1651 -0.7366) (xy -0.16256 -0.76835) (xy -0.1524 -0.8001) (xy -0.13716 -0.82804)
						(xy -0.11684 -0.85344) (xy -0.09144 -0.87376) (xy -0.0635 -0.889) (xy -0.03175 -0.89916) (xy 0 -0.9017)
						(xy 0.03175 -0.89916) (xy 0.0635 -0.889) (xy 0.09144 -0.87376) (xy 0.11684 -0.85344) (xy 0.13716 -0.82804)
						(xy 0.1524 -0.8001) (xy 0.16256 -0.76835) (xy 0.1651 -0.7366) (xy 0.1651 -0.44958) (xy 0.17272 -0.44196)
						(xy 0.19812 -0.4064) (xy 0.2032 -0.39624) (xy 0.20701 -0.38735) (xy 0.21209 -0.37719) (xy 0.2159 -0.36703)
						(xy 0.21844 -0.35687) (xy 0.22225 -0.34544) (xy 0.22352 -0.33528) (xy 0.22606 -0.32512) (xy 0.22733 -0.31369)
						(xy 0.22733 -0.30353) (xy 0.2286 -0.2921) (xy 0.22733 -0.28067) (xy 0.22733 -0.27051) (xy 0.22606 -0.25908)
						(xy 0.22352 -0.24892) (xy 0.22225 -0.23876) (xy 0.21844 -0.22733) (xy 0.2159 -0.21717) (xy 0.21209 -0.20701)
						(xy 0.20701 -0.19685) (xy 0.2032 -0.18796) (xy 0.19812 -0.1778) (xy 0.17272 -0.14224) (xy 0.1651 -0.13462)
						(xy 0.1651 0.7366) (xy 0.16256 0.76835) (xy 0.1524 0.8001) (xy 0.13716 0.82804) (xy 0.11684 0.85344)
						(xy 0.09144 0.87376) (xy 0.0635 0.889) (xy 0.03175 0.89916)
					)
					(width 0)
					(fill yes)
				)
			)
		)
		(pad "170" smd custom
			(at 21.450046 -4.106672)
			(size 0.1143 0.1143)
			(layers "F.Cu" "F.Mask" "F.Paste")
			(net "GND")
			(options
				(clearance outline)
				(anchor circle)
			)
			(primitives
				(gr_poly
					(pts
						(xy 0 0.9017) (xy -0.03175 0.89916) (xy -0.0635 0.889) (xy -0.09144 0.87376) (xy -0.11684 0.85344)
						(xy -0.13716 0.82804) (xy -0.1524 0.8001) (xy -0.16256 0.76835) (xy -0.1651 0.7366) (xy -0.1651 0.44958)
						(xy -0.17272 0.44196) (xy -0.19812 0.4064) (xy -0.2032 0.39624) (xy -0.20701 0.38735) (xy -0.21209 0.37719)
						(xy -0.2159 0.36703) (xy -0.21844 0.35687) (xy -0.22225 0.34544) (xy -0.22352 0.33528) (xy -0.22606 0.32512)
						(xy -0.22733 0.31369) (xy -0.22733 0.30353) (xy -0.2286 0.2921) (xy -0.22733 0.28067) (xy -0.22733 0.27051)
						(xy -0.22606 0.25908) (xy -0.22352 0.24892) (xy -0.22225 0.23876) (xy -0.21844 0.22733) (xy -0.2159 0.21717)
						(xy -0.21209 0.20701) (xy -0.20701 0.19685) (xy -0.2032 0.18796) (xy -0.19812 0.1778) (xy -0.17272 0.14224)
						(xy -0.1651 0.13462) (xy -0.1651 -0.7366) (xy -0.16256 -0.76835) (xy -0.1524 -0.8001) (xy -0.13716 -0.82804)
						(xy -0.11684 -0.85344) (xy -0.09144 -0.87376) (xy -0.0635 -0.889) (xy -0.03175 -0.89916) (xy 0 -0.9017)
						(xy 0.03175 -0.89916) (xy 0.0635 -0.889) (xy 0.09144 -0.87376) (xy 0.11684 -0.85344) (xy 0.13716 -0.82804)
						(xy 0.1524 -0.8001) (xy 0.16256 -0.76835) (xy 0.1651 -0.7366) (xy 0.1651 0.13462) (xy 0.17272 0.14224)
						(xy 0.19812 0.1778) (xy 0.2032 0.18796) (xy 0.20701 0.19685) (xy 0.21209 0.20701) (xy 0.2159 0.21717)
						(xy 0.21844 0.22733) (xy 0.22225 0.23876) (xy 0.22352 0.24892) (xy 0.22606 0.25908) (xy 0.22733 0.27051)
						(xy 0.22733 0.28067) (xy 0.2286 0.2921) (xy 0.22733 0.30353) (xy 0.22733 0.31369) (xy 0.22606 0.32512)
						(xy 0.22352 0.33528) (xy 0.22225 0.34544) (xy 0.21844 0.35687) (xy 0.2159 0.36703) (xy 0.21209 0.37719)
						(xy 0.20701 0.38735) (xy 0.2032 0.39624) (xy 0.19812 0.4064) (xy 0.17272 0.44196) (xy 0.1651 0.44958)
						(xy 0.1651 0.7366) (xy 0.16256 0.76835) (xy 0.1524 0.8001) (xy 0.13716 0.82804) (xy 0.11684 0.85344)
						(xy 0.09144 0.87376) (xy 0.0635 0.889) (xy 0.03175 0.89916)
					)
					(width 0)
					(fill yes)
				)
			)
		)
		(pad "171" smd custom
			(at 21.75002 4.106672)
			(size 0.1143 0.1143)
			(layers "F.Cu" "F.Mask" "F.Paste")
			(net "M_B_DQS_DN6")
			(options
				(clearance outline)
				(anchor circle)
			)
			(primitives
				(gr_poly
					(pts
						(xy 0 0.9017) (xy -0.03175 0.89916) (xy -0.0635 0.889) (xy -0.09144 0.87376) (xy -0.11684 0.85344)
						(xy -0.13716 0.82804) (xy -0.1524 0.8001) (xy -0.16256 0.76835) (xy -0.1651 0.7366) (xy -0.1651 0.11938)
						(xy -0.17272 0.11176) (xy -0.19812 0.0762) (xy -0.2032 0.06604) (xy -0.20701 0.05715) (xy -0.21209 0.04699)
						(xy -0.2159 0.03683) (xy -0.21844 0.02667) (xy -0.22225 0.01524) (xy -0.22352 0.00508) (xy -0.22606 -0.00508)
						(xy -0.22733 -0.01651) (xy -0.22733 -0.02667) (xy -0.2286 -0.0381) (xy -0.22733 -0.04953) (xy -0.22733 -0.05969)
						(xy -0.22606 -0.07112) (xy -0.22352 -0.08128) (xy -0.22225 -0.09144) (xy -0.21844 -0.10287) (xy -0.2159 -0.11303)
						(xy -0.21209 -0.12319) (xy -0.20701 -0.13335) (xy -0.2032 -0.14224) (xy -0.19812 -0.1524) (xy -0.17272 -0.18796)
						(xy -0.1651 -0.19558) (xy -0.1651 -0.7366) (xy -0.16256 -0.76835) (xy -0.1524 -0.8001) (xy -0.13716 -0.82804)
						(xy -0.11684 -0.85344) (xy -0.09144 -0.87376) (xy -0.0635 -0.889) (xy -0.03175 -0.89916) (xy 0 -0.9017)
						(xy 0.03175 -0.89916) (xy 0.0635 -0.889) (xy 0.09144 -0.87376) (xy 0.11684 -0.85344) (xy 0.13716 -0.82804)
						(xy 0.1524 -0.8001) (xy 0.16256 -0.76835) (xy 0.1651 -0.7366) (xy 0.1651 -0.19685) (xy 0.17272 -0.18923)
						(xy 0.17907 -0.18034) (xy 0.18669 -0.17145) (xy 0.19177 -0.16256) (xy 0.19812 -0.15367) (xy 0.20828 -0.13335)
						(xy 0.21971 -0.10287) (xy 0.22225 -0.09271) (xy 0.22479 -0.08128) (xy 0.22606 -0.07112) (xy 0.2286 -0.05969)
						(xy 0.2286 -0.01651) (xy 0.22606 -0.00508) (xy 0.22479 0.00508) (xy 0.22225 0.01651) (xy 0.21971 0.02667)
						(xy 0.20828 0.05715) (xy 0.19812 0.07747) (xy 0.19177 0.08636) (xy 0.18669 0.09525) (xy 0.17907 0.10414)
						(xy 0.17272 0.11303) (xy 0.1651 0.12065) (xy 0.1651 0.7366) (xy 0.16256 0.76835) (xy 0.1524 0.8001)
						(xy 0.13716 0.82804) (xy 0.11684 0.85344) (xy 0.09144 0.87376) (xy 0.0635 0.889) (xy 0.03175 0.89916)
					)
					(width 0)
					(fill yes)
				)
			)
		)
		(pad "172" smd custom
			(at 22.049994 -4.106672)
			(size 0.1143 0.1143)
			(layers "F.Cu" "F.Mask" "F.Paste")
			(net "GND")
			(options
				(clearance outline)
				(anchor circle)
			)
			(primitives
				(gr_poly
					(pts
						(xy 0 0.9017) (xy -0.03175 0.89916) (xy -0.0635 0.889) (xy -0.09144 0.87376) (xy -0.11684 0.85344)
						(xy -0.13716 0.82804) (xy -0.1524 0.8001) (xy -0.16256 0.76835) (xy -0.1651 0.7366) (xy -0.1651 0.19685)
						(xy -0.17272 0.18923) (xy -0.17907 0.18034) (xy -0.18669 0.17145) (xy -0.19177 0.16256) (xy -0.19812 0.15367)
						(xy -0.20828 0.13335) (xy -0.21971 0.10287) (xy -0.22225 0.09271) (xy -0.22479 0.08128) (xy -0.22606 0.07112)
						(xy -0.2286 0.05969) (xy -0.2286 0.01651) (xy -0.22606 0.00508) (xy -0.22479 -0.00508) (xy -0.22225 -0.01651)
						(xy -0.21971 -0.02667) (xy -0.20828 -0.05715) (xy -0.19812 -0.07747) (xy -0.19177 -0.08636) (xy -0.18669 -0.09525)
						(xy -0.17907 -0.10414) (xy -0.17272 -0.11303) (xy -0.1651 -0.12065) (xy -0.1651 -0.7366) (xy -0.16256 -0.76835)
						(xy -0.1524 -0.8001) (xy -0.13716 -0.82804) (xy -0.11684 -0.85344) (xy -0.09144 -0.87376) (xy -0.0635 -0.889)
						(xy -0.03175 -0.89916) (xy 0 -0.9017) (xy 0.03175 -0.89916) (xy 0.0635 -0.889) (xy 0.09144 -0.87376)
						(xy 0.11684 -0.85344) (xy 0.13716 -0.82804) (xy 0.1524 -0.8001) (xy 0.16256 -0.76835) (xy 0.1651 -0.7366)
						(xy 0.1651 -0.11938) (xy 0.17272 -0.11176) (xy 0.19812 -0.0762) (xy 0.2032 -0.06604) (xy 0.20701 -0.05715)
						(xy 0.21209 -0.04699) (xy 0.2159 -0.03683) (xy 0.21844 -0.02667) (xy 0.22225 -0.01524) (xy 0.22352 -0.00508)
						(xy 0.22606 0.00508) (xy 0.22733 0.01651) (xy 0.22733 0.02667) (xy 0.2286 0.0381) (xy 0.22733 0.04953)
						(xy 0.22733 0.05969) (xy 0.22606 0.07112) (xy 0.22352 0.08128) (xy 0.22225 0.09144) (xy 0.21844 0.10287)
						(xy 0.2159 0.11303) (xy 0.21209 0.12319) (xy 0.20701 0.13335) (xy 0.2032 0.14224) (xy 0.19812 0.1524)
						(xy 0.17272 0.18796) (xy 0.1651 0.19558) (xy 0.1651 0.7366) (xy 0.16256 0.76835) (xy 0.1524 0.8001)
						(xy 0.13716 0.82804) (xy 0.11684 0.85344) (xy 0.09144 0.87376) (xy 0.0635 0.889) (xy 0.03175 0.89916)
					)
					(width 0)
					(fill yes)
				)
			)
		)
		(pad "173" smd custom
			(at 22.349968 4.106672)
			(size 0.1143 0.1143)
			(layers "F.Cu" "F.Mask" "F.Paste")
			(net "M_B_DQS_DP6")
			(options
				(clearance outline)
				(anchor circle)
			)
			(primitives
				(gr_poly
					(pts
						(xy 0 0.9017) (xy -0.03175 0.89916) (xy -0.0635 0.889) (xy -0.09144 0.87376) (xy -0.11684 0.85344)
						(xy -0.13716 0.82804) (xy -0.1524 0.8001) (xy -0.16256 0.76835) (xy -0.1651 0.7366) (xy -0.1651 -0.13462)
						(xy -0.17272 -0.14224) (xy -0.19812 -0.1778) (xy -0.2032 -0.18796) (xy -0.20701 -0.19685) (xy -0.21209 -0.20701)
						(xy -0.2159 -0.21717) (xy -0.21844 -0.22733) (xy -0.22225 -0.23876) (xy -0.22352 -0.24892) (xy -0.22606 -0.25908)
						(xy -0.22733 -0.27051) (xy -0.22733 -0.28067) (xy -0.2286 -0.2921) (xy -0.22733 -0.30353) (xy -0.22733 -0.31369)
						(xy -0.22606 -0.32512) (xy -0.22352 -0.33528) (xy -0.22225 -0.34544) (xy -0.21844 -0.35687) (xy -0.2159 -0.36703)
						(xy -0.21209 -0.37719) (xy -0.20701 -0.38735) (xy -0.2032 -0.39624) (xy -0.19812 -0.4064) (xy -0.17272 -0.44196)
						(xy -0.1651 -0.44958) (xy -0.1651 -0.7366) (xy -0.16256 -0.76835) (xy -0.1524 -0.8001) (xy -0.13716 -0.82804)
						(xy -0.11684 -0.85344) (xy -0.09144 -0.87376) (xy -0.0635 -0.889) (xy -0.03175 -0.89916) (xy 0 -0.9017)
						(xy 0.03175 -0.89916) (xy 0.0635 -0.889) (xy 0.09144 -0.87376) (xy 0.11684 -0.85344) (xy 0.13716 -0.82804)
						(xy 0.1524 -0.8001) (xy 0.16256 -0.76835) (xy 0.1651 -0.7366) (xy 0.1651 -0.44958) (xy 0.17272 -0.44196)
						(xy 0.19812 -0.4064) (xy 0.2032 -0.39624) (xy 0.20701 -0.38735) (xy 0.21209 -0.37719) (xy 0.2159 -0.36703)
						(xy 0.21844 -0.35687) (xy 0.22225 -0.34544) (xy 0.22352 -0.33528) (xy 0.22606 -0.32512) (xy 0.22733 -0.31369)
						(xy 0.22733 -0.30353) (xy 0.2286 -0.2921) (xy 0.22733 -0.28067) (xy 0.22733 -0.27051) (xy 0.22606 -0.25908)
						(xy 0.22352 -0.24892) (xy 0.22225 -0.23876) (xy 0.21844 -0.22733) (xy 0.2159 -0.21717) (xy 0.21209 -0.20701)
						(xy 0.20701 -0.19685) (xy 0.2032 -0.18796) (xy 0.19812 -0.1778) (xy 0.17272 -0.14224) (xy 0.1651 -0.13462)
						(xy 0.1651 0.7366) (xy 0.16256 0.76835) (xy 0.1524 0.8001) (xy 0.13716 0.82804) (xy 0.11684 0.85344)
						(xy 0.09144 0.87376) (xy 0.0635 0.889) (xy 0.03175 0.89916)
					)
					(width 0)
					(fill yes)
				)
			)
		)
		(pad "174" smd custom
			(at 22.649942 -4.106672)
			(size 0.1143 0.1143)
			(layers "F.Cu" "F.Mask" "F.Paste")
			(net "M_B_DQ50")
			(options
				(clearance outline)
				(anchor circle)
			)
			(primitives
				(gr_poly
					(pts
						(xy 0 0.9017) (xy -0.03175 0.89916) (xy -0.0635 0.889) (xy -0.09144 0.87376) (xy -0.11684 0.85344)
						(xy -0.13716 0.82804) (xy -0.1524 0.8001) (xy -0.16256 0.76835) (xy -0.1651 0.7366) (xy -0.1651 0.44958)
						(xy -0.17272 0.44196) (xy -0.19812 0.4064) (xy -0.2032 0.39624) (xy -0.20701 0.38735) (xy -0.21209 0.37719)
						(xy -0.2159 0.36703) (xy -0.21844 0.35687) (xy -0.22225 0.34544) (xy -0.22352 0.33528) (xy -0.22606 0.32512)
						(xy -0.22733 0.31369) (xy -0.22733 0.30353) (xy -0.2286 0.2921) (xy -0.22733 0.28067) (xy -0.22733 0.27051)
						(xy -0.22606 0.25908) (xy -0.22352 0.24892) (xy -0.22225 0.23876) (xy -0.21844 0.22733) (xy -0.2159 0.21717)
						(xy -0.21209 0.20701) (xy -0.20701 0.19685) (xy -0.2032 0.18796) (xy -0.19812 0.1778) (xy -0.17272 0.14224)
						(xy -0.1651 0.13462) (xy -0.1651 -0.7366) (xy -0.16256 -0.76835) (xy -0.1524 -0.8001) (xy -0.13716 -0.82804)
						(xy -0.11684 -0.85344) (xy -0.09144 -0.87376) (xy -0.0635 -0.889) (xy -0.03175 -0.89916) (xy 0 -0.9017)
						(xy 0.03175 -0.89916) (xy 0.0635 -0.889) (xy 0.09144 -0.87376) (xy 0.11684 -0.85344) (xy 0.13716 -0.82804)
						(xy 0.1524 -0.8001) (xy 0.16256 -0.76835) (xy 0.1651 -0.7366) (xy 0.1651 0.13462) (xy 0.17272 0.14224)
						(xy 0.19812 0.1778) (xy 0.2032 0.18796) (xy 0.20701 0.19685) (xy 0.21209 0.20701) (xy 0.2159 0.21717)
						(xy 0.21844 0.22733) (xy 0.22225 0.23876) (xy 0.22352 0.24892) (xy 0.22606 0.25908) (xy 0.22733 0.27051)
						(xy 0.22733 0.28067) (xy 0.2286 0.2921) (xy 0.22733 0.30353) (xy 0.22733 0.31369) (xy 0.22606 0.32512)
						(xy 0.22352 0.33528) (xy 0.22225 0.34544) (xy 0.21844 0.35687) (xy 0.2159 0.36703) (xy 0.21209 0.37719)
						(xy 0.20701 0.38735) (xy 0.2032 0.39624) (xy 0.19812 0.4064) (xy 0.17272 0.44196) (xy 0.1651 0.44958)
						(xy 0.1651 0.7366) (xy 0.16256 0.76835) (xy 0.1524 0.8001) (xy 0.13716 0.82804) (xy 0.11684 0.85344)
						(xy 0.09144 0.87376) (xy 0.0635 0.889) (xy 0.03175 0.89916)
					)
					(width 0)
					(fill yes)
				)
			)
		)
		(pad "175" smd custom
			(at 22.949916 4.106672)
			(size 0.1143 0.1143)
			(layers "F.Cu" "F.Mask" "F.Paste")
			(net "GND")
			(options
				(clearance outline)
				(anchor circle)
			)
			(primitives
				(gr_poly
					(pts
						(xy 0 0.9017) (xy -0.03175 0.89916) (xy -0.0635 0.889) (xy -0.09144 0.87376) (xy -0.11684 0.85344)
						(xy -0.13716 0.82804) (xy -0.1524 0.8001) (xy -0.16256 0.76835) (xy -0.1651 0.7366) (xy -0.1651 0.11938)
						(xy -0.17272 0.11176) (xy -0.19812 0.0762) (xy -0.2032 0.06604) (xy -0.20701 0.05715) (xy -0.21209 0.04699)
						(xy -0.2159 0.03683) (xy -0.21844 0.02667) (xy -0.22225 0.01524) (xy -0.22352 0.00508) (xy -0.22606 -0.00508)
						(xy -0.22733 -0.01651) (xy -0.22733 -0.02667) (xy -0.2286 -0.0381) (xy -0.22733 -0.04953) (xy -0.22733 -0.05969)
						(xy -0.22606 -0.07112) (xy -0.22352 -0.08128) (xy -0.22225 -0.09144) (xy -0.21844 -0.10287) (xy -0.2159 -0.11303)
						(xy -0.21209 -0.12319) (xy -0.20701 -0.13335) (xy -0.2032 -0.14224) (xy -0.19812 -0.1524) (xy -0.17272 -0.18796)
						(xy -0.1651 -0.19558) (xy -0.1651 -0.7366) (xy -0.16256 -0.76835) (xy -0.1524 -0.8001) (xy -0.13716 -0.82804)
						(xy -0.11684 -0.85344) (xy -0.09144 -0.87376) (xy -0.0635 -0.889) (xy -0.03175 -0.89916) (xy 0 -0.9017)
						(xy 0.03175 -0.89916) (xy 0.0635 -0.889) (xy 0.09144 -0.87376) (xy 0.11684 -0.85344) (xy 0.13716 -0.82804)
						(xy 0.1524 -0.8001) (xy 0.16256 -0.76835) (xy 0.1651 -0.7366) (xy 0.1651 -0.19685) (xy 0.17272 -0.18923)
						(xy 0.17907 -0.18034) (xy 0.18669 -0.17145) (xy 0.19177 -0.16256) (xy 0.19812 -0.15367) (xy 0.20828 -0.13335)
						(xy 0.21971 -0.10287) (xy 0.22225 -0.09271) (xy 0.22479 -0.08128) (xy 0.22606 -0.07112) (xy 0.2286 -0.05969)
						(xy 0.2286 -0.01651) (xy 0.22606 -0.00508) (xy 0.22479 0.00508) (xy 0.22225 0.01651) (xy 0.21971 0.02667)
						(xy 0.20828 0.05715) (xy 0.19812 0.07747) (xy 0.19177 0.08636) (xy 0.18669 0.09525) (xy 0.17907 0.10414)
						(xy 0.17272 0.11303) (xy 0.1651 0.12065) (xy 0.1651 0.7366) (xy 0.16256 0.76835) (xy 0.1524 0.8001)
						(xy 0.13716 0.82804) (xy 0.11684 0.85344) (xy 0.09144 0.87376) (xy 0.0635 0.889) (xy 0.03175 0.89916)
					)
					(width 0)
					(fill yes)
				)
			)
		)
		(pad "176" smd custom
			(at 23.24989 -4.106672)
			(size 0.1143 0.1143)
			(layers "F.Cu" "F.Mask" "F.Paste")
			(net "M_B_DQ51")
			(options
				(clearance outline)
				(anchor circle)
			)
			(primitives
				(gr_poly
					(pts
						(xy 0 0.9017) (xy -0.03175 0.89916) (xy -0.0635 0.889) (xy -0.09144 0.87376) (xy -0.11684 0.85344)
						(xy -0.13716 0.82804) (xy -0.1524 0.8001) (xy -0.16256 0.76835) (xy -0.1651 0.7366) (xy -0.1651 0.19685)
						(xy -0.17272 0.18923) (xy -0.17907 0.18034) (xy -0.18669 0.17145) (xy -0.19177 0.16256) (xy -0.19812 0.15367)
						(xy -0.20828 0.13335) (xy -0.21971 0.10287) (xy -0.22225 0.09271) (xy -0.22479 0.08128) (xy -0.22606 0.07112)
						(xy -0.2286 0.05969) (xy -0.2286 0.01651) (xy -0.22606 0.00508) (xy -0.22479 -0.00508) (xy -0.22225 -0.01651)
						(xy -0.21971 -0.02667) (xy -0.20828 -0.05715) (xy -0.19812 -0.07747) (xy -0.19177 -0.08636) (xy -0.18669 -0.09525)
						(xy -0.17907 -0.10414) (xy -0.17272 -0.11303) (xy -0.1651 -0.12065) (xy -0.1651 -0.7366) (xy -0.16256 -0.76835)
						(xy -0.1524 -0.8001) (xy -0.13716 -0.82804) (xy -0.11684 -0.85344) (xy -0.09144 -0.87376) (xy -0.0635 -0.889)
						(xy -0.03175 -0.89916) (xy 0 -0.9017) (xy 0.03175 -0.89916) (xy 0.0635 -0.889) (xy 0.09144 -0.87376)
						(xy 0.11684 -0.85344) (xy 0.13716 -0.82804) (xy 0.1524 -0.8001) (xy 0.16256 -0.76835) (xy 0.1651 -0.7366)
						(xy 0.1651 -0.11938) (xy 0.17272 -0.11176) (xy 0.19812 -0.0762) (xy 0.2032 -0.06604) (xy 0.20701 -0.05715)
						(xy 0.21209 -0.04699) (xy 0.2159 -0.03683) (xy 0.21844 -0.02667) (xy 0.22225 -0.01524) (xy 0.22352 -0.00508)
						(xy 0.22606 0.00508) (xy 0.22733 0.01651) (xy 0.22733 0.02667) (xy 0.2286 0.0381) (xy 0.22733 0.04953)
						(xy 0.22733 0.05969) (xy 0.22606 0.07112) (xy 0.22352 0.08128) (xy 0.22225 0.09144) (xy 0.21844 0.10287)
						(xy 0.2159 0.11303) (xy 0.21209 0.12319) (xy 0.20701 0.13335) (xy 0.2032 0.14224) (xy 0.19812 0.1524)
						(xy 0.17272 0.18796) (xy 0.1651 0.19558) (xy 0.1651 0.7366) (xy 0.16256 0.76835) (xy 0.1524 0.8001)
						(xy 0.13716 0.82804) (xy 0.11684 0.85344) (xy 0.09144 0.87376) (xy 0.0635 0.889) (xy 0.03175 0.89916)
					)
					(width 0)
					(fill yes)
				)
			)
		)
		(pad "177" smd custom
			(at 23.550118 4.106672)
			(size 0.1143 0.1143)
			(layers "F.Cu" "F.Mask" "F.Paste")
			(net "M_B_DQ54")
			(options
				(clearance outline)
				(anchor circle)
			)
			(primitives
				(gr_poly
					(pts
						(xy 0 0.9017) (xy -0.03175 0.89916) (xy -0.0635 0.889) (xy -0.09144 0.87376) (xy -0.11684 0.85344)
						(xy -0.13716 0.82804) (xy -0.1524 0.8001) (xy -0.16256 0.76835) (xy -0.1651 0.7366) (xy -0.1651 -0.13462)
						(xy -0.17272 -0.14224) (xy -0.19812 -0.1778) (xy -0.2032 -0.18796) (xy -0.20701 -0.19685) (xy -0.21209 -0.20701)
						(xy -0.2159 -0.21717) (xy -0.21844 -0.22733) (xy -0.22225 -0.23876) (xy -0.22352 -0.24892) (xy -0.22606 -0.25908)
						(xy -0.22733 -0.27051) (xy -0.22733 -0.28067) (xy -0.2286 -0.2921) (xy -0.22733 -0.30353) (xy -0.22733 -0.31369)
						(xy -0.22606 -0.32512) (xy -0.22352 -0.33528) (xy -0.22225 -0.34544) (xy -0.21844 -0.35687) (xy -0.2159 -0.36703)
						(xy -0.21209 -0.37719) (xy -0.20701 -0.38735) (xy -0.2032 -0.39624) (xy -0.19812 -0.4064) (xy -0.17272 -0.44196)
						(xy -0.1651 -0.44958) (xy -0.1651 -0.7366) (xy -0.16256 -0.76835) (xy -0.1524 -0.8001) (xy -0.13716 -0.82804)
						(xy -0.11684 -0.85344) (xy -0.09144 -0.87376) (xy -0.0635 -0.889) (xy -0.03175 -0.89916) (xy 0 -0.9017)
						(xy 0.03175 -0.89916) (xy 0.0635 -0.889) (xy 0.09144 -0.87376) (xy 0.11684 -0.85344) (xy 0.13716 -0.82804)
						(xy 0.1524 -0.8001) (xy 0.16256 -0.76835) (xy 0.1651 -0.7366) (xy 0.1651 -0.44958) (xy 0.17272 -0.44196)
						(xy 0.19812 -0.4064) (xy 0.2032 -0.39624) (xy 0.20701 -0.38735) (xy 0.21209 -0.37719) (xy 0.2159 -0.36703)
						(xy 0.21844 -0.35687) (xy 0.22225 -0.34544) (xy 0.22352 -0.33528) (xy 0.22606 -0.32512) (xy 0.22733 -0.31369)
						(xy 0.22733 -0.30353) (xy 0.2286 -0.2921) (xy 0.22733 -0.28067) (xy 0.22733 -0.27051) (xy 0.22606 -0.25908)
						(xy 0.22352 -0.24892) (xy 0.22225 -0.23876) (xy 0.21844 -0.22733) (xy 0.2159 -0.21717) (xy 0.21209 -0.20701)
						(xy 0.20701 -0.19685) (xy 0.2032 -0.18796) (xy 0.19812 -0.1778) (xy 0.17272 -0.14224) (xy 0.1651 -0.13462)
						(xy 0.1651 0.7366) (xy 0.16256 0.76835) (xy 0.1524 0.8001) (xy 0.13716 0.82804) (xy 0.11684 0.85344)
						(xy 0.09144 0.87376) (xy 0.0635 0.889) (xy 0.03175 0.89916)
					)
					(width 0)
					(fill yes)
				)
			)
		)
		(pad "178" smd custom
			(at 23.850092 -4.106672)
			(size 0.1143 0.1143)
			(layers "F.Cu" "F.Mask" "F.Paste")
			(net "GND")
			(options
				(clearance outline)
				(anchor circle)
			)
			(primitives
				(gr_poly
					(pts
						(xy 0 0.9017) (xy -0.03175 0.89916) (xy -0.0635 0.889) (xy -0.09144 0.87376) (xy -0.11684 0.85344)
						(xy -0.13716 0.82804) (xy -0.1524 0.8001) (xy -0.16256 0.76835) (xy -0.1651 0.7366) (xy -0.1651 0.44958)
						(xy -0.17272 0.44196) (xy -0.19812 0.4064) (xy -0.2032 0.39624) (xy -0.20701 0.38735) (xy -0.21209 0.37719)
						(xy -0.2159 0.36703) (xy -0.21844 0.35687) (xy -0.22225 0.34544) (xy -0.22352 0.33528) (xy -0.22606 0.32512)
						(xy -0.22733 0.31369) (xy -0.22733 0.30353) (xy -0.2286 0.2921) (xy -0.22733 0.28067) (xy -0.22733 0.27051)
						(xy -0.22606 0.25908) (xy -0.22352 0.24892) (xy -0.22225 0.23876) (xy -0.21844 0.22733) (xy -0.2159 0.21717)
						(xy -0.21209 0.20701) (xy -0.20701 0.19685) (xy -0.2032 0.18796) (xy -0.19812 0.1778) (xy -0.17272 0.14224)
						(xy -0.1651 0.13462) (xy -0.1651 -0.7366) (xy -0.16256 -0.76835) (xy -0.1524 -0.8001) (xy -0.13716 -0.82804)
						(xy -0.11684 -0.85344) (xy -0.09144 -0.87376) (xy -0.0635 -0.889) (xy -0.03175 -0.89916) (xy 0 -0.9017)
						(xy 0.03175 -0.89916) (xy 0.0635 -0.889) (xy 0.09144 -0.87376) (xy 0.11684 -0.85344) (xy 0.13716 -0.82804)
						(xy 0.1524 -0.8001) (xy 0.16256 -0.76835) (xy 0.1651 -0.7366) (xy 0.1651 0.13462) (xy 0.17272 0.14224)
						(xy 0.19812 0.1778) (xy 0.2032 0.18796) (xy 0.20701 0.19685) (xy 0.21209 0.20701) (xy 0.2159 0.21717)
						(xy 0.21844 0.22733) (xy 0.22225 0.23876) (xy 0.22352 0.24892) (xy 0.22606 0.25908) (xy 0.22733 0.27051)
						(xy 0.22733 0.28067) (xy 0.2286 0.2921) (xy 0.22733 0.30353) (xy 0.22733 0.31369) (xy 0.22606 0.32512)
						(xy 0.22352 0.33528) (xy 0.22225 0.34544) (xy 0.21844 0.35687) (xy 0.2159 0.36703) (xy 0.21209 0.37719)
						(xy 0.20701 0.38735) (xy 0.2032 0.39624) (xy 0.19812 0.4064) (xy 0.17272 0.44196) (xy 0.1651 0.44958)
						(xy 0.1651 0.7366) (xy 0.16256 0.76835) (xy 0.1524 0.8001) (xy 0.13716 0.82804) (xy 0.11684 0.85344)
						(xy 0.09144 0.87376) (xy 0.0635 0.889) (xy 0.03175 0.89916)
					)
					(width 0)
					(fill yes)
				)
			)
		)
		(pad "179" smd custom
			(at 24.150066 4.106672)
			(size 0.1143 0.1143)
			(layers "F.Cu" "F.Mask" "F.Paste")
			(net "M_B_DQ55")
			(options
				(clearance outline)
				(anchor circle)
			)
			(primitives
				(gr_poly
					(pts
						(xy 0 0.9017) (xy -0.03175 0.89916) (xy -0.0635 0.889) (xy -0.09144 0.87376) (xy -0.11684 0.85344)
						(xy -0.13716 0.82804) (xy -0.1524 0.8001) (xy -0.16256 0.76835) (xy -0.1651 0.7366) (xy -0.1651 0.11938)
						(xy -0.17272 0.11176) (xy -0.19812 0.0762) (xy -0.2032 0.06604) (xy -0.20701 0.05715) (xy -0.21209 0.04699)
						(xy -0.2159 0.03683) (xy -0.21844 0.02667) (xy -0.22225 0.01524) (xy -0.22352 0.00508) (xy -0.22606 -0.00508)
						(xy -0.22733 -0.01651) (xy -0.22733 -0.02667) (xy -0.2286 -0.0381) (xy -0.22733 -0.04953) (xy -0.22733 -0.05969)
						(xy -0.22606 -0.07112) (xy -0.22352 -0.08128) (xy -0.22225 -0.09144) (xy -0.21844 -0.10287) (xy -0.2159 -0.11303)
						(xy -0.21209 -0.12319) (xy -0.20701 -0.13335) (xy -0.2032 -0.14224) (xy -0.19812 -0.1524) (xy -0.17272 -0.18796)
						(xy -0.1651 -0.19558) (xy -0.1651 -0.7366) (xy -0.16256 -0.76835) (xy -0.1524 -0.8001) (xy -0.13716 -0.82804)
						(xy -0.11684 -0.85344) (xy -0.09144 -0.87376) (xy -0.0635 -0.889) (xy -0.03175 -0.89916) (xy 0 -0.9017)
						(xy 0.03175 -0.89916) (xy 0.0635 -0.889) (xy 0.09144 -0.87376) (xy 0.11684 -0.85344) (xy 0.13716 -0.82804)
						(xy 0.1524 -0.8001) (xy 0.16256 -0.76835) (xy 0.1651 -0.7366) (xy 0.1651 -0.19685) (xy 0.17272 -0.18923)
						(xy 0.17907 -0.18034) (xy 0.18669 -0.17145) (xy 0.19177 -0.16256) (xy 0.19812 -0.15367) (xy 0.20828 -0.13335)
						(xy 0.21971 -0.10287) (xy 0.22225 -0.09271) (xy 0.22479 -0.08128) (xy 0.22606 -0.07112) (xy 0.2286 -0.05969)
						(xy 0.2286 -0.01651) (xy 0.22606 -0.00508) (xy 0.22479 0.00508) (xy 0.22225 0.01651) (xy 0.21971 0.02667)
						(xy 0.20828 0.05715) (xy 0.19812 0.07747) (xy 0.19177 0.08636) (xy 0.18669 0.09525) (xy 0.17907 0.10414)
						(xy 0.17272 0.11303) (xy 0.1651 0.12065) (xy 0.1651 0.7366) (xy 0.16256 0.76835) (xy 0.1524 0.8001)
						(xy 0.13716 0.82804) (xy 0.11684 0.85344) (xy 0.09144 0.87376) (xy 0.0635 0.889) (xy 0.03175 0.89916)
					)
					(width 0)
					(fill yes)
				)
			)
		)
		(pad "180" smd custom
			(at 24.45004 -4.106672)
			(size 0.1143 0.1143)
			(layers "F.Cu" "F.Mask" "F.Paste")
			(net "M_B_DQ56")
			(options
				(clearance outline)
				(anchor circle)
			)
			(primitives
				(gr_poly
					(pts
						(xy 0 0.9017) (xy -0.03175 0.89916) (xy -0.0635 0.889) (xy -0.09144 0.87376) (xy -0.11684 0.85344)
						(xy -0.13716 0.82804) (xy -0.1524 0.8001) (xy -0.16256 0.76835) (xy -0.1651 0.7366) (xy -0.1651 0.19685)
						(xy -0.17272 0.18923) (xy -0.17907 0.18034) (xy -0.18669 0.17145) (xy -0.19177 0.16256) (xy -0.19812 0.15367)
						(xy -0.20828 0.13335) (xy -0.21971 0.10287) (xy -0.22225 0.09271) (xy -0.22479 0.08128) (xy -0.22606 0.07112)
						(xy -0.2286 0.05969) (xy -0.2286 0.01651) (xy -0.22606 0.00508) (xy -0.22479 -0.00508) (xy -0.22225 -0.01651)
						(xy -0.21971 -0.02667) (xy -0.20828 -0.05715) (xy -0.19812 -0.07747) (xy -0.19177 -0.08636) (xy -0.18669 -0.09525)
						(xy -0.17907 -0.10414) (xy -0.17272 -0.11303) (xy -0.1651 -0.12065) (xy -0.1651 -0.7366) (xy -0.16256 -0.76835)
						(xy -0.1524 -0.8001) (xy -0.13716 -0.82804) (xy -0.11684 -0.85344) (xy -0.09144 -0.87376) (xy -0.0635 -0.889)
						(xy -0.03175 -0.89916) (xy 0 -0.9017) (xy 0.03175 -0.89916) (xy 0.0635 -0.889) (xy 0.09144 -0.87376)
						(xy 0.11684 -0.85344) (xy 0.13716 -0.82804) (xy 0.1524 -0.8001) (xy 0.16256 -0.76835) (xy 0.1651 -0.7366)
						(xy 0.1651 -0.11938) (xy 0.17272 -0.11176) (xy 0.19812 -0.0762) (xy 0.2032 -0.06604) (xy 0.20701 -0.05715)
						(xy 0.21209 -0.04699) (xy 0.2159 -0.03683) (xy 0.21844 -0.02667) (xy 0.22225 -0.01524) (xy 0.22352 -0.00508)
						(xy 0.22606 0.00508) (xy 0.22733 0.01651) (xy 0.22733 0.02667) (xy 0.2286 0.0381) (xy 0.22733 0.04953)
						(xy 0.22733 0.05969) (xy 0.22606 0.07112) (xy 0.22352 0.08128) (xy 0.22225 0.09144) (xy 0.21844 0.10287)
						(xy 0.2159 0.11303) (xy 0.21209 0.12319) (xy 0.20701 0.13335) (xy 0.2032 0.14224) (xy 0.19812 0.1524)
						(xy 0.17272 0.18796) (xy 0.1651 0.19558) (xy 0.1651 0.7366) (xy 0.16256 0.76835) (xy 0.1524 0.8001)
						(xy 0.13716 0.82804) (xy 0.11684 0.85344) (xy 0.09144 0.87376) (xy 0.0635 0.889) (xy 0.03175 0.89916)
					)
					(width 0)
					(fill yes)
				)
			)
		)
		(pad "181" smd custom
			(at 24.750014 4.106672)
			(size 0.1143 0.1143)
			(layers "F.Cu" "F.Mask" "F.Paste")
			(net "GND")
			(options
				(clearance outline)
				(anchor circle)
			)
			(primitives
				(gr_poly
					(pts
						(xy 0 0.9017) (xy -0.03175 0.89916) (xy -0.0635 0.889) (xy -0.09144 0.87376) (xy -0.11684 0.85344)
						(xy -0.13716 0.82804) (xy -0.1524 0.8001) (xy -0.16256 0.76835) (xy -0.1651 0.7366) (xy -0.1651 -0.13462)
						(xy -0.17272 -0.14224) (xy -0.19812 -0.1778) (xy -0.2032 -0.18796) (xy -0.20701 -0.19685) (xy -0.21209 -0.20701)
						(xy -0.2159 -0.21717) (xy -0.21844 -0.22733) (xy -0.22225 -0.23876) (xy -0.22352 -0.24892) (xy -0.22606 -0.25908)
						(xy -0.22733 -0.27051) (xy -0.22733 -0.28067) (xy -0.2286 -0.2921) (xy -0.22733 -0.30353) (xy -0.22733 -0.31369)
						(xy -0.22606 -0.32512) (xy -0.22352 -0.33528) (xy -0.22225 -0.34544) (xy -0.21844 -0.35687) (xy -0.2159 -0.36703)
						(xy -0.21209 -0.37719) (xy -0.20701 -0.38735) (xy -0.2032 -0.39624) (xy -0.19812 -0.4064) (xy -0.17272 -0.44196)
						(xy -0.1651 -0.44958) (xy -0.1651 -0.7366) (xy -0.16256 -0.76835) (xy -0.1524 -0.8001) (xy -0.13716 -0.82804)
						(xy -0.11684 -0.85344) (xy -0.09144 -0.87376) (xy -0.0635 -0.889) (xy -0.03175 -0.89916) (xy 0 -0.9017)
						(xy 0.03175 -0.89916) (xy 0.0635 -0.889) (xy 0.09144 -0.87376) (xy 0.11684 -0.85344) (xy 0.13716 -0.82804)
						(xy 0.1524 -0.8001) (xy 0.16256 -0.76835) (xy 0.1651 -0.7366) (xy 0.1651 -0.44958) (xy 0.17272 -0.44196)
						(xy 0.19812 -0.4064) (xy 0.2032 -0.39624) (xy 0.20701 -0.38735) (xy 0.21209 -0.37719) (xy 0.2159 -0.36703)
						(xy 0.21844 -0.35687) (xy 0.22225 -0.34544) (xy 0.22352 -0.33528) (xy 0.22606 -0.32512) (xy 0.22733 -0.31369)
						(xy 0.22733 -0.30353) (xy 0.2286 -0.2921) (xy 0.22733 -0.28067) (xy 0.22733 -0.27051) (xy 0.22606 -0.25908)
						(xy 0.22352 -0.24892) (xy 0.22225 -0.23876) (xy 0.21844 -0.22733) (xy 0.2159 -0.21717) (xy 0.21209 -0.20701)
						(xy 0.20701 -0.19685) (xy 0.2032 -0.18796) (xy 0.19812 -0.1778) (xy 0.17272 -0.14224) (xy 0.1651 -0.13462)
						(xy 0.1651 0.7366) (xy 0.16256 0.76835) (xy 0.1524 0.8001) (xy 0.13716 0.82804) (xy 0.11684 0.85344)
						(xy 0.09144 0.87376) (xy 0.0635 0.889) (xy 0.03175 0.89916)
					)
					(width 0)
					(fill yes)
				)
			)
		)
		(pad "182" smd custom
			(at 25.049988 -4.106672)
			(size 0.1143 0.1143)
			(layers "F.Cu" "F.Mask" "F.Paste")
			(net "M_B_DQ57")
			(options
				(clearance outline)
				(anchor circle)
			)
			(primitives
				(gr_poly
					(pts
						(xy 0 0.9017) (xy -0.03175 0.89916) (xy -0.0635 0.889) (xy -0.09144 0.87376) (xy -0.11684 0.85344)
						(xy -0.13716 0.82804) (xy -0.1524 0.8001) (xy -0.16256 0.76835) (xy -0.1651 0.7366) (xy -0.1651 0.44958)
						(xy -0.17272 0.44196) (xy -0.19812 0.4064) (xy -0.2032 0.39624) (xy -0.20701 0.38735) (xy -0.21209 0.37719)
						(xy -0.2159 0.36703) (xy -0.21844 0.35687) (xy -0.22225 0.34544) (xy -0.22352 0.33528) (xy -0.22606 0.32512)
						(xy -0.22733 0.31369) (xy -0.22733 0.30353) (xy -0.2286 0.2921) (xy -0.22733 0.28067) (xy -0.22733 0.27051)
						(xy -0.22606 0.25908) (xy -0.22352 0.24892) (xy -0.22225 0.23876) (xy -0.21844 0.22733) (xy -0.2159 0.21717)
						(xy -0.21209 0.20701) (xy -0.20701 0.19685) (xy -0.2032 0.18796) (xy -0.19812 0.1778) (xy -0.17272 0.14224)
						(xy -0.1651 0.13462) (xy -0.1651 -0.7366) (xy -0.16256 -0.76835) (xy -0.1524 -0.8001) (xy -0.13716 -0.82804)
						(xy -0.11684 -0.85344) (xy -0.09144 -0.87376) (xy -0.0635 -0.889) (xy -0.03175 -0.89916) (xy 0 -0.9017)
						(xy 0.03175 -0.89916) (xy 0.0635 -0.889) (xy 0.09144 -0.87376) (xy 0.11684 -0.85344) (xy 0.13716 -0.82804)
						(xy 0.1524 -0.8001) (xy 0.16256 -0.76835) (xy 0.1651 -0.7366) (xy 0.1651 0.13462) (xy 0.17272 0.14224)
						(xy 0.19812 0.1778) (xy 0.2032 0.18796) (xy 0.20701 0.19685) (xy 0.21209 0.20701) (xy 0.2159 0.21717)
						(xy 0.21844 0.22733) (xy 0.22225 0.23876) (xy 0.22352 0.24892) (xy 0.22606 0.25908) (xy 0.22733 0.27051)
						(xy 0.22733 0.28067) (xy 0.2286 0.2921) (xy 0.22733 0.30353) (xy 0.22733 0.31369) (xy 0.22606 0.32512)
						(xy 0.22352 0.33528) (xy 0.22225 0.34544) (xy 0.21844 0.35687) (xy 0.2159 0.36703) (xy 0.21209 0.37719)
						(xy 0.20701 0.38735) (xy 0.2032 0.39624) (xy 0.19812 0.4064) (xy 0.17272 0.44196) (xy 0.1651 0.44958)
						(xy 0.1651 0.7366) (xy 0.16256 0.76835) (xy 0.1524 0.8001) (xy 0.13716 0.82804) (xy 0.11684 0.85344)
						(xy 0.09144 0.87376) (xy 0.0635 0.889) (xy 0.03175 0.89916)
					)
					(width 0)
					(fill yes)
				)
			)
		)
		(pad "183" smd custom
			(at 25.349962 4.106672)
			(size 0.1143 0.1143)
			(layers "F.Cu" "F.Mask" "F.Paste")
			(net "M_B_DQ60")
			(options
				(clearance outline)
				(anchor circle)
			)
			(primitives
				(gr_poly
					(pts
						(xy 0 0.9017) (xy -0.03175 0.89916) (xy -0.0635 0.889) (xy -0.09144 0.87376) (xy -0.11684 0.85344)
						(xy -0.13716 0.82804) (xy -0.1524 0.8001) (xy -0.16256 0.76835) (xy -0.1651 0.7366) (xy -0.1651 0.11938)
						(xy -0.17272 0.11176) (xy -0.19812 0.0762) (xy -0.2032 0.06604) (xy -0.20701 0.05715) (xy -0.21209 0.04699)
						(xy -0.2159 0.03683) (xy -0.21844 0.02667) (xy -0.22225 0.01524) (xy -0.22352 0.00508) (xy -0.22606 -0.00508)
						(xy -0.22733 -0.01651) (xy -0.22733 -0.02667) (xy -0.2286 -0.0381) (xy -0.22733 -0.04953) (xy -0.22733 -0.05969)
						(xy -0.22606 -0.07112) (xy -0.22352 -0.08128) (xy -0.22225 -0.09144) (xy -0.21844 -0.10287) (xy -0.2159 -0.11303)
						(xy -0.21209 -0.12319) (xy -0.20701 -0.13335) (xy -0.2032 -0.14224) (xy -0.19812 -0.1524) (xy -0.17272 -0.18796)
						(xy -0.1651 -0.19558) (xy -0.1651 -0.7366) (xy -0.16256 -0.76835) (xy -0.1524 -0.8001) (xy -0.13716 -0.82804)
						(xy -0.11684 -0.85344) (xy -0.09144 -0.87376) (xy -0.0635 -0.889) (xy -0.03175 -0.89916) (xy 0 -0.9017)
						(xy 0.03175 -0.89916) (xy 0.0635 -0.889) (xy 0.09144 -0.87376) (xy 0.11684 -0.85344) (xy 0.13716 -0.82804)
						(xy 0.1524 -0.8001) (xy 0.16256 -0.76835) (xy 0.1651 -0.7366) (xy 0.1651 -0.19685) (xy 0.17272 -0.18923)
						(xy 0.17907 -0.18034) (xy 0.18669 -0.17145) (xy 0.19177 -0.16256) (xy 0.19812 -0.15367) (xy 0.20828 -0.13335)
						(xy 0.21971 -0.10287) (xy 0.22225 -0.09271) (xy 0.22479 -0.08128) (xy 0.22606 -0.07112) (xy 0.2286 -0.05969)
						(xy 0.2286 -0.01651) (xy 0.22606 -0.00508) (xy 0.22479 0.00508) (xy 0.22225 0.01651) (xy 0.21971 0.02667)
						(xy 0.20828 0.05715) (xy 0.19812 0.07747) (xy 0.19177 0.08636) (xy 0.18669 0.09525) (xy 0.17907 0.10414)
						(xy 0.17272 0.11303) (xy 0.1651 0.12065) (xy 0.1651 0.7366) (xy 0.16256 0.76835) (xy 0.1524 0.8001)
						(xy 0.13716 0.82804) (xy 0.11684 0.85344) (xy 0.09144 0.87376) (xy 0.0635 0.889) (xy 0.03175 0.89916)
					)
					(width 0)
					(fill yes)
				)
			)
		)
		(pad "184" smd custom
			(at 25.649936 -4.106672)
			(size 0.1143 0.1143)
			(layers "F.Cu" "F.Mask" "F.Paste")
			(net "GND")
			(options
				(clearance outline)
				(anchor circle)
			)
			(primitives
				(gr_poly
					(pts
						(xy 0 0.9017) (xy -0.03175 0.89916) (xy -0.0635 0.889) (xy -0.09144 0.87376) (xy -0.11684 0.85344)
						(xy -0.13716 0.82804) (xy -0.1524 0.8001) (xy -0.16256 0.76835) (xy -0.1651 0.7366) (xy -0.1651 0.19685)
						(xy -0.17272 0.18923) (xy -0.17907 0.18034) (xy -0.18669 0.17145) (xy -0.19177 0.16256) (xy -0.19812 0.15367)
						(xy -0.20828 0.13335) (xy -0.21971 0.10287) (xy -0.22225 0.09271) (xy -0.22479 0.08128) (xy -0.22606 0.07112)
						(xy -0.2286 0.05969) (xy -0.2286 0.01651) (xy -0.22606 0.00508) (xy -0.22479 -0.00508) (xy -0.22225 -0.01651)
						(xy -0.21971 -0.02667) (xy -0.20828 -0.05715) (xy -0.19812 -0.07747) (xy -0.19177 -0.08636) (xy -0.18669 -0.09525)
						(xy -0.17907 -0.10414) (xy -0.17272 -0.11303) (xy -0.1651 -0.12065) (xy -0.1651 -0.7366) (xy -0.16256 -0.76835)
						(xy -0.1524 -0.8001) (xy -0.13716 -0.82804) (xy -0.11684 -0.85344) (xy -0.09144 -0.87376) (xy -0.0635 -0.889)
						(xy -0.03175 -0.89916) (xy 0 -0.9017) (xy 0.03175 -0.89916) (xy 0.0635 -0.889) (xy 0.09144 -0.87376)
						(xy 0.11684 -0.85344) (xy 0.13716 -0.82804) (xy 0.1524 -0.8001) (xy 0.16256 -0.76835) (xy 0.1651 -0.7366)
						(xy 0.1651 -0.11938) (xy 0.17272 -0.11176) (xy 0.19812 -0.0762) (xy 0.2032 -0.06604) (xy 0.20701 -0.05715)
						(xy 0.21209 -0.04699) (xy 0.2159 -0.03683) (xy 0.21844 -0.02667) (xy 0.22225 -0.01524) (xy 0.22352 -0.00508)
						(xy 0.22606 0.00508) (xy 0.22733 0.01651) (xy 0.22733 0.02667) (xy 0.2286 0.0381) (xy 0.22733 0.04953)
						(xy 0.22733 0.05969) (xy 0.22606 0.07112) (xy 0.22352 0.08128) (xy 0.22225 0.09144) (xy 0.21844 0.10287)
						(xy 0.2159 0.11303) (xy 0.21209 0.12319) (xy 0.20701 0.13335) (xy 0.2032 0.14224) (xy 0.19812 0.1524)
						(xy 0.17272 0.18796) (xy 0.1651 0.19558) (xy 0.1651 0.7366) (xy 0.16256 0.76835) (xy 0.1524 0.8001)
						(xy 0.13716 0.82804) (xy 0.11684 0.85344) (xy 0.09144 0.87376) (xy 0.0635 0.889) (xy 0.03175 0.89916)
					)
					(width 0)
					(fill yes)
				)
			)
		)
		(pad "185" smd custom
			(at 25.94991 4.106672)
			(size 0.1143 0.1143)
			(layers "F.Cu" "F.Mask" "F.Paste")
			(net "M_B_DQ61")
			(options
				(clearance outline)
				(anchor circle)
			)
			(primitives
				(gr_poly
					(pts
						(xy 0 0.9017) (xy -0.03175 0.89916) (xy -0.0635 0.889) (xy -0.09144 0.87376) (xy -0.11684 0.85344)
						(xy -0.13716 0.82804) (xy -0.1524 0.8001) (xy -0.16256 0.76835) (xy -0.1651 0.7366) (xy -0.1651 -0.13462)
						(xy -0.17272 -0.14224) (xy -0.19812 -0.1778) (xy -0.2032 -0.18796) (xy -0.20701 -0.19685) (xy -0.21209 -0.20701)
						(xy -0.2159 -0.21717) (xy -0.21844 -0.22733) (xy -0.22225 -0.23876) (xy -0.22352 -0.24892) (xy -0.22606 -0.25908)
						(xy -0.22733 -0.27051) (xy -0.22733 -0.28067) (xy -0.2286 -0.2921) (xy -0.22733 -0.30353) (xy -0.22733 -0.31369)
						(xy -0.22606 -0.32512) (xy -0.22352 -0.33528) (xy -0.22225 -0.34544) (xy -0.21844 -0.35687) (xy -0.2159 -0.36703)
						(xy -0.21209 -0.37719) (xy -0.20701 -0.38735) (xy -0.2032 -0.39624) (xy -0.19812 -0.4064) (xy -0.17272 -0.44196)
						(xy -0.1651 -0.44958) (xy -0.1651 -0.7366) (xy -0.16256 -0.76835) (xy -0.1524 -0.8001) (xy -0.13716 -0.82804)
						(xy -0.11684 -0.85344) (xy -0.09144 -0.87376) (xy -0.0635 -0.889) (xy -0.03175 -0.89916) (xy 0 -0.9017)
						(xy 0.03175 -0.89916) (xy 0.0635 -0.889) (xy 0.09144 -0.87376) (xy 0.11684 -0.85344) (xy 0.13716 -0.82804)
						(xy 0.1524 -0.8001) (xy 0.16256 -0.76835) (xy 0.1651 -0.7366) (xy 0.1651 -0.44958) (xy 0.17272 -0.44196)
						(xy 0.19812 -0.4064) (xy 0.2032 -0.39624) (xy 0.20701 -0.38735) (xy 0.21209 -0.37719) (xy 0.2159 -0.36703)
						(xy 0.21844 -0.35687) (xy 0.22225 -0.34544) (xy 0.22352 -0.33528) (xy 0.22606 -0.32512) (xy 0.22733 -0.31369)
						(xy 0.22733 -0.30353) (xy 0.2286 -0.2921) (xy 0.22733 -0.28067) (xy 0.22733 -0.27051) (xy 0.22606 -0.25908)
						(xy 0.22352 -0.24892) (xy 0.22225 -0.23876) (xy 0.21844 -0.22733) (xy 0.2159 -0.21717) (xy 0.21209 -0.20701)
						(xy 0.20701 -0.19685) (xy 0.2032 -0.18796) (xy 0.19812 -0.1778) (xy 0.17272 -0.14224) (xy 0.1651 -0.13462)
						(xy 0.1651 0.7366) (xy 0.16256 0.76835) (xy 0.1524 0.8001) (xy 0.13716 0.82804) (xy 0.11684 0.85344)
						(xy 0.09144 0.87376) (xy 0.0635 0.889) (xy 0.03175 0.89916)
					)
					(width 0)
					(fill yes)
				)
			)
		)
		(pad "186" smd custom
			(at 26.249884 -4.106672)
			(size 0.1143 0.1143)
			(layers "F.Cu" "F.Mask" "F.Paste")
			(net "M_B_DQS_DN7")
			(options
				(clearance outline)
				(anchor circle)
			)
			(primitives
				(gr_poly
					(pts
						(xy 0 0.9017) (xy -0.03175 0.89916) (xy -0.0635 0.889) (xy -0.09144 0.87376) (xy -0.11684 0.85344)
						(xy -0.13716 0.82804) (xy -0.1524 0.8001) (xy -0.16256 0.76835) (xy -0.1651 0.7366) (xy -0.1651 0.44958)
						(xy -0.17272 0.44196) (xy -0.19812 0.4064) (xy -0.2032 0.39624) (xy -0.20701 0.38735) (xy -0.21209 0.37719)
						(xy -0.2159 0.36703) (xy -0.21844 0.35687) (xy -0.22225 0.34544) (xy -0.22352 0.33528) (xy -0.22606 0.32512)
						(xy -0.22733 0.31369) (xy -0.22733 0.30353) (xy -0.2286 0.2921) (xy -0.22733 0.28067) (xy -0.22733 0.27051)
						(xy -0.22606 0.25908) (xy -0.22352 0.24892) (xy -0.22225 0.23876) (xy -0.21844 0.22733) (xy -0.2159 0.21717)
						(xy -0.21209 0.20701) (xy -0.20701 0.19685) (xy -0.2032 0.18796) (xy -0.19812 0.1778) (xy -0.17272 0.14224)
						(xy -0.1651 0.13462) (xy -0.1651 -0.7366) (xy -0.16256 -0.76835) (xy -0.1524 -0.8001) (xy -0.13716 -0.82804)
						(xy -0.11684 -0.85344) (xy -0.09144 -0.87376) (xy -0.0635 -0.889) (xy -0.03175 -0.89916) (xy 0 -0.9017)
						(xy 0.03175 -0.89916) (xy 0.0635 -0.889) (xy 0.09144 -0.87376) (xy 0.11684 -0.85344) (xy 0.13716 -0.82804)
						(xy 0.1524 -0.8001) (xy 0.16256 -0.76835) (xy 0.1651 -0.7366) (xy 0.1651 0.13462) (xy 0.17272 0.14224)
						(xy 0.19812 0.1778) (xy 0.2032 0.18796) (xy 0.20701 0.19685) (xy 0.21209 0.20701) (xy 0.2159 0.21717)
						(xy 0.21844 0.22733) (xy 0.22225 0.23876) (xy 0.22352 0.24892) (xy 0.22606 0.25908) (xy 0.22733 0.27051)
						(xy 0.22733 0.28067) (xy 0.2286 0.2921) (xy 0.22733 0.30353) (xy 0.22733 0.31369) (xy 0.22606 0.32512)
						(xy 0.22352 0.33528) (xy 0.22225 0.34544) (xy 0.21844 0.35687) (xy 0.2159 0.36703) (xy 0.21209 0.37719)
						(xy 0.20701 0.38735) (xy 0.2032 0.39624) (xy 0.19812 0.4064) (xy 0.17272 0.44196) (xy 0.1651 0.44958)
						(xy 0.1651 0.7366) (xy 0.16256 0.76835) (xy 0.1524 0.8001) (xy 0.13716 0.82804) (xy 0.11684 0.85344)
						(xy 0.09144 0.87376) (xy 0.0635 0.889) (xy 0.03175 0.89916)
					)
					(width 0)
					(fill yes)
				)
			)
		)
		(pad "187" smd custom
			(at 26.550112 4.106672)
			(size 0.1143 0.1143)
			(layers "F.Cu" "F.Mask" "F.Paste")
			(net "GND")
			(options
				(clearance outline)
				(anchor circle)
			)
			(primitives
				(gr_poly
					(pts
						(xy 0 0.9017) (xy -0.03175 0.89916) (xy -0.0635 0.889) (xy -0.09144 0.87376) (xy -0.11684 0.85344)
						(xy -0.13716 0.82804) (xy -0.1524 0.8001) (xy -0.16256 0.76835) (xy -0.1651 0.7366) (xy -0.1651 0.11938)
						(xy -0.17272 0.11176) (xy -0.19812 0.0762) (xy -0.2032 0.06604) (xy -0.20701 0.05715) (xy -0.21209 0.04699)
						(xy -0.2159 0.03683) (xy -0.21844 0.02667) (xy -0.22225 0.01524) (xy -0.22352 0.00508) (xy -0.22606 -0.00508)
						(xy -0.22733 -0.01651) (xy -0.22733 -0.02667) (xy -0.2286 -0.0381) (xy -0.22733 -0.04953) (xy -0.22733 -0.05969)
						(xy -0.22606 -0.07112) (xy -0.22352 -0.08128) (xy -0.22225 -0.09144) (xy -0.21844 -0.10287) (xy -0.2159 -0.11303)
						(xy -0.21209 -0.12319) (xy -0.20701 -0.13335) (xy -0.2032 -0.14224) (xy -0.19812 -0.1524) (xy -0.17272 -0.18796)
						(xy -0.1651 -0.19558) (xy -0.1651 -0.7366) (xy -0.16256 -0.76835) (xy -0.1524 -0.8001) (xy -0.13716 -0.82804)
						(xy -0.11684 -0.85344) (xy -0.09144 -0.87376) (xy -0.0635 -0.889) (xy -0.03175 -0.89916) (xy 0 -0.9017)
						(xy 0.03175 -0.89916) (xy 0.0635 -0.889) (xy 0.09144 -0.87376) (xy 0.11684 -0.85344) (xy 0.13716 -0.82804)
						(xy 0.1524 -0.8001) (xy 0.16256 -0.76835) (xy 0.1651 -0.7366) (xy 0.1651 -0.19685) (xy 0.17272 -0.18923)
						(xy 0.17907 -0.18034) (xy 0.18669 -0.17145) (xy 0.19177 -0.16256) (xy 0.19812 -0.15367) (xy 0.20828 -0.13335)
						(xy 0.21971 -0.10287) (xy 0.22225 -0.09271) (xy 0.22479 -0.08128) (xy 0.22606 -0.07112) (xy 0.2286 -0.05969)
						(xy 0.2286 -0.01651) (xy 0.22606 -0.00508) (xy 0.22479 0.00508) (xy 0.22225 0.01651) (xy 0.21971 0.02667)
						(xy 0.20828 0.05715) (xy 0.19812 0.07747) (xy 0.19177 0.08636) (xy 0.18669 0.09525) (xy 0.17907 0.10414)
						(xy 0.17272 0.11303) (xy 0.1651 0.12065) (xy 0.1651 0.7366) (xy 0.16256 0.76835) (xy 0.1524 0.8001)
						(xy 0.13716 0.82804) (xy 0.11684 0.85344) (xy 0.09144 0.87376) (xy 0.0635 0.889) (xy 0.03175 0.89916)
					)
					(width 0)
					(fill yes)
				)
			)
		)
		(pad "188" smd custom
			(at 26.850086 -4.106672)
			(size 0.1143 0.1143)
			(layers "F.Cu" "F.Mask" "F.Paste")
			(net "M_B_DQS_DP7")
			(options
				(clearance outline)
				(anchor circle)
			)
			(primitives
				(gr_poly
					(pts
						(xy 0 0.9017) (xy -0.03175 0.89916) (xy -0.0635 0.889) (xy -0.09144 0.87376) (xy -0.11684 0.85344)
						(xy -0.13716 0.82804) (xy -0.1524 0.8001) (xy -0.16256 0.76835) (xy -0.1651 0.7366) (xy -0.1651 0.19685)
						(xy -0.17272 0.18923) (xy -0.17907 0.18034) (xy -0.18669 0.17145) (xy -0.19177 0.16256) (xy -0.19812 0.15367)
						(xy -0.20828 0.13335) (xy -0.21971 0.10287) (xy -0.22225 0.09271) (xy -0.22479 0.08128) (xy -0.22606 0.07112)
						(xy -0.2286 0.05969) (xy -0.2286 0.01651) (xy -0.22606 0.00508) (xy -0.22479 -0.00508) (xy -0.22225 -0.01651)
						(xy -0.21971 -0.02667) (xy -0.20828 -0.05715) (xy -0.19812 -0.07747) (xy -0.19177 -0.08636) (xy -0.18669 -0.09525)
						(xy -0.17907 -0.10414) (xy -0.17272 -0.11303) (xy -0.1651 -0.12065) (xy -0.1651 -0.7366) (xy -0.16256 -0.76835)
						(xy -0.1524 -0.8001) (xy -0.13716 -0.82804) (xy -0.11684 -0.85344) (xy -0.09144 -0.87376) (xy -0.0635 -0.889)
						(xy -0.03175 -0.89916) (xy 0 -0.9017) (xy 0.03175 -0.89916) (xy 0.0635 -0.889) (xy 0.09144 -0.87376)
						(xy 0.11684 -0.85344) (xy 0.13716 -0.82804) (xy 0.1524 -0.8001) (xy 0.16256 -0.76835) (xy 0.1651 -0.7366)
						(xy 0.1651 -0.11938) (xy 0.17272 -0.11176) (xy 0.19812 -0.0762) (xy 0.2032 -0.06604) (xy 0.20701 -0.05715)
						(xy 0.21209 -0.04699) (xy 0.2159 -0.03683) (xy 0.21844 -0.02667) (xy 0.22225 -0.01524) (xy 0.22352 -0.00508)
						(xy 0.22606 0.00508) (xy 0.22733 0.01651) (xy 0.22733 0.02667) (xy 0.2286 0.0381) (xy 0.22733 0.04953)
						(xy 0.22733 0.05969) (xy 0.22606 0.07112) (xy 0.22352 0.08128) (xy 0.22225 0.09144) (xy 0.21844 0.10287)
						(xy 0.2159 0.11303) (xy 0.21209 0.12319) (xy 0.20701 0.13335) (xy 0.2032 0.14224) (xy 0.19812 0.1524)
						(xy 0.17272 0.18796) (xy 0.1651 0.19558) (xy 0.1651 0.7366) (xy 0.16256 0.76835) (xy 0.1524 0.8001)
						(xy 0.13716 0.82804) (xy 0.11684 0.85344) (xy 0.09144 0.87376) (xy 0.0635 0.889) (xy 0.03175 0.89916)
					)
					(width 0)
					(fill yes)
				)
			)
		)
		(pad "189" smd custom
			(at 27.15006 4.106672)
			(size 0.1143 0.1143)
			(layers "F.Cu" "F.Mask" "F.Paste")
			(net "GND")
			(options
				(clearance outline)
				(anchor circle)
			)
			(primitives
				(gr_poly
					(pts
						(xy 0 0.9017) (xy -0.03175 0.89916) (xy -0.0635 0.889) (xy -0.09144 0.87376) (xy -0.11684 0.85344)
						(xy -0.13716 0.82804) (xy -0.1524 0.8001) (xy -0.16256 0.76835) (xy -0.1651 0.7366) (xy -0.1651 -0.13462)
						(xy -0.17272 -0.14224) (xy -0.19812 -0.1778) (xy -0.2032 -0.18796) (xy -0.20701 -0.19685) (xy -0.21209 -0.20701)
						(xy -0.2159 -0.21717) (xy -0.21844 -0.22733) (xy -0.22225 -0.23876) (xy -0.22352 -0.24892) (xy -0.22606 -0.25908)
						(xy -0.22733 -0.27051) (xy -0.22733 -0.28067) (xy -0.2286 -0.2921) (xy -0.22733 -0.30353) (xy -0.22733 -0.31369)
						(xy -0.22606 -0.32512) (xy -0.22352 -0.33528) (xy -0.22225 -0.34544) (xy -0.21844 -0.35687) (xy -0.2159 -0.36703)
						(xy -0.21209 -0.37719) (xy -0.20701 -0.38735) (xy -0.2032 -0.39624) (xy -0.19812 -0.4064) (xy -0.17272 -0.44196)
						(xy -0.1651 -0.44958) (xy -0.1651 -0.7366) (xy -0.16256 -0.76835) (xy -0.1524 -0.8001) (xy -0.13716 -0.82804)
						(xy -0.11684 -0.85344) (xy -0.09144 -0.87376) (xy -0.0635 -0.889) (xy -0.03175 -0.89916) (xy 0 -0.9017)
						(xy 0.03175 -0.89916) (xy 0.0635 -0.889) (xy 0.09144 -0.87376) (xy 0.11684 -0.85344) (xy 0.13716 -0.82804)
						(xy 0.1524 -0.8001) (xy 0.16256 -0.76835) (xy 0.1651 -0.7366) (xy 0.1651 -0.44958) (xy 0.17272 -0.44196)
						(xy 0.19812 -0.4064) (xy 0.2032 -0.39624) (xy 0.20701 -0.38735) (xy 0.21209 -0.37719) (xy 0.2159 -0.36703)
						(xy 0.21844 -0.35687) (xy 0.22225 -0.34544) (xy 0.22352 -0.33528) (xy 0.22606 -0.32512) (xy 0.22733 -0.31369)
						(xy 0.22733 -0.30353) (xy 0.2286 -0.2921) (xy 0.22733 -0.28067) (xy 0.22733 -0.27051) (xy 0.22606 -0.25908)
						(xy 0.22352 -0.24892) (xy 0.22225 -0.23876) (xy 0.21844 -0.22733) (xy 0.2159 -0.21717) (xy 0.21209 -0.20701)
						(xy 0.20701 -0.19685) (xy 0.2032 -0.18796) (xy 0.19812 -0.1778) (xy 0.17272 -0.14224) (xy 0.1651 -0.13462)
						(xy 0.1651 0.7366) (xy 0.16256 0.76835) (xy 0.1524 0.8001) (xy 0.13716 0.82804) (xy 0.11684 0.85344)
						(xy 0.09144 0.87376) (xy 0.0635 0.889) (xy 0.03175 0.89916)
					)
					(width 0)
					(fill yes)
				)
			)
		)
		(pad "190" smd custom
			(at 27.450034 -4.106672)
			(size 0.1143 0.1143)
			(layers "F.Cu" "F.Mask" "F.Paste")
			(net "GND")
			(options
				(clearance outline)
				(anchor circle)
			)
			(primitives
				(gr_poly
					(pts
						(xy 0 0.9017) (xy -0.03175 0.89916) (xy -0.0635 0.889) (xy -0.09144 0.87376) (xy -0.11684 0.85344)
						(xy -0.13716 0.82804) (xy -0.1524 0.8001) (xy -0.16256 0.76835) (xy -0.1651 0.7366) (xy -0.1651 0.44958)
						(xy -0.17272 0.44196) (xy -0.19812 0.4064) (xy -0.2032 0.39624) (xy -0.20701 0.38735) (xy -0.21209 0.37719)
						(xy -0.2159 0.36703) (xy -0.21844 0.35687) (xy -0.22225 0.34544) (xy -0.22352 0.33528) (xy -0.22606 0.32512)
						(xy -0.22733 0.31369) (xy -0.22733 0.30353) (xy -0.2286 0.2921) (xy -0.22733 0.28067) (xy -0.22733 0.27051)
						(xy -0.22606 0.25908) (xy -0.22352 0.24892) (xy -0.22225 0.23876) (xy -0.21844 0.22733) (xy -0.2159 0.21717)
						(xy -0.21209 0.20701) (xy -0.20701 0.19685) (xy -0.2032 0.18796) (xy -0.19812 0.1778) (xy -0.17272 0.14224)
						(xy -0.1651 0.13462) (xy -0.1651 -0.7366) (xy -0.16256 -0.76835) (xy -0.1524 -0.8001) (xy -0.13716 -0.82804)
						(xy -0.11684 -0.85344) (xy -0.09144 -0.87376) (xy -0.0635 -0.889) (xy -0.03175 -0.89916) (xy 0 -0.9017)
						(xy 0.03175 -0.89916) (xy 0.0635 -0.889) (xy 0.09144 -0.87376) (xy 0.11684 -0.85344) (xy 0.13716 -0.82804)
						(xy 0.1524 -0.8001) (xy 0.16256 -0.76835) (xy 0.1651 -0.7366) (xy 0.1651 0.13462) (xy 0.17272 0.14224)
						(xy 0.19812 0.1778) (xy 0.2032 0.18796) (xy 0.20701 0.19685) (xy 0.21209 0.20701) (xy 0.2159 0.21717)
						(xy 0.21844 0.22733) (xy 0.22225 0.23876) (xy 0.22352 0.24892) (xy 0.22606 0.25908) (xy 0.22733 0.27051)
						(xy 0.22733 0.28067) (xy 0.2286 0.2921) (xy 0.22733 0.30353) (xy 0.22733 0.31369) (xy 0.22606 0.32512)
						(xy 0.22352 0.33528) (xy 0.22225 0.34544) (xy 0.21844 0.35687) (xy 0.2159 0.36703) (xy 0.21209 0.37719)
						(xy 0.20701 0.38735) (xy 0.2032 0.39624) (xy 0.19812 0.4064) (xy 0.17272 0.44196) (xy 0.1651 0.44958)
						(xy 0.1651 0.7366) (xy 0.16256 0.76835) (xy 0.1524 0.8001) (xy 0.13716 0.82804) (xy 0.11684 0.85344)
						(xy 0.09144 0.87376) (xy 0.0635 0.889) (xy 0.03175 0.89916)
					)
					(width 0)
					(fill yes)
				)
			)
		)
		(pad "191" smd custom
			(at 27.750008 4.106672)
			(size 0.1143 0.1143)
			(layers "F.Cu" "F.Mask" "F.Paste")
			(net "M_B_DQ62")
			(options
				(clearance outline)
				(anchor circle)
			)
			(primitives
				(gr_poly
					(pts
						(xy 0 0.9017) (xy -0.03175 0.89916) (xy -0.0635 0.889) (xy -0.09144 0.87376) (xy -0.11684 0.85344)
						(xy -0.13716 0.82804) (xy -0.1524 0.8001) (xy -0.16256 0.76835) (xy -0.1651 0.7366) (xy -0.1651 0.11938)
						(xy -0.17272 0.11176) (xy -0.19812 0.0762) (xy -0.2032 0.06604) (xy -0.20701 0.05715) (xy -0.21209 0.04699)
						(xy -0.2159 0.03683) (xy -0.21844 0.02667) (xy -0.22225 0.01524) (xy -0.22352 0.00508) (xy -0.22606 -0.00508)
						(xy -0.22733 -0.01651) (xy -0.22733 -0.02667) (xy -0.2286 -0.0381) (xy -0.22733 -0.04953) (xy -0.22733 -0.05969)
						(xy -0.22606 -0.07112) (xy -0.22352 -0.08128) (xy -0.22225 -0.09144) (xy -0.21844 -0.10287) (xy -0.2159 -0.11303)
						(xy -0.21209 -0.12319) (xy -0.20701 -0.13335) (xy -0.2032 -0.14224) (xy -0.19812 -0.1524) (xy -0.17272 -0.18796)
						(xy -0.1651 -0.19558) (xy -0.1651 -0.7366) (xy -0.16256 -0.76835) (xy -0.1524 -0.8001) (xy -0.13716 -0.82804)
						(xy -0.11684 -0.85344) (xy -0.09144 -0.87376) (xy -0.0635 -0.889) (xy -0.03175 -0.89916) (xy 0 -0.9017)
						(xy 0.03175 -0.89916) (xy 0.0635 -0.889) (xy 0.09144 -0.87376) (xy 0.11684 -0.85344) (xy 0.13716 -0.82804)
						(xy 0.1524 -0.8001) (xy 0.16256 -0.76835) (xy 0.1651 -0.7366) (xy 0.1651 -0.19685) (xy 0.17272 -0.18923)
						(xy 0.17907 -0.18034) (xy 0.18669 -0.17145) (xy 0.19177 -0.16256) (xy 0.19812 -0.15367) (xy 0.20828 -0.13335)
						(xy 0.21971 -0.10287) (xy 0.22225 -0.09271) (xy 0.22479 -0.08128) (xy 0.22606 -0.07112) (xy 0.2286 -0.05969)
						(xy 0.2286 -0.01651) (xy 0.22606 -0.00508) (xy 0.22479 0.00508) (xy 0.22225 0.01651) (xy 0.21971 0.02667)
						(xy 0.20828 0.05715) (xy 0.19812 0.07747) (xy 0.19177 0.08636) (xy 0.18669 0.09525) (xy 0.17907 0.10414)
						(xy 0.17272 0.11303) (xy 0.1651 0.12065) (xy 0.1651 0.7366) (xy 0.16256 0.76835) (xy 0.1524 0.8001)
						(xy 0.13716 0.82804) (xy 0.11684 0.85344) (xy 0.09144 0.87376) (xy 0.0635 0.889) (xy 0.03175 0.89916)
					)
					(width 0)
					(fill yes)
				)
			)
		)
		(pad "192" smd custom
			(at 28.049982 -4.106672)
			(size 0.1143 0.1143)
			(layers "F.Cu" "F.Mask" "F.Paste")
			(net "M_B_DQ58")
			(options
				(clearance outline)
				(anchor circle)
			)
			(primitives
				(gr_poly
					(pts
						(xy 0 0.9017) (xy -0.03175 0.89916) (xy -0.0635 0.889) (xy -0.09144 0.87376) (xy -0.11684 0.85344)
						(xy -0.13716 0.82804) (xy -0.1524 0.8001) (xy -0.16256 0.76835) (xy -0.1651 0.7366) (xy -0.1651 0.19685)
						(xy -0.17272 0.18923) (xy -0.17907 0.18034) (xy -0.18669 0.17145) (xy -0.19177 0.16256) (xy -0.19812 0.15367)
						(xy -0.20828 0.13335) (xy -0.21971 0.10287) (xy -0.22225 0.09271) (xy -0.22479 0.08128) (xy -0.22606 0.07112)
						(xy -0.2286 0.05969) (xy -0.2286 0.01651) (xy -0.22606 0.00508) (xy -0.22479 -0.00508) (xy -0.22225 -0.01651)
						(xy -0.21971 -0.02667) (xy -0.20828 -0.05715) (xy -0.19812 -0.07747) (xy -0.19177 -0.08636) (xy -0.18669 -0.09525)
						(xy -0.17907 -0.10414) (xy -0.17272 -0.11303) (xy -0.1651 -0.12065) (xy -0.1651 -0.7366) (xy -0.16256 -0.76835)
						(xy -0.1524 -0.8001) (xy -0.13716 -0.82804) (xy -0.11684 -0.85344) (xy -0.09144 -0.87376) (xy -0.0635 -0.889)
						(xy -0.03175 -0.89916) (xy 0 -0.9017) (xy 0.03175 -0.89916) (xy 0.0635 -0.889) (xy 0.09144 -0.87376)
						(xy 0.11684 -0.85344) (xy 0.13716 -0.82804) (xy 0.1524 -0.8001) (xy 0.16256 -0.76835) (xy 0.1651 -0.7366)
						(xy 0.1651 -0.11938) (xy 0.17272 -0.11176) (xy 0.19812 -0.0762) (xy 0.2032 -0.06604) (xy 0.20701 -0.05715)
						(xy 0.21209 -0.04699) (xy 0.2159 -0.03683) (xy 0.21844 -0.02667) (xy 0.22225 -0.01524) (xy 0.22352 -0.00508)
						(xy 0.22606 0.00508) (xy 0.22733 0.01651) (xy 0.22733 0.02667) (xy 0.2286 0.0381) (xy 0.22733 0.04953)
						(xy 0.22733 0.05969) (xy 0.22606 0.07112) (xy 0.22352 0.08128) (xy 0.22225 0.09144) (xy 0.21844 0.10287)
						(xy 0.2159 0.11303) (xy 0.21209 0.12319) (xy 0.20701 0.13335) (xy 0.2032 0.14224) (xy 0.19812 0.1524)
						(xy 0.17272 0.18796) (xy 0.1651 0.19558) (xy 0.1651 0.7366) (xy 0.16256 0.76835) (xy 0.1524 0.8001)
						(xy 0.13716 0.82804) (xy 0.11684 0.85344) (xy 0.09144 0.87376) (xy 0.0635 0.889) (xy 0.03175 0.89916)
					)
					(width 0)
					(fill yes)
				)
			)
		)
		(pad "193" smd custom
			(at 28.349956 4.106672)
			(size 0.1143 0.1143)
			(layers "F.Cu" "F.Mask" "F.Paste")
			(net "M_B_DQ63")
			(options
				(clearance outline)
				(anchor circle)
			)
			(primitives
				(gr_poly
					(pts
						(xy 0 0.9017) (xy -0.03175 0.89916) (xy -0.0635 0.889) (xy -0.09144 0.87376) (xy -0.11684 0.85344)
						(xy -0.13716 0.82804) (xy -0.1524 0.8001) (xy -0.16256 0.76835) (xy -0.1651 0.7366) (xy -0.1651 -0.13462)
						(xy -0.17272 -0.14224) (xy -0.19812 -0.1778) (xy -0.2032 -0.18796) (xy -0.20701 -0.19685) (xy -0.21209 -0.20701)
						(xy -0.2159 -0.21717) (xy -0.21844 -0.22733) (xy -0.22225 -0.23876) (xy -0.22352 -0.24892) (xy -0.22606 -0.25908)
						(xy -0.22733 -0.27051) (xy -0.22733 -0.28067) (xy -0.2286 -0.2921) (xy -0.22733 -0.30353) (xy -0.22733 -0.31369)
						(xy -0.22606 -0.32512) (xy -0.22352 -0.33528) (xy -0.22225 -0.34544) (xy -0.21844 -0.35687) (xy -0.2159 -0.36703)
						(xy -0.21209 -0.37719) (xy -0.20701 -0.38735) (xy -0.2032 -0.39624) (xy -0.19812 -0.4064) (xy -0.17272 -0.44196)
						(xy -0.1651 -0.44958) (xy -0.1651 -0.7366) (xy -0.16256 -0.76835) (xy -0.1524 -0.8001) (xy -0.13716 -0.82804)
						(xy -0.11684 -0.85344) (xy -0.09144 -0.87376) (xy -0.0635 -0.889) (xy -0.03175 -0.89916) (xy 0 -0.9017)
						(xy 0.03175 -0.89916) (xy 0.0635 -0.889) (xy 0.09144 -0.87376) (xy 0.11684 -0.85344) (xy 0.13716 -0.82804)
						(xy 0.1524 -0.8001) (xy 0.16256 -0.76835) (xy 0.1651 -0.7366) (xy 0.1651 -0.44958) (xy 0.17272 -0.44196)
						(xy 0.19812 -0.4064) (xy 0.2032 -0.39624) (xy 0.20701 -0.38735) (xy 0.21209 -0.37719) (xy 0.2159 -0.36703)
						(xy 0.21844 -0.35687) (xy 0.22225 -0.34544) (xy 0.22352 -0.33528) (xy 0.22606 -0.32512) (xy 0.22733 -0.31369)
						(xy 0.22733 -0.30353) (xy 0.2286 -0.2921) (xy 0.22733 -0.28067) (xy 0.22733 -0.27051) (xy 0.22606 -0.25908)
						(xy 0.22352 -0.24892) (xy 0.22225 -0.23876) (xy 0.21844 -0.22733) (xy 0.2159 -0.21717) (xy 0.21209 -0.20701)
						(xy 0.20701 -0.19685) (xy 0.2032 -0.18796) (xy 0.19812 -0.1778) (xy 0.17272 -0.14224) (xy 0.1651 -0.13462)
						(xy 0.1651 0.7366) (xy 0.16256 0.76835) (xy 0.1524 0.8001) (xy 0.13716 0.82804) (xy 0.11684 0.85344)
						(xy 0.09144 0.87376) (xy 0.0635 0.889) (xy 0.03175 0.89916)
					)
					(width 0)
					(fill yes)
				)
			)
		)
		(pad "194" smd custom
			(at 28.64993 -4.106672)
			(size 0.1143 0.1143)
			(layers "F.Cu" "F.Mask" "F.Paste")
			(net "M_B_DQ59")
			(options
				(clearance outline)
				(anchor circle)
			)
			(primitives
				(gr_poly
					(pts
						(xy 0 0.9017) (xy -0.03175 0.89916) (xy -0.0635 0.889) (xy -0.09144 0.87376) (xy -0.11684 0.85344)
						(xy -0.13716 0.82804) (xy -0.1524 0.8001) (xy -0.16256 0.76835) (xy -0.1651 0.7366) (xy -0.1651 0.44958)
						(xy -0.17272 0.44196) (xy -0.19812 0.4064) (xy -0.2032 0.39624) (xy -0.20701 0.38735) (xy -0.21209 0.37719)
						(xy -0.2159 0.36703) (xy -0.21844 0.35687) (xy -0.22225 0.34544) (xy -0.22352 0.33528) (xy -0.22606 0.32512)
						(xy -0.22733 0.31369) (xy -0.22733 0.30353) (xy -0.2286 0.2921) (xy -0.22733 0.28067) (xy -0.22733 0.27051)
						(xy -0.22606 0.25908) (xy -0.22352 0.24892) (xy -0.22225 0.23876) (xy -0.21844 0.22733) (xy -0.2159 0.21717)
						(xy -0.21209 0.20701) (xy -0.20701 0.19685) (xy -0.2032 0.18796) (xy -0.19812 0.1778) (xy -0.17272 0.14224)
						(xy -0.1651 0.13462) (xy -0.1651 -0.7366) (xy -0.16256 -0.76835) (xy -0.1524 -0.8001) (xy -0.13716 -0.82804)
						(xy -0.11684 -0.85344) (xy -0.09144 -0.87376) (xy -0.0635 -0.889) (xy -0.03175 -0.89916) (xy 0 -0.9017)
						(xy 0.03175 -0.89916) (xy 0.0635 -0.889) (xy 0.09144 -0.87376) (xy 0.11684 -0.85344) (xy 0.13716 -0.82804)
						(xy 0.1524 -0.8001) (xy 0.16256 -0.76835) (xy 0.1651 -0.7366) (xy 0.1651 0.13462) (xy 0.17272 0.14224)
						(xy 0.19812 0.1778) (xy 0.2032 0.18796) (xy 0.20701 0.19685) (xy 0.21209 0.20701) (xy 0.2159 0.21717)
						(xy 0.21844 0.22733) (xy 0.22225 0.23876) (xy 0.22352 0.24892) (xy 0.22606 0.25908) (xy 0.22733 0.27051)
						(xy 0.22733 0.28067) (xy 0.2286 0.2921) (xy 0.22733 0.30353) (xy 0.22733 0.31369) (xy 0.22606 0.32512)
						(xy 0.22352 0.33528) (xy 0.22225 0.34544) (xy 0.21844 0.35687) (xy 0.2159 0.36703) (xy 0.21209 0.37719)
						(xy 0.20701 0.38735) (xy 0.2032 0.39624) (xy 0.19812 0.4064) (xy 0.17272 0.44196) (xy 0.1651 0.44958)
						(xy 0.1651 0.7366) (xy 0.16256 0.76835) (xy 0.1524 0.8001) (xy 0.13716 0.82804) (xy 0.11684 0.85344)
						(xy 0.09144 0.87376) (xy 0.0635 0.889) (xy 0.03175 0.89916)
					)
					(width 0)
					(fill yes)
				)
			)
		)
		(pad "195" smd custom
			(at 28.949904 4.106672)
			(size 0.1143 0.1143)
			(layers "F.Cu" "F.Mask" "F.Paste")
			(net "GND")
			(options
				(clearance outline)
				(anchor circle)
			)
			(primitives
				(gr_poly
					(pts
						(xy 0 0.9017) (xy -0.03175 0.89916) (xy -0.0635 0.889) (xy -0.09144 0.87376) (xy -0.11684 0.85344)
						(xy -0.13716 0.82804) (xy -0.1524 0.8001) (xy -0.16256 0.76835) (xy -0.1651 0.7366) (xy -0.1651 0.11938)
						(xy -0.17272 0.11176) (xy -0.19812 0.0762) (xy -0.2032 0.06604) (xy -0.20701 0.05715) (xy -0.21209 0.04699)
						(xy -0.2159 0.03683) (xy -0.21844 0.02667) (xy -0.22225 0.01524) (xy -0.22352 0.00508) (xy -0.22606 -0.00508)
						(xy -0.22733 -0.01651) (xy -0.22733 -0.02667) (xy -0.2286 -0.0381) (xy -0.22733 -0.04953) (xy -0.22733 -0.05969)
						(xy -0.22606 -0.07112) (xy -0.22352 -0.08128) (xy -0.22225 -0.09144) (xy -0.21844 -0.10287) (xy -0.2159 -0.11303)
						(xy -0.21209 -0.12319) (xy -0.20701 -0.13335) (xy -0.2032 -0.14224) (xy -0.19812 -0.1524) (xy -0.17272 -0.18796)
						(xy -0.1651 -0.19558) (xy -0.1651 -0.7366) (xy -0.16256 -0.76835) (xy -0.1524 -0.8001) (xy -0.13716 -0.82804)
						(xy -0.11684 -0.85344) (xy -0.09144 -0.87376) (xy -0.0635 -0.889) (xy -0.03175 -0.89916) (xy 0 -0.9017)
						(xy 0.03175 -0.89916) (xy 0.0635 -0.889) (xy 0.09144 -0.87376) (xy 0.11684 -0.85344) (xy 0.13716 -0.82804)
						(xy 0.1524 -0.8001) (xy 0.16256 -0.76835) (xy 0.1651 -0.7366) (xy 0.1651 -0.19685) (xy 0.17272 -0.18923)
						(xy 0.17907 -0.18034) (xy 0.18669 -0.17145) (xy 0.19177 -0.16256) (xy 0.19812 -0.15367) (xy 0.20828 -0.13335)
						(xy 0.21971 -0.10287) (xy 0.22225 -0.09271) (xy 0.22479 -0.08128) (xy 0.22606 -0.07112) (xy 0.2286 -0.05969)
						(xy 0.2286 -0.01651) (xy 0.22606 -0.00508) (xy 0.22479 0.00508) (xy 0.22225 0.01651) (xy 0.21971 0.02667)
						(xy 0.20828 0.05715) (xy 0.19812 0.07747) (xy 0.19177 0.08636) (xy 0.18669 0.09525) (xy 0.17907 0.10414)
						(xy 0.17272 0.11303) (xy 0.1651 0.12065) (xy 0.1651 0.7366) (xy 0.16256 0.76835) (xy 0.1524 0.8001)
						(xy 0.13716 0.82804) (xy 0.11684 0.85344) (xy 0.09144 0.87376) (xy 0.0635 0.889) (xy 0.03175 0.89916)
					)
					(width 0)
					(fill yes)
				)
			)
		)
		(pad "196" smd custom
			(at 29.249878 -4.106672)
			(size 0.1143 0.1143)
			(layers "F.Cu" "F.Mask" "F.Paste")
			(net "GND")
			(options
				(clearance outline)
				(anchor circle)
			)
			(primitives
				(gr_poly
					(pts
						(xy 0 0.9017) (xy -0.03175 0.89916) (xy -0.0635 0.889) (xy -0.09144 0.87376) (xy -0.11684 0.85344)
						(xy -0.13716 0.82804) (xy -0.1524 0.8001) (xy -0.16256 0.76835) (xy -0.1651 0.7366) (xy -0.1651 0.19685)
						(xy -0.17272 0.18923) (xy -0.17907 0.18034) (xy -0.18669 0.17145) (xy -0.19177 0.16256) (xy -0.19812 0.15367)
						(xy -0.20828 0.13335) (xy -0.21971 0.10287) (xy -0.22225 0.09271) (xy -0.22479 0.08128) (xy -0.22606 0.07112)
						(xy -0.2286 0.05969) (xy -0.2286 0.01651) (xy -0.22606 0.00508) (xy -0.22479 -0.00508) (xy -0.22225 -0.01651)
						(xy -0.21971 -0.02667) (xy -0.20828 -0.05715) (xy -0.19812 -0.07747) (xy -0.19177 -0.08636) (xy -0.18669 -0.09525)
						(xy -0.17907 -0.10414) (xy -0.17272 -0.11303) (xy -0.1651 -0.12065) (xy -0.1651 -0.7366) (xy -0.16256 -0.76835)
						(xy -0.1524 -0.8001) (xy -0.13716 -0.82804) (xy -0.11684 -0.85344) (xy -0.09144 -0.87376) (xy -0.0635 -0.889)
						(xy -0.03175 -0.89916) (xy 0 -0.9017) (xy 0.03175 -0.89916) (xy 0.0635 -0.889) (xy 0.09144 -0.87376)
						(xy 0.11684 -0.85344) (xy 0.13716 -0.82804) (xy 0.1524 -0.8001) (xy 0.16256 -0.76835) (xy 0.1651 -0.7366)
						(xy 0.1651 -0.11938) (xy 0.17272 -0.11176) (xy 0.19812 -0.0762) (xy 0.2032 -0.06604) (xy 0.20701 -0.05715)
						(xy 0.21209 -0.04699) (xy 0.2159 -0.03683) (xy 0.21844 -0.02667) (xy 0.22225 -0.01524) (xy 0.22352 -0.00508)
						(xy 0.22606 0.00508) (xy 0.22733 0.01651) (xy 0.22733 0.02667) (xy 0.2286 0.0381) (xy 0.22733 0.04953)
						(xy 0.22733 0.05969) (xy 0.22606 0.07112) (xy 0.22352 0.08128) (xy 0.22225 0.09144) (xy 0.21844 0.10287)
						(xy 0.2159 0.11303) (xy 0.21209 0.12319) (xy 0.20701 0.13335) (xy 0.2032 0.14224) (xy 0.19812 0.1524)
						(xy 0.17272 0.18796) (xy 0.1651 0.19558) (xy 0.1651 0.7366) (xy 0.16256 0.76835) (xy 0.1524 0.8001)
						(xy 0.13716 0.82804) (xy 0.11684 0.85344) (xy 0.09144 0.87376) (xy 0.0635 0.889) (xy 0.03175 0.89916)
					)
					(width 0)
					(fill yes)
				)
			)
		)
		(pad "197" smd custom
			(at 29.550106 4.106672)
			(size 0.1143 0.1143)
			(layers "F.Cu" "F.Mask" "F.Paste")
			(net "CHB_1_SA0")
			(options
				(clearance outline)
				(anchor circle)
			)
			(primitives
				(gr_poly
					(pts
						(xy 0 0.9017) (xy -0.03175 0.89916) (xy -0.0635 0.889) (xy -0.09144 0.87376) (xy -0.11684 0.85344)
						(xy -0.13716 0.82804) (xy -0.1524 0.8001) (xy -0.16256 0.76835) (xy -0.1651 0.7366) (xy -0.1651 -0.13462)
						(xy -0.17272 -0.14224) (xy -0.19812 -0.1778) (xy -0.2032 -0.18796) (xy -0.20701 -0.19685) (xy -0.21209 -0.20701)
						(xy -0.2159 -0.21717) (xy -0.21844 -0.22733) (xy -0.22225 -0.23876) (xy -0.22352 -0.24892) (xy -0.22606 -0.25908)
						(xy -0.22733 -0.27051) (xy -0.22733 -0.28067) (xy -0.2286 -0.2921) (xy -0.22733 -0.30353) (xy -0.22733 -0.31369)
						(xy -0.22606 -0.32512) (xy -0.22352 -0.33528) (xy -0.22225 -0.34544) (xy -0.21844 -0.35687) (xy -0.2159 -0.36703)
						(xy -0.21209 -0.37719) (xy -0.20701 -0.38735) (xy -0.2032 -0.39624) (xy -0.19812 -0.4064) (xy -0.17272 -0.44196)
						(xy -0.1651 -0.44958) (xy -0.1651 -0.7366) (xy -0.16256 -0.76835) (xy -0.1524 -0.8001) (xy -0.13716 -0.82804)
						(xy -0.11684 -0.85344) (xy -0.09144 -0.87376) (xy -0.0635 -0.889) (xy -0.03175 -0.89916) (xy 0 -0.9017)
						(xy 0.03175 -0.89916) (xy 0.0635 -0.889) (xy 0.09144 -0.87376) (xy 0.11684 -0.85344) (xy 0.13716 -0.82804)
						(xy 0.1524 -0.8001) (xy 0.16256 -0.76835) (xy 0.1651 -0.7366) (xy 0.1651 -0.44958) (xy 0.17272 -0.44196)
						(xy 0.19812 -0.4064) (xy 0.2032 -0.39624) (xy 0.20701 -0.38735) (xy 0.21209 -0.37719) (xy 0.2159 -0.36703)
						(xy 0.21844 -0.35687) (xy 0.22225 -0.34544) (xy 0.22352 -0.33528) (xy 0.22606 -0.32512) (xy 0.22733 -0.31369)
						(xy 0.22733 -0.30353) (xy 0.2286 -0.2921) (xy 0.22733 -0.28067) (xy 0.22733 -0.27051) (xy 0.22606 -0.25908)
						(xy 0.22352 -0.24892) (xy 0.22225 -0.23876) (xy 0.21844 -0.22733) (xy 0.2159 -0.21717) (xy 0.21209 -0.20701)
						(xy 0.20701 -0.19685) (xy 0.2032 -0.18796) (xy 0.19812 -0.1778) (xy 0.17272 -0.14224) (xy 0.1651 -0.13462)
						(xy 0.1651 0.7366) (xy 0.16256 0.76835) (xy 0.1524 0.8001) (xy 0.13716 0.82804) (xy 0.11684 0.85344)
						(xy 0.09144 0.87376) (xy 0.0635 0.889) (xy 0.03175 0.89916)
					)
					(width 0)
					(fill yes)
				)
			)
		)
		(pad "198" smd custom
			(at 29.85008 -4.106672)
			(size 0.1143 0.1143)
			(layers "F.Cu" "F.Mask" "F.Paste")
			(net "MEMORY_HOT_LV_R#")
			(options
				(clearance outline)
				(anchor circle)
			)
			(primitives
				(gr_poly
					(pts
						(xy 0 0.9017) (xy -0.03175 0.89916) (xy -0.0635 0.889) (xy -0.09144 0.87376) (xy -0.11684 0.85344)
						(xy -0.13716 0.82804) (xy -0.1524 0.8001) (xy -0.16256 0.76835) (xy -0.1651 0.7366) (xy -0.1651 0.44958)
						(xy -0.17272 0.44196) (xy -0.19812 0.4064) (xy -0.2032 0.39624) (xy -0.20701 0.38735) (xy -0.21209 0.37719)
						(xy -0.2159 0.36703) (xy -0.21844 0.35687) (xy -0.22225 0.34544) (xy -0.22352 0.33528) (xy -0.22606 0.32512)
						(xy -0.22733 0.31369) (xy -0.22733 0.30353) (xy -0.2286 0.2921) (xy -0.22733 0.28067) (xy -0.22733 0.27051)
						(xy -0.22606 0.25908) (xy -0.22352 0.24892) (xy -0.22225 0.23876) (xy -0.21844 0.22733) (xy -0.2159 0.21717)
						(xy -0.21209 0.20701) (xy -0.20701 0.19685) (xy -0.2032 0.18796) (xy -0.19812 0.1778) (xy -0.17272 0.14224)
						(xy -0.1651 0.13462) (xy -0.1651 -0.7366) (xy -0.16256 -0.76835) (xy -0.1524 -0.8001) (xy -0.13716 -0.82804)
						(xy -0.11684 -0.85344) (xy -0.09144 -0.87376) (xy -0.0635 -0.889) (xy -0.03175 -0.89916) (xy 0 -0.9017)
						(xy 0.03175 -0.89916) (xy 0.0635 -0.889) (xy 0.09144 -0.87376) (xy 0.11684 -0.85344) (xy 0.13716 -0.82804)
						(xy 0.1524 -0.8001) (xy 0.16256 -0.76835) (xy 0.1651 -0.7366) (xy 0.1651 0.13462) (xy 0.17272 0.14224)
						(xy 0.19812 0.1778) (xy 0.2032 0.18796) (xy 0.20701 0.19685) (xy 0.21209 0.20701) (xy 0.2159 0.21717)
						(xy 0.21844 0.22733) (xy 0.22225 0.23876) (xy 0.22352 0.24892) (xy 0.22606 0.25908) (xy 0.22733 0.27051)
						(xy 0.22733 0.28067) (xy 0.2286 0.2921) (xy 0.22733 0.30353) (xy 0.22733 0.31369) (xy 0.22606 0.32512)
						(xy 0.22352 0.33528) (xy 0.22225 0.34544) (xy 0.21844 0.35687) (xy 0.2159 0.36703) (xy 0.21209 0.37719)
						(xy 0.20701 0.38735) (xy 0.2032 0.39624) (xy 0.19812 0.4064) (xy 0.17272 0.44196) (xy 0.1651 0.44958)
						(xy 0.1651 0.7366) (xy 0.16256 0.76835) (xy 0.1524 0.8001) (xy 0.13716 0.82804) (xy 0.11684 0.85344)
						(xy 0.09144 0.87376) (xy 0.0635 0.889) (xy 0.03175 0.89916)
					)
					(width 0)
					(fill yes)
				)
			)
		)
		(pad "199" smd custom
			(at 30.150054 4.106672)
			(size 0.1143 0.1143)
			(layers "F.Cu" "F.Mask" "F.Paste")
			(net "P3V3_STBY")
			(options
				(clearance outline)
				(anchor circle)
			)
			(primitives
				(gr_poly
					(pts
						(xy 0 0.9017) (xy -0.03175 0.89916) (xy -0.0635 0.889) (xy -0.09144 0.87376) (xy -0.11684 0.85344)
						(xy -0.13716 0.82804) (xy -0.1524 0.8001) (xy -0.16256 0.76835) (xy -0.1651 0.7366) (xy -0.1651 0.11938)
						(xy -0.17272 0.11176) (xy -0.19812 0.0762) (xy -0.2032 0.06604) (xy -0.20701 0.05715) (xy -0.21209 0.04699)
						(xy -0.2159 0.03683) (xy -0.21844 0.02667) (xy -0.22225 0.01524) (xy -0.22352 0.00508) (xy -0.22606 -0.00508)
						(xy -0.22733 -0.01651) (xy -0.22733 -0.02667) (xy -0.2286 -0.0381) (xy -0.22733 -0.04953) (xy -0.22733 -0.05969)
						(xy -0.22606 -0.07112) (xy -0.22352 -0.08128) (xy -0.22225 -0.09144) (xy -0.21844 -0.10287) (xy -0.2159 -0.11303)
						(xy -0.21209 -0.12319) (xy -0.20701 -0.13335) (xy -0.2032 -0.14224) (xy -0.19812 -0.1524) (xy -0.17272 -0.18796)
						(xy -0.1651 -0.19558) (xy -0.1651 -0.7366) (xy -0.16256 -0.76835) (xy -0.1524 -0.8001) (xy -0.13716 -0.82804)
						(xy -0.11684 -0.85344) (xy -0.09144 -0.87376) (xy -0.0635 -0.889) (xy -0.03175 -0.89916) (xy 0 -0.9017)
						(xy 0.03175 -0.89916) (xy 0.0635 -0.889) (xy 0.09144 -0.87376) (xy 0.11684 -0.85344) (xy 0.13716 -0.82804)
						(xy 0.1524 -0.8001) (xy 0.16256 -0.76835) (xy 0.1651 -0.7366) (xy 0.1651 -0.19685) (xy 0.17272 -0.18923)
						(xy 0.17907 -0.18034) (xy 0.18669 -0.17145) (xy 0.19177 -0.16256) (xy 0.19812 -0.15367) (xy 0.20828 -0.13335)
						(xy 0.21971 -0.10287) (xy 0.22225 -0.09271) (xy 0.22479 -0.08128) (xy 0.22606 -0.07112) (xy 0.2286 -0.05969)
						(xy 0.2286 -0.01651) (xy 0.22606 -0.00508) (xy 0.22479 0.00508) (xy 0.22225 0.01651) (xy 0.21971 0.02667)
						(xy 0.20828 0.05715) (xy 0.19812 0.07747) (xy 0.19177 0.08636) (xy 0.18669 0.09525) (xy 0.17907 0.10414)
						(xy 0.17272 0.11303) (xy 0.1651 0.12065) (xy 0.1651 0.7366) (xy 0.16256 0.76835) (xy 0.1524 0.8001)
						(xy 0.13716 0.82804) (xy 0.11684 0.85344) (xy 0.09144 0.87376) (xy 0.0635 0.889) (xy 0.03175 0.89916)
					)
					(width 0)
					(fill yes)
				)
			)
		)
		(pad "200" smd custom
			(at 30.450028 -4.106672)
			(size 0.1143 0.1143)
			(layers "F.Cu" "F.Mask" "F.Paste")
			(net "SMB_M_B1_R_DATA")
			(options
				(clearance outline)
				(anchor circle)
			)
			(primitives
				(gr_poly
					(pts
						(xy 0 0.9017) (xy -0.03175 0.89916) (xy -0.0635 0.889) (xy -0.09144 0.87376) (xy -0.11684 0.85344)
						(xy -0.13716 0.82804) (xy -0.1524 0.8001) (xy -0.16256 0.76835) (xy -0.1651 0.7366) (xy -0.1651 0.19685)
						(xy -0.17272 0.18923) (xy -0.17907 0.18034) (xy -0.18669 0.17145) (xy -0.19177 0.16256) (xy -0.19812 0.15367)
						(xy -0.20828 0.13335) (xy -0.21971 0.10287) (xy -0.22225 0.09271) (xy -0.22479 0.08128) (xy -0.22606 0.07112)
						(xy -0.2286 0.05969) (xy -0.2286 0.01651) (xy -0.22606 0.00508) (xy -0.22479 -0.00508) (xy -0.22225 -0.01651)
						(xy -0.21971 -0.02667) (xy -0.20828 -0.05715) (xy -0.19812 -0.07747) (xy -0.19177 -0.08636) (xy -0.18669 -0.09525)
						(xy -0.17907 -0.10414) (xy -0.17272 -0.11303) (xy -0.1651 -0.12065) (xy -0.1651 -0.7366) (xy -0.16256 -0.76835)
						(xy -0.1524 -0.8001) (xy -0.13716 -0.82804) (xy -0.11684 -0.85344) (xy -0.09144 -0.87376) (xy -0.0635 -0.889)
						(xy -0.03175 -0.89916) (xy 0 -0.9017) (xy 0.03175 -0.89916) (xy 0.0635 -0.889) (xy 0.09144 -0.87376)
						(xy 0.11684 -0.85344) (xy 0.13716 -0.82804) (xy 0.1524 -0.8001) (xy 0.16256 -0.76835) (xy 0.1651 -0.7366)
						(xy 0.1651 -0.11938) (xy 0.17272 -0.11176) (xy 0.19812 -0.0762) (xy 0.2032 -0.06604) (xy 0.20701 -0.05715)
						(xy 0.21209 -0.04699) (xy 0.2159 -0.03683) (xy 0.21844 -0.02667) (xy 0.22225 -0.01524) (xy 0.22352 -0.00508)
						(xy 0.22606 0.00508) (xy 0.22733 0.01651) (xy 0.22733 0.02667) (xy 0.2286 0.0381) (xy 0.22733 0.04953)
						(xy 0.22733 0.05969) (xy 0.22606 0.07112) (xy 0.22352 0.08128) (xy 0.22225 0.09144) (xy 0.21844 0.10287)
						(xy 0.2159 0.11303) (xy 0.21209 0.12319) (xy 0.20701 0.13335) (xy 0.2032 0.14224) (xy 0.19812 0.1524)
						(xy 0.17272 0.18796) (xy 0.1651 0.19558) (xy 0.1651 0.7366) (xy 0.16256 0.76835) (xy 0.1524 0.8001)
						(xy 0.13716 0.82804) (xy 0.11684 0.85344) (xy 0.09144 0.87376) (xy 0.0635 0.889) (xy 0.03175 0.89916)
					)
					(width 0)
					(fill yes)
				)
			)
		)
		(pad "201" smd custom
			(at 30.750002 4.106672)
			(size 0.1143 0.1143)
			(layers "F.Cu" "F.Mask" "F.Paste")
			(net "CHB_1_SA1")
			(options
				(clearance outline)
				(anchor circle)
			)
			(primitives
				(gr_poly
					(pts
						(xy 0 0.9017) (xy -0.03175 0.89916) (xy -0.0635 0.889) (xy -0.09144 0.87376) (xy -0.11684 0.85344)
						(xy -0.13716 0.82804) (xy -0.1524 0.8001) (xy -0.16256 0.76835) (xy -0.1651 0.7366) (xy -0.1651 -0.13462)
						(xy -0.17272 -0.14224) (xy -0.19812 -0.1778) (xy -0.2032 -0.18796) (xy -0.20701 -0.19685) (xy -0.21209 -0.20701)
						(xy -0.2159 -0.21717) (xy -0.21844 -0.22733) (xy -0.22225 -0.23876) (xy -0.22352 -0.24892) (xy -0.22606 -0.25908)
						(xy -0.22733 -0.27051) (xy -0.22733 -0.28067) (xy -0.2286 -0.2921) (xy -0.22733 -0.30353) (xy -0.22733 -0.31369)
						(xy -0.22606 -0.32512) (xy -0.22352 -0.33528) (xy -0.22225 -0.34544) (xy -0.21844 -0.35687) (xy -0.2159 -0.36703)
						(xy -0.21209 -0.37719) (xy -0.20701 -0.38735) (xy -0.2032 -0.39624) (xy -0.19812 -0.4064) (xy -0.17272 -0.44196)
						(xy -0.1651 -0.44958) (xy -0.1651 -0.7366) (xy -0.16256 -0.76835) (xy -0.1524 -0.8001) (xy -0.13716 -0.82804)
						(xy -0.11684 -0.85344) (xy -0.09144 -0.87376) (xy -0.0635 -0.889) (xy -0.03175 -0.89916) (xy 0 -0.9017)
						(xy 0.03175 -0.89916) (xy 0.0635 -0.889) (xy 0.09144 -0.87376) (xy 0.11684 -0.85344) (xy 0.13716 -0.82804)
						(xy 0.1524 -0.8001) (xy 0.16256 -0.76835) (xy 0.1651 -0.7366) (xy 0.1651 -0.44958) (xy 0.17272 -0.44196)
						(xy 0.19812 -0.4064) (xy 0.2032 -0.39624) (xy 0.20701 -0.38735) (xy 0.21209 -0.37719) (xy 0.2159 -0.36703)
						(xy 0.21844 -0.35687) (xy 0.22225 -0.34544) (xy 0.22352 -0.33528) (xy 0.22606 -0.32512) (xy 0.22733 -0.31369)
						(xy 0.22733 -0.30353) (xy 0.2286 -0.2921) (xy 0.22733 -0.28067) (xy 0.22733 -0.27051) (xy 0.22606 -0.25908)
						(xy 0.22352 -0.24892) (xy 0.22225 -0.23876) (xy 0.21844 -0.22733) (xy 0.2159 -0.21717) (xy 0.21209 -0.20701)
						(xy 0.20701 -0.19685) (xy 0.2032 -0.18796) (xy 0.19812 -0.1778) (xy 0.17272 -0.14224) (xy 0.1651 -0.13462)
						(xy 0.1651 0.7366) (xy 0.16256 0.76835) (xy 0.1524 0.8001) (xy 0.13716 0.82804) (xy 0.11684 0.85344)
						(xy 0.09144 0.87376) (xy 0.0635 0.889) (xy 0.03175 0.89916)
					)
					(width 0)
					(fill yes)
				)
			)
		)
		(pad "202" smd custom
			(at 31.049976 -4.106672)
			(size 0.1143 0.1143)
			(layers "F.Cu" "F.Mask" "F.Paste")
			(net "SMB_M_B1_R_CLK")
			(options
				(clearance outline)
				(anchor circle)
			)
			(primitives
				(gr_poly
					(pts
						(xy 0 0.9017) (xy -0.03175 0.89916) (xy -0.0635 0.889) (xy -0.09144 0.87376) (xy -0.11684 0.85344)
						(xy -0.13716 0.82804) (xy -0.1524 0.8001) (xy -0.16256 0.76835) (xy -0.1651 0.7366) (xy -0.1651 0.44958)
						(xy -0.17272 0.44196) (xy -0.19812 0.4064) (xy -0.2032 0.39624) (xy -0.20701 0.38735) (xy -0.21209 0.37719)
						(xy -0.2159 0.36703) (xy -0.21844 0.35687) (xy -0.22225 0.34544) (xy -0.22352 0.33528) (xy -0.22606 0.32512)
						(xy -0.22733 0.31369) (xy -0.22733 0.30353) (xy -0.2286 0.2921) (xy -0.22733 0.28067) (xy -0.22733 0.27051)
						(xy -0.22606 0.25908) (xy -0.22352 0.24892) (xy -0.22225 0.23876) (xy -0.21844 0.22733) (xy -0.2159 0.21717)
						(xy -0.21209 0.20701) (xy -0.20701 0.19685) (xy -0.2032 0.18796) (xy -0.19812 0.1778) (xy -0.17272 0.14224)
						(xy -0.1651 0.13462) (xy -0.1651 -0.7366) (xy -0.16256 -0.76835) (xy -0.1524 -0.8001) (xy -0.13716 -0.82804)
						(xy -0.11684 -0.85344) (xy -0.09144 -0.87376) (xy -0.0635 -0.889) (xy -0.03175 -0.89916) (xy 0 -0.9017)
						(xy 0.03175 -0.89916) (xy 0.0635 -0.889) (xy 0.09144 -0.87376) (xy 0.11684 -0.85344) (xy 0.13716 -0.82804)
						(xy 0.1524 -0.8001) (xy 0.16256 -0.76835) (xy 0.1651 -0.7366) (xy 0.1651 0.13462) (xy 0.17272 0.14224)
						(xy 0.19812 0.1778) (xy 0.2032 0.18796) (xy 0.20701 0.19685) (xy 0.21209 0.20701) (xy 0.2159 0.21717)
						(xy 0.21844 0.22733) (xy 0.22225 0.23876) (xy 0.22352 0.24892) (xy 0.22606 0.25908) (xy 0.22733 0.27051)
						(xy 0.22733 0.28067) (xy 0.2286 0.2921) (xy 0.22733 0.30353) (xy 0.22733 0.31369) (xy 0.22606 0.32512)
						(xy 0.22352 0.33528) (xy 0.22225 0.34544) (xy 0.21844 0.35687) (xy 0.2159 0.36703) (xy 0.21209 0.37719)
						(xy 0.20701 0.38735) (xy 0.2032 0.39624) (xy 0.19812 0.4064) (xy 0.17272 0.44196) (xy 0.1651 0.44958)
						(xy 0.1651 0.7366) (xy 0.16256 0.76835) (xy 0.1524 0.8001) (xy 0.13716 0.82804) (xy 0.11684 0.85344)
						(xy 0.09144 0.87376) (xy 0.0635 0.889) (xy 0.03175 0.89916)
					)
					(width 0)
					(fill yes)
				)
			)
		)
		(pad "203" smd custom
			(at 31.34995 4.106672)
			(size 0.1143 0.1143)
			(layers "F.Cu" "F.Mask" "F.Paste")
			(net "PV_VTT_DDR_B")
			(options
				(clearance outline)
				(anchor circle)
			)
			(primitives
				(gr_poly
					(pts
						(xy 0 0.9017) (xy -0.03175 0.89916) (xy -0.0635 0.889) (xy -0.09144 0.87376) (xy -0.11684 0.85344)
						(xy -0.13716 0.82804) (xy -0.1524 0.8001) (xy -0.16256 0.76835) (xy -0.1651 0.7366) (xy -0.1651 0.11938)
						(xy -0.17272 0.11176) (xy -0.19812 0.0762) (xy -0.2032 0.06604) (xy -0.20701 0.05715) (xy -0.21209 0.04699)
						(xy -0.2159 0.03683) (xy -0.21844 0.02667) (xy -0.22225 0.01524) (xy -0.22352 0.00508) (xy -0.22606 -0.00508)
						(xy -0.22733 -0.01651) (xy -0.22733 -0.02667) (xy -0.2286 -0.0381) (xy -0.22733 -0.04953) (xy -0.22733 -0.05969)
						(xy -0.22606 -0.07112) (xy -0.22352 -0.08128) (xy -0.22225 -0.09144) (xy -0.21844 -0.10287) (xy -0.2159 -0.11303)
						(xy -0.21209 -0.12319) (xy -0.20701 -0.13335) (xy -0.2032 -0.14224) (xy -0.19812 -0.1524) (xy -0.17272 -0.18796)
						(xy -0.1651 -0.19558) (xy -0.1651 -0.7366) (xy -0.16256 -0.76835) (xy -0.1524 -0.8001) (xy -0.13716 -0.82804)
						(xy -0.11684 -0.85344) (xy -0.09144 -0.87376) (xy -0.0635 -0.889) (xy -0.03175 -0.89916) (xy 0 -0.9017)
						(xy 0.03175 -0.89916) (xy 0.0635 -0.889) (xy 0.09144 -0.87376) (xy 0.11684 -0.85344) (xy 0.13716 -0.82804)
						(xy 0.1524 -0.8001) (xy 0.16256 -0.76835) (xy 0.1651 -0.7366) (xy 0.1651 -0.19685) (xy 0.17272 -0.18923)
						(xy 0.17907 -0.18034) (xy 0.18669 -0.17145) (xy 0.19177 -0.16256) (xy 0.19812 -0.15367) (xy 0.20828 -0.13335)
						(xy 0.21971 -0.10287) (xy 0.22225 -0.09271) (xy 0.22479 -0.08128) (xy 0.22606 -0.07112) (xy 0.2286 -0.05969)
						(xy 0.2286 -0.01651) (xy 0.22606 -0.00508) (xy 0.22479 0.00508) (xy 0.22225 0.01651) (xy 0.21971 0.02667)
						(xy 0.20828 0.05715) (xy 0.19812 0.07747) (xy 0.19177 0.08636) (xy 0.18669 0.09525) (xy 0.17907 0.10414)
						(xy 0.17272 0.11303) (xy 0.1651 0.12065) (xy 0.1651 0.7366) (xy 0.16256 0.76835) (xy 0.1524 0.8001)
						(xy 0.13716 0.82804) (xy 0.11684 0.85344) (xy 0.09144 0.87376) (xy 0.0635 0.889) (xy 0.03175 0.89916)
					)
					(width 0)
					(fill yes)
				)
			)
		)
		(pad "204" smd custom
			(at 31.649924 -4.106672)
			(size 0.1143 0.1143)
			(layers "F.Cu" "F.Mask" "F.Paste")
			(net "PV_VTT_DDR_B")
			(options
				(clearance outline)
				(anchor circle)
			)
			(primitives
				(gr_poly
					(pts
						(xy 0 0.9017) (xy -0.03175 0.89916) (xy -0.0635 0.889) (xy -0.09144 0.87376) (xy -0.11684 0.85344)
						(xy -0.13716 0.82804) (xy -0.1524 0.8001) (xy -0.16256 0.76835) (xy -0.1651 0.7366) (xy -0.1651 0.19685)
						(xy -0.17272 0.18923) (xy -0.17907 0.18034) (xy -0.18669 0.17145) (xy -0.19177 0.16256) (xy -0.19812 0.15367)
						(xy -0.20828 0.13335) (xy -0.21971 0.10287) (xy -0.22225 0.09271) (xy -0.22479 0.08128) (xy -0.22606 0.07112)
						(xy -0.2286 0.05969) (xy -0.2286 0.01651) (xy -0.22606 0.00508) (xy -0.22479 -0.00508) (xy -0.22225 -0.01651)
						(xy -0.21971 -0.02667) (xy -0.20828 -0.05715) (xy -0.19812 -0.07747) (xy -0.19177 -0.08636) (xy -0.18669 -0.09525)
						(xy -0.17907 -0.10414) (xy -0.17272 -0.11303) (xy -0.1651 -0.12065) (xy -0.1651 -0.7366) (xy -0.16256 -0.76835)
						(xy -0.1524 -0.8001) (xy -0.13716 -0.82804) (xy -0.11684 -0.85344) (xy -0.09144 -0.87376) (xy -0.0635 -0.889)
						(xy -0.03175 -0.89916) (xy 0 -0.9017) (xy 0.03175 -0.89916) (xy 0.0635 -0.889) (xy 0.09144 -0.87376)
						(xy 0.11684 -0.85344) (xy 0.13716 -0.82804) (xy 0.1524 -0.8001) (xy 0.16256 -0.76835) (xy 0.1651 -0.7366)
						(xy 0.1651 -0.11938) (xy 0.17272 -0.11176) (xy 0.19812 -0.0762) (xy 0.2032 -0.06604) (xy 0.20701 -0.05715)
						(xy 0.21209 -0.04699) (xy 0.2159 -0.03683) (xy 0.21844 -0.02667) (xy 0.22225 -0.01524) (xy 0.22352 -0.00508)
						(xy 0.22606 0.00508) (xy 0.22733 0.01651) (xy 0.22733 0.02667) (xy 0.2286 0.0381) (xy 0.22733 0.04953)
						(xy 0.22733 0.05969) (xy 0.22606 0.07112) (xy 0.22352 0.08128) (xy 0.22225 0.09144) (xy 0.21844 0.10287)
						(xy 0.2159 0.11303) (xy 0.21209 0.12319) (xy 0.20701 0.13335) (xy 0.2032 0.14224) (xy 0.19812 0.1524)
						(xy 0.17272 0.18796) (xy 0.1651 0.19558) (xy 0.1651 0.7366) (xy 0.16256 0.76835) (xy 0.1524 0.8001)
						(xy 0.13716 0.82804) (xy 0.11684 0.85344) (xy 0.09144 0.87376) (xy 0.0635 0.889) (xy 0.03175 0.89916)
					)
					(width 0)
					(fill yes)
				)
			)
		)
		(pad "205" smd rect
			(at -37.349938 -11.299952)
			(size 4.699 6.8072)
			(layers "F.Cu" "F.Mask" "F.Paste")
			(net "GND")
		)
		(pad "206" smd rect
			(at 37.349938 -11.299952)
			(size 4.699 6.8072)
			(layers "F.Cu" "F.Mask" "F.Paste")
			(net "GND")
		)
		(pad "207" smd rect
			(at -32.800036 -11.999976)
			(size 3.5052 4.5974)
			(layers "F.Cu" "F.Mask" "F.Paste")
			(net "GND")
		)
		(pad "208" smd rect
			(at 32.800036 -11.999976)
			(size 3.5052 4.5974)
			(layers "F.Cu" "F.Mask" "F.Paste")
			(net "GND")
		)
		(zone
			(layer "F.Cu")
			(hatch none 0.5)
			(connect_pads
				(clearance 0)
			)
			(min_thickness 0.25)
			(keepout
				(tracks allowed)
				(vias not_allowed)
				(pads allowed)
				(copperpour not_allowed)
				(footprints allowed)
			)
			(placement
				(enabled no)
				(sheetname "")
			)
			(fill
				(thermal_gap 0.5)
				(thermal_bridge_width 0.5)
				(island_removal_mode 0)
			)
			(polygon
				(pts
					(xy 128.107694 -2.891028) (xy 149.593554 -2.891028) (xy 149.593554 -2.586228) (xy 128.107694 -2.586228)
				)
			)
		)
		(zone
			(layer "F.Cu")
			(hatch none 0.5)
			(connect_pads
				(clearance 0)
			)
			(min_thickness 0.25)
			(keepout
				(tracks allowed)
				(vias not_allowed)
				(pads allowed)
				(copperpour not_allowed)
				(footprints allowed)
			)
			(placement
				(enabled no)
				(sheetname "")
			)
			(fill
				(thermal_gap 0.5)
				(thermal_bridge_width 0.5)
				(island_removal_mode 0)
			)
			(polygon
				(pts
					(xy 128.453134 -8.995156) (xy 149.852634 -8.995156) (xy 149.852634 -8.690356) (xy 128.453134 -8.690356)
				)
			)
		)
		(zone
			(layer "F.Cu")
			(hatch none 0.5)
			(connect_pads
				(clearance 0)
			)
			(min_thickness 0.25)
			(keepout
				(tracks allowed)
				(vias not_allowed)
				(pads allowed)
				(copperpour not_allowed)
				(footprints allowed)
			)
			(placement
				(enabled no)
				(sheetname "")
			)
			(fill
				(thermal_gap 0.5)
				(thermal_bridge_width 0.5)
				(island_removal_mode 0)
			)
			(polygon
				(pts
					(xy 152.080214 -2.89052) (xy 191.602614 -2.89052) (xy 191.602614 -2.58572) (xy 152.080214 -2.58572)
				)
			)
		)
		(zone
			(layer "F.Cu")
			(hatch none 0.5)
			(connect_pads
				(clearance 0)
			)
			(min_thickness 0.25)
			(keepout
				(tracks allowed)
				(vias not_allowed)
				(pads allowed)
				(copperpour not_allowed)
				(footprints allowed)
			)
			(placement
				(enabled no)
				(sheetname "")
			)
			(fill
				(thermal_gap 0.5)
				(thermal_bridge_width 0.5)
				(island_removal_mode 0)
			)
			(polygon
				(pts
					(xy 152.4254 -8.995664) (xy 191.87414 -8.995664) (xy 191.87414 -8.690864) (xy 152.4254 -8.690864)
				)
			)
		)
		(zone
			(layers "F.Cu" "B.Cu" "In1.Cu" "In2.Cu" "In3.Cu" "In4.Cu" "In5.Cu" "In6.Cu"
				"In7.Cu" "In8.Cu" "In9.Cu" "In10.Cu"
			)
			(hatch none 0.5)
			(connect_pads
				(clearance 0)
			)
			(min_thickness 0.25)
			(keepout
				(tracks not_allowed)
				(vias allowed)
				(pads allowed)
				(copperpour not_allowed)
				(footprints allowed)
			)
			(placement
				(enabled no)
				(sheetname "")
			)
			(fill
				(thermal_gap 0.5)
				(thermal_bridge_width 0.5)
				(island_removal_mode 0)
			)
			(polygon
				(pts
					(arc
						(start 194.263518 -5.790692)
						(mid 192.536318 -5.790692)
						(end 194.263518 -5.790692)
					)
				)
			)
		)
		(zone
			(layers "F.Cu" "B.Cu" "In1.Cu" "In2.Cu" "In3.Cu" "In4.Cu" "In5.Cu" "In6.Cu"
				"In7.Cu" "In8.Cu" "In9.Cu" "In10.Cu"
			)
			(hatch none 0.5)
			(connect_pads
				(clearance 0)
			)
			(min_thickness 0.25)
			(keepout
				(tracks not_allowed)
				(vias allowed)
				(pads allowed)
				(copperpour not_allowed)
				(footprints allowed)
			)
			(placement
				(enabled no)
				(sheetname "")
			)
			(fill
				(thermal_gap 0.5)
				(thermal_bridge_width 0.5)
				(island_removal_mode 0)
			)
			(polygon
				(pts
					(arc
						(start 127.70485 -5.790692)
						(mid 125.49505 -5.790692)
						(end 127.70485 -5.790692)
					)
				)
			)
		)
	)
	(footprint ""
		(layer "F.Cu")
		(at 27.2542 -66.4972 -90)
		(property "Reference" "PQ2"
			(at 0 0 270)
			(layer "F.SilkS")
			(hide yes)
			(effects
				(font
					(size 1.27 1.27)
				)
			)
		)
		(property "Value" "MMBT3904TT1G-GP"
			(at -2.032 -3.674618 270)
			(unlocked yes)
			(layer "F.Fab")
			(hide yes)
			(effects
				(font
					(size 1.016 1.016)
					(thickness 0.1524)
				)
			)
		)
		(property "Device Type" "SC75CBE1D6H36"
			(at -2.032 -5.198618 270)
			(unlocked yes)
			(layer "F.Fab")
			(hide yes)
			(effects
				(font
					(size 1.016 1.016)
					(thickness 0.1524)
				)
			)
		)
		(duplicate_pad_numbers_are_jumpers no)
		(fp_poly
			(pts
				(xy 0.381 -1.1938) (xy -0.381 -1.1938) (xy -0.381 -0.6604) (xy -1.0541 -0.6604) (xy -1.0541 0.6604)
				(xy -0.889 0.6604) (xy -0.889 1.1938) (xy 0.889 1.1938) (xy 0.889 0.6604) (xy 1.0541 0.6604) (xy 1.0541 -0.6604)
				(xy 0.381 -0.6604)
			)
			(stroke
				(width 0)
				(type default)
			)
			(fill no)
			(layer "F.CrtYd")
		)
		(fp_poly
			(pts
				(xy 0.381 -1.1938) (xy -0.381 -1.1938) (xy -0.381 -0.6604) (xy -1.0541 -0.6604) (xy -1.0541 0.6604)
				(xy -0.889 0.6604) (xy -0.889 1.1938) (xy 0.889 1.1938) (xy 0.889 0.6604) (xy 1.0541 0.6604) (xy 1.0541 -0.6604)
				(xy 0.381 -0.6604)
			)
			(stroke
				(width 0)
				(type default)
			)
			(fill no)
			(layer "F.Fab")
		)
		(pad "B" smd custom
			(at -0.508 0.6604 270)
			(size 0.127 0.127)
			(layers "F.Cu" "F.Mask" "F.Paste")
			(net "VCCP_Z")
			(options
				(clearance outline)
				(anchor circle)
			)
			(primitives
				(gr_poly
					(pts
						(arc
							(start -0.0508 0.4064)
							(mid -0.194484 0.346884)
							(end -0.254 0.2032)
						)
						(arc
							(start -0.254 -0.2032)
							(mid -0.194484 -0.346884)
							(end -0.0508 -0.4064)
						)
						(arc
							(start 0.0508 -0.4064)
							(mid 0.194484 -0.346884)
							(end 0.254 -0.2032)
						)
						(arc
							(start 0.254 0.2032)
							(mid 0.194484 0.346884)
							(end 0.0508 0.4064)
						)
					)
					(width 0)
					(fill yes)
				)
			)
		)
		(pad "C" smd custom
			(at 0 -0.6604 270)
			(size 0.127 0.127)
			(layers "F.Cu" "F.Mask" "F.Paste")
			(net "P12V")
			(options
				(clearance outline)
				(anchor circle)
			)
			(primitives
				(gr_poly
					(pts
						(arc
							(start -0.0508 0.4064)
							(mid -0.194484 0.346884)
							(end -0.254 0.2032)
						)
						(arc
							(start -0.254 -0.2032)
							(mid -0.194484 -0.346884)
							(end -0.0508 -0.4064)
						)
						(arc
							(start 0.0508 -0.4064)
							(mid 0.194484 -0.346884)
							(end 0.254 -0.2032)
						)
						(arc
							(start 0.254 0.2032)
							(mid 0.194484 0.346884)
							(end 0.0508 0.4064)
						)
					)
					(width 0)
					(fill yes)
				)
			)
		)
		(pad "E" smd custom
			(at 0.508 0.6604 270)
			(size 0.127 0.127)
			(layers "F.Cu" "F.Mask" "F.Paste")
			(net "VCCP_5VBIAS")
			(options
				(clearance outline)
				(anchor circle)
			)
			(primitives
				(gr_poly
					(pts
						(arc
							(start -0.0508 0.4064)
							(mid -0.194484 0.346884)
							(end -0.254 0.2032)
						)
						(arc
							(start -0.254 -0.2032)
							(mid -0.194484 -0.346884)
							(end -0.0508 -0.4064)
						)
						(arc
							(start 0.0508 -0.4064)
							(mid 0.194484 -0.346884)
							(end 0.254 -0.2032)
						)
						(arc
							(start 0.254 0.2032)
							(mid 0.194484 0.346884)
							(end 0.0508 0.4064)
						)
					)
					(width 0)
					(fill yes)
				)
			)
		)
	)
	(footprint ""
		(layer "F.Cu")
		(at 20.828 -47.371 90)
		(property "Reference" "PR98"
			(at 0 0 90)
			(layer "F.SilkS")
			(hide yes)
			(effects
				(font
					(size 1.27 1.27)
				)
			)
		)
		(property "Value" "3K65R2F-1-GP"
			(at 1.7907 -1.1176 90)
			(unlocked yes)
			(layer "F.Fab")
			(hide yes)
			(effects
				(font
					(size 1.016 1.016)
					(thickness 0.1524)
				)
			)
		)
		(property "Device Type" "R402H16"
			(at 1.7907 -2.6416 90)
			(unlocked yes)
			(layer "F.Fab")
			(hide yes)
			(effects
				(font
					(size 1.016 1.016)
					(thickness 0.1524)
				)
			)
		)
		(duplicate_pad_numbers_are_jumpers no)
		(fp_rect
			(start -0.381 0.8382)
			(end 0.381 -0.8382)
			(stroke
				(width 0)
				(type default)
			)
			(fill no)
			(layer "F.CrtYd")
		)
		(fp_rect
			(start -0.381 0.8382)
			(end 0.381 -0.8382)
			(stroke
				(width 0)
				(type default)
			)
			(fill no)
			(layer "F.Fab")
		)
		(pad "1" smd custom
			(at 0 -0.4318 90)
			(size 0.127 0.127)
			(layers "F.Cu" "F.Mask" "F.Paste")
			(net "VR_PVCCP_ISUMP_R2")
			(options
				(clearance outline)
				(anchor circle)
			)
			(primitives
				(gr_poly
					(pts
						(arc
							(start -0.2032 -0.2794)
							(mid -0.239121 -0.264521)
							(end -0.254 -0.2286)
						)
						(arc
							(start -0.254 0.2286)
							(mid -0.239121 0.264521)
							(end -0.2032 0.2794)
						)
						(arc
							(start 0.2032 0.2794)
							(mid 0.239121 0.264521)
							(end 0.254 0.2286)
						)
						(arc
							(start 0.254 -0.2286)
							(mid 0.239121 -0.264521)
							(end 0.2032 -0.2794)
						)
					)
					(width 0)
					(fill yes)
				)
			)
		)
		(pad "2" smd custom
			(at 0 0.4318 90)
			(size 0.127 0.127)
			(layers "F.Cu" "F.Mask" "F.Paste")
			(net "VR_PVCCP_ISUMP")
			(options
				(clearance outline)
				(anchor circle)
			)
			(primitives
				(gr_poly
					(pts
						(arc
							(start -0.2032 -0.2794)
							(mid -0.239121 -0.264521)
							(end -0.254 -0.2286)
						)
						(arc
							(start -0.254 0.2286)
							(mid -0.239121 0.264521)
							(end -0.2032 0.2794)
						)
						(arc
							(start 0.2032 0.2794)
							(mid 0.239121 0.264521)
							(end 0.254 0.2286)
						)
						(arc
							(start 0.254 -0.2286)
							(mid 0.239121 -0.264521)
							(end 0.2032 -0.2794)
						)
					)
					(width 0)
					(fill yes)
				)
			)
		)
	)
	(footprint ""
		(layer "F.Cu")
		(at 31.75 -55.118)
		(property "Reference" "PR71"
			(at 0 0 0)
			(layer "F.SilkS")
			(hide yes)
			(effects
				(font
					(size 1.27 1.27)
				)
			)
		)
		(property "Value" "0R2J-2-GP"
			(at 1.7907 -1.1176 0)
			(unlocked yes)
			(layer "F.Fab")
			(hide yes)
			(effects
				(font
					(size 1.016 1.016)
					(thickness 0.1524)
				)
			)
		)
		(property "Device Type" "R402H16"
			(at 1.7907 -2.6416 0)
			(unlocked yes)
			(layer "F.Fab")
			(hide yes)
			(effects
				(font
					(size 1.016 1.016)
					(thickness 0.1524)
				)
			)
		)
		(duplicate_pad_numbers_are_jumpers no)
		(fp_rect
			(start -0.381 0.8382)
			(end 0.381 -0.8382)
			(stroke
				(width 0)
				(type default)
			)
			(fill no)
			(layer "F.CrtYd")
		)
		(fp_rect
			(start -0.381 0.8382)
			(end 0.381 -0.8382)
			(stroke
				(width 0)
				(type default)
			)
			(fill no)
			(layer "F.Fab")
		)
		(pad "1" smd custom
			(at 0 -0.4318)
			(size 0.127 0.127)
			(layers "F.Cu" "F.Mask" "F.Paste")
			(net "VR_FET_SW_P12V_PVCCP_PVNN")
			(options
				(clearance outline)
				(anchor circle)
			)
			(primitives
				(gr_poly
					(pts
						(arc
							(start -0.2032 -0.2794)
							(mid -0.239121 -0.264521)
							(end -0.254 -0.2286)
						)
						(arc
							(start -0.254 0.2286)
							(mid -0.239121 0.264521)
							(end -0.2032 0.2794)
						)
						(arc
							(start 0.2032 0.2794)
							(mid 0.239121 0.264521)
							(end 0.254 0.2286)
						)
						(arc
							(start 0.254 -0.2286)
							(mid 0.239121 -0.264521)
							(end 0.2032 -0.2794)
						)
					)
					(width 0)
					(fill yes)
				)
			)
		)
		(pad "2" smd custom
			(at 0 0.4318)
			(size 0.127 0.127)
			(layers "F.Cu" "F.Mask" "F.Paste")
			(net "VR_PVCCP_PVNN_VIN")
			(options
				(clearance outline)
				(anchor circle)
			)
			(primitives
				(gr_poly
					(pts
						(arc
							(start -0.2032 -0.2794)
							(mid -0.239121 -0.264521)
							(end -0.254 -0.2286)
						)
						(arc
							(start -0.254 0.2286)
							(mid -0.239121 0.264521)
							(end -0.2032 0.2794)
						)
						(arc
							(start 0.2032 0.2794)
							(mid 0.239121 0.264521)
							(end 0.254 0.2286)
						)
						(arc
							(start 0.254 -0.2286)
							(mid 0.239121 -0.264521)
							(end 0.2032 -0.2794)
						)
					)
					(width 0)
					(fill yes)
				)
			)
		)
	)
	(footprint ""
		(layer "F.Cu")
		(at 23.5204 -50.5206)
		(property "Reference" "PR83"
			(at 0 0 0)
			(layer "F.SilkS")
			(hide yes)
			(effects
				(font
					(size 1.27 1.27)
				)
			)
		)
		(property "Value" "10R2F-L-GP"
			(at 1.7907 -1.1176 0)
			(unlocked yes)
			(layer "F.Fab")
			(hide yes)
			(effects
				(font
					(size 1.016 1.016)
					(thickness 0.1524)
				)
			)
		)
		(property "Device Type" "R402H14"
			(at 1.7907 -2.6416 0)
			(unlocked yes)
			(layer "F.Fab")
			(hide yes)
			(effects
				(font
					(size 1.016 1.016)
					(thickness 0.1524)
				)
			)
		)
		(duplicate_pad_numbers_are_jumpers no)
		(fp_rect
			(start -0.381 0.8382)
			(end 0.381 -0.8382)
			(stroke
				(width 0)
				(type default)
			)
			(fill no)
			(layer "F.CrtYd")
		)
		(fp_rect
			(start -0.381 0.8382)
			(end 0.381 -0.8382)
			(stroke
				(width 0)
				(type default)
			)
			(fill no)
			(layer "F.Fab")
		)
		(pad "1" smd custom
			(at 0 -0.4318)
			(size 0.127 0.127)
			(layers "F.Cu" "F.Mask" "F.Paste")
			(net "VR_PVCCP_RTN")
			(options
				(clearance outline)
				(anchor circle)
			)
			(primitives
				(gr_poly
					(pts
						(arc
							(start -0.2032 -0.2794)
							(mid -0.239121 -0.264521)
							(end -0.254 -0.2286)
						)
						(arc
							(start -0.254 0.2286)
							(mid -0.239121 0.264521)
							(end -0.2032 0.2794)
						)
						(arc
							(start 0.2032 0.2794)
							(mid 0.239121 0.264521)
							(end 0.254 0.2286)
						)
						(arc
							(start 0.254 -0.2286)
							(mid 0.239121 -0.264521)
							(end 0.2032 -0.2794)
						)
					)
					(width 0)
					(fill yes)
				)
			)
		)
		(pad "2" smd custom
			(at 0 0.4318)
			(size 0.127 0.127)
			(layers "F.Cu" "F.Mask" "F.Paste")
			(net "GND")
			(options
				(clearance outline)
				(anchor circle)
			)
			(primitives
				(gr_poly
					(pts
						(arc
							(start -0.2032 -0.2794)
							(mid -0.239121 -0.264521)
							(end -0.254 -0.2286)
						)
						(arc
							(start -0.254 0.2286)
							(mid -0.239121 0.264521)
							(end -0.2032 0.2794)
						)
						(arc
							(start 0.2032 0.2794)
							(mid 0.239121 0.264521)
							(end 0.254 0.2286)
						)
						(arc
							(start 0.254 -0.2286)
							(mid 0.239121 -0.264521)
							(end 0.2032 -0.2794)
						)
					)
					(width 0)
					(fill yes)
				)
			)
		)
	)
	(footprint ""
		(layer "F.Cu")
		(at 17.1196 -63.8302 180)
		(property "Reference" "PC24"
			(at 0 0 180)
			(layer "F.SilkS")
			(hide yes)
			(effects
				(font
					(size 1.27 1.27)
				)
			)
		)
		(property "Value" "SCD22U10V2KX-1GP"
			(at 1.8923 -1.2065 180)
			(unlocked yes)
			(layer "F.Fab")
			(hide yes)
			(effects
				(font
					(size 1.016 1.016)
					(thickness 0.1524)
				)
			)
		)
		(property "Device Type" "C402H22"
			(at 1.8923 -2.7305 180)
			(unlocked yes)
			(layer "F.Fab")
			(hide yes)
			(effects
				(font
					(size 1.016 1.016)
					(thickness 0.1524)
				)
			)
		)
		(duplicate_pad_numbers_are_jumpers no)
		(fp_rect
			(start -0.381 0.7366)
			(end 0.381 -0.7366)
			(stroke
				(width 0)
				(type default)
			)
			(fill no)
			(layer "F.CrtYd")
		)
		(fp_rect
			(start -0.381 0.7366)
			(end 0.381 -0.7366)
			(stroke
				(width 0)
				(type default)
			)
			(fill no)
			(layer "F.Fab")
		)
		(pad "1" smd custom
			(at 0 -0.4572 180)
			(size 0.1143 0.1143)
			(layers "F.Cu" "F.Mask" "F.Paste")
			(net "VR_PVNN_IMON")
			(options
				(clearance outline)
				(anchor circle)
			)
			(primitives
				(gr_poly
					(pts
						(arc
							(start -0.254 -0.1778)
							(mid -0.239121 -0.213721)
							(end -0.2032 -0.2286)
						)
						(arc
							(start 0.2032 -0.2286)
							(mid 0.239121 -0.213721)
							(end 0.254 -0.1778)
						)
						(arc
							(start 0.254 0.1778)
							(mid 0.239121 0.213721)
							(end 0.2032 0.2286)
						)
						(arc
							(start -0.2032 0.2286)
							(mid -0.239121 0.213721)
							(end -0.254 0.1778)
						)
					)
					(width 0)
					(fill yes)
				)
			)
		)
		(pad "2" smd custom
			(at 0 0.4572 180)
			(size 0.1143 0.1143)
			(layers "F.Cu" "F.Mask" "F.Paste")
			(net "GND")
			(options
				(clearance outline)
				(anchor circle)
			)
			(primitives
				(gr_poly
					(pts
						(arc
							(start -0.254 -0.1778)
							(mid -0.239121 -0.213721)
							(end -0.2032 -0.2286)
						)
						(arc
							(start 0.2032 -0.2286)
							(mid 0.239121 -0.213721)
							(end 0.254 -0.1778)
						)
						(arc
							(start 0.254 0.1778)
							(mid 0.239121 0.213721)
							(end 0.2032 0.2286)
						)
						(arc
							(start -0.2032 0.2286)
							(mid -0.239121 0.213721)
							(end -0.254 0.1778)
						)
					)
					(width 0)
					(fill yes)
				)
			)
		)
	)
	(footprint ""
		(layer "F.Cu")
		(at 116.967 -36.465002 90)
		(property "Reference" "PR113"
			(at 0 0 90)
			(layer "F.SilkS")
			(hide yes)
			(effects
				(font
					(size 1.27 1.27)
				)
			)
		)
		(property "Value" "0R2J-2-GP"
			(at 0.064008 -3.993896 90)
			(unlocked yes)
			(layer "F.Fab")
			(hide yes)
			(effects
				(font
					(size 1.016 1.016)
					(thickness 0.1524)
				)
			)
		)
		(property "Device Type" "R402H16"
			(at 0.064008 -5.517896 90)
			(unlocked yes)
			(layer "F.Fab")
			(hide yes)
			(effects
				(font
					(size 1.016 1.016)
					(thickness 0.1524)
				)
			)
		)
		(duplicate_pad_numbers_are_jumpers no)
		(fp_rect
			(start -0.381 0.8382)
			(end 0.381 -0.8382)
			(stroke
				(width 0)
				(type default)
			)
			(fill no)
			(layer "F.CrtYd")
		)
		(fp_rect
			(start -0.381 0.8382)
			(end 0.381 -0.8382)
			(stroke
				(width 0)
				(type default)
			)
			(fill no)
			(layer "F.Fab")
		)
		(pad "1" smd custom
			(at 0 -0.4318 90)
			(size 0.127 0.127)
			(layers "F.Cu" "F.Mask" "F.Paste")
			(net "AVV_VCCCPUVIDSIO_1P03_SENSE")
			(options
				(clearance outline)
				(anchor circle)
			)
			(primitives
				(gr_poly
					(pts
						(arc
							(start -0.2032 -0.2794)
							(mid -0.239121 -0.264521)
							(end -0.254 -0.2286)
						)
						(arc
							(start -0.254 0.2286)
							(mid -0.239121 0.264521)
							(end -0.2032 0.2794)
						)
						(arc
							(start 0.2032 0.2794)
							(mid 0.239121 0.264521)
							(end 0.254 0.2286)
						)
						(arc
							(start 0.254 -0.2286)
							(mid 0.239121 -0.264521)
							(end 0.2032 -0.2794)
						)
					)
					(width 0)
					(fill yes)
				)
			)
		)
		(pad "2" smd custom
			(at 0 0.4318 90)
			(size 0.127 0.127)
			(layers "F.Cu" "F.Mask" "F.Paste")
			(net "VR_PVCCP_VSEN")
			(options
				(clearance outline)
				(anchor circle)
			)
			(primitives
				(gr_poly
					(pts
						(arc
							(start -0.2032 -0.2794)
							(mid -0.239121 -0.264521)
							(end -0.254 -0.2286)
						)
						(arc
							(start -0.254 0.2286)
							(mid -0.239121 0.264521)
							(end -0.2032 0.2794)
						)
						(arc
							(start 0.2032 0.2794)
							(mid 0.239121 0.264521)
							(end 0.254 0.2286)
						)
						(arc
							(start 0.254 -0.2286)
							(mid 0.239121 -0.264521)
							(end 0.2032 -0.2794)
						)
					)
					(width 0)
					(fill yes)
				)
			)
		)
	)
	(footprint ""
		(layer "F.Cu")
		(at 187.3758 -28.2194 90)
		(property "Reference" "PC107"
			(at 0 0 90)
			(layer "F.SilkS")
			(hide yes)
			(effects
				(font
					(size 1.27 1.27)
				)
			)
		)
		(property "Value" "SCD068U16V2KX-GP"
			(at 1.8923 -1.2065 90)
			(unlocked yes)
			(layer "F.Fab")
			(hide yes)
			(effects
				(font
					(size 1.016 1.016)
					(thickness 0.1524)
				)
			)
		)
		(property "Device Type" "C402H22"
			(at 1.8923 -2.7305 90)
			(unlocked yes)
			(layer "F.Fab")
			(hide yes)
			(effects
				(font
					(size 1.016 1.016)
					(thickness 0.1524)
				)
			)
		)
		(duplicate_pad_numbers_are_jumpers no)
		(fp_rect
			(start -0.381 0.7366)
			(end 0.381 -0.7366)
			(stroke
				(width 0)
				(type default)
			)
			(fill no)
			(layer "F.CrtYd")
		)
		(fp_rect
			(start -0.381 0.7366)
			(end 0.381 -0.7366)
			(stroke
				(width 0)
				(type default)
			)
			(fill no)
			(layer "F.Fab")
		)
		(pad "1" smd custom
			(at 0 -0.4572 90)
			(size 0.1143 0.1143)
			(layers "F.Cu" "F.Mask" "F.Paste")
			(net "VR_PVDDR_A_VSEN")
			(options
				(clearance outline)
				(anchor circle)
			)
			(primitives
				(gr_poly
					(pts
						(arc
							(start -0.254 -0.1778)
							(mid -0.239121 -0.213721)
							(end -0.2032 -0.2286)
						)
						(arc
							(start 0.2032 -0.2286)
							(mid 0.239121 -0.213721)
							(end 0.254 -0.1778)
						)
						(arc
							(start 0.254 0.1778)
							(mid 0.239121 0.213721)
							(end 0.2032 0.2286)
						)
						(arc
							(start -0.2032 0.2286)
							(mid -0.239121 0.213721)
							(end -0.254 0.1778)
						)
					)
					(width 0)
					(fill yes)
				)
			)
		)
		(pad "2" smd custom
			(at 0 0.4572 90)
			(size 0.1143 0.1143)
			(layers "F.Cu" "F.Mask" "F.Paste")
			(net "VSENSE_PVDDR_A_VRTN")
			(options
				(clearance outline)
				(anchor circle)
			)
			(primitives
				(gr_poly
					(pts
						(arc
							(start -0.254 -0.1778)
							(mid -0.239121 -0.213721)
							(end -0.2032 -0.2286)
						)
						(arc
							(start 0.2032 -0.2286)
							(mid 0.239121 -0.213721)
							(end 0.254 -0.1778)
						)
						(arc
							(start 0.254 0.1778)
							(mid 0.239121 0.213721)
							(end 0.2032 0.2286)
						)
						(arc
							(start -0.2032 0.2286)
							(mid -0.239121 0.213721)
							(end -0.254 0.1778)
						)
					)
					(width 0)
					(fill yes)
				)
			)
		)
	)
	(footprint ""
		(layer "F.Cu")
		(at 100.6094 -66.8274 90)
		(property "Reference" "PR7"
			(at 0 0 90)
			(layer "F.SilkS")
			(hide yes)
			(effects
				(font
					(size 1.27 1.27)
				)
			)
		)
		(property "Value" "10KR2F-2-GP"
			(at 0.064008 -3.993896 90)
			(unlocked yes)
			(layer "F.Fab")
			(hide yes)
			(effects
				(font
					(size 1.016 1.016)
					(thickness 0.1524)
				)
			)
		)
		(property "Device Type" "R402H16"
			(at 0.064008 -5.517896 90)
			(unlocked yes)
			(layer "F.Fab")
			(hide yes)
			(effects
				(font
					(size 1.016 1.016)
					(thickness 0.1524)
				)
			)
		)
		(duplicate_pad_numbers_are_jumpers no)
		(fp_rect
			(start -0.381 0.8382)
			(end 0.381 -0.8382)
			(stroke
				(width 0)
				(type default)
			)
			(fill no)
			(layer "F.CrtYd")
		)
		(fp_rect
			(start -0.381 0.8382)
			(end 0.381 -0.8382)
			(stroke
				(width 0)
				(type default)
			)
			(fill no)
			(layer "F.Fab")
		)
		(pad "1" smd custom
			(at 0 -0.4318 90)
			(size 0.127 0.127)
			(layers "F.Cu" "F.Mask" "F.Paste")
			(net "PWRGD_P1V1_PG")
			(options
				(clearance outline)
				(anchor circle)
			)
			(primitives
				(gr_poly
					(pts
						(arc
							(start -0.2032 -0.2794)
							(mid -0.239121 -0.264521)
							(end -0.254 -0.2286)
						)
						(arc
							(start -0.254 0.2286)
							(mid -0.239121 0.264521)
							(end -0.2032 0.2794)
						)
						(arc
							(start 0.2032 0.2794)
							(mid 0.239121 0.264521)
							(end 0.254 0.2286)
						)
						(arc
							(start 0.254 -0.2286)
							(mid 0.239121 -0.264521)
							(end 0.2032 -0.2794)
						)
					)
					(width 0)
					(fill yes)
				)
			)
		)
		(pad "2" smd custom
			(at 0 0.4318 90)
			(size 0.127 0.127)
			(layers "F.Cu" "F.Mask" "F.Paste")
			(net "P3V3_STBY")
			(options
				(clearance outline)
				(anchor circle)
			)
			(primitives
				(gr_poly
					(pts
						(arc
							(start -0.2032 -0.2794)
							(mid -0.239121 -0.264521)
							(end -0.254 -0.2286)
						)
						(arc
							(start -0.254 0.2286)
							(mid -0.239121 0.264521)
							(end -0.2032 0.2794)
						)
						(arc
							(start 0.2032 0.2794)
							(mid 0.239121 0.264521)
							(end 0.254 0.2286)
						)
						(arc
							(start 0.254 -0.2286)
							(mid 0.239121 -0.264521)
							(end 0.2032 -0.2794)
						)
					)
					(width 0)
					(fill yes)
				)
			)
		)
	)
	(footprint ""
		(layer "F.Cu")
		(at 107.569 -64.262 180)
		(property "Reference" "C8"
			(at 0 0 180)
			(layer "F.SilkS")
			(hide yes)
			(effects
				(font
					(size 1.27 1.27)
				)
			)
		)
		(property "Value" "SCD1U10V2KX-5GP"
			(at 1.1811 -2.7051 180)
			(unlocked yes)
			(layer "F.Fab")
			(hide yes)
			(effects
				(font
					(size 1.016 1.016)
					(thickness 0.1524)
				)
			)
		)
		(property "Device Type" "C402H22"
			(at 1.1811 -4.2291 180)
			(unlocked yes)
			(layer "F.Fab")
			(hide yes)
			(effects
				(font
					(size 1.016 1.016)
					(thickness 0.1524)
				)
			)
		)
		(duplicate_pad_numbers_are_jumpers no)
		(fp_rect
			(start -0.381 0.7366)
			(end 0.381 -0.7366)
			(stroke
				(width 0)
				(type default)
			)
			(fill no)
			(layer "F.CrtYd")
		)
		(fp_rect
			(start -0.381 0.7366)
			(end 0.381 -0.7366)
			(stroke
				(width 0)
				(type default)
			)
			(fill no)
			(layer "F.Fab")
		)
		(pad "1" smd custom
			(at 0 -0.4572 180)
			(size 0.1143 0.1143)
			(layers "F.Cu" "F.Mask" "F.Paste")
			(net "P3V3_STBY")
			(options
				(clearance outline)
				(anchor circle)
			)
			(primitives
				(gr_poly
					(pts
						(arc
							(start -0.254 -0.1778)
							(mid -0.239121 -0.213721)
							(end -0.2032 -0.2286)
						)
						(arc
							(start 0.2032 -0.2286)
							(mid 0.239121 -0.213721)
							(end 0.254 -0.1778)
						)
						(arc
							(start 0.254 0.1778)
							(mid 0.239121 0.213721)
							(end 0.2032 0.2286)
						)
						(arc
							(start -0.2032 0.2286)
							(mid -0.239121 0.213721)
							(end -0.254 0.1778)
						)
					)
					(width 0)
					(fill yes)
				)
			)
		)
		(pad "2" smd custom
			(at 0 0.4572 180)
			(size 0.1143 0.1143)
			(layers "F.Cu" "F.Mask" "F.Paste")
			(net "GND")
			(options
				(clearance outline)
				(anchor circle)
			)
			(primitives
				(gr_poly
					(pts
						(arc
							(start -0.254 -0.1778)
							(mid -0.239121 -0.213721)
							(end -0.2032 -0.2286)
						)
						(arc
							(start 0.2032 -0.2286)
							(mid 0.239121 -0.213721)
							(end 0.254 -0.1778)
						)
						(arc
							(start 0.254 0.1778)
							(mid 0.239121 0.213721)
							(end 0.2032 0.2286)
						)
						(arc
							(start -0.2032 0.2286)
							(mid -0.239121 0.213721)
							(end -0.254 0.1778)
						)
					)
					(width 0)
					(fill yes)
				)
			)
		)
	)
	(footprint ""
		(layer "F.Cu")
		(at 29.083 -32.385 180)
		(property "Reference" "PC36"
			(at 0 0 180)
			(layer "F.SilkS")
			(hide yes)
			(effects
				(font
					(size 1.27 1.27)
				)
			)
		)
		(property "Value" "SC22U6D3V3MX-1-GP"
			(at -0.0254 -2.0193 180)
			(unlocked yes)
			(layer "F.Fab")
			(hide yes)
			(effects
				(font
					(size 1.016 1.016)
					(thickness 0.1524)
				)
			)
		)
		(property "Device Type" "C603H40"
			(at -0.0254 -3.5433 180)
			(unlocked yes)
			(layer "F.Fab")
			(hide yes)
			(effects
				(font
					(size 1.016 1.016)
					(thickness 0.1524)
				)
			)
		)
		(duplicate_pad_numbers_are_jumpers no)
		(fp_line
			(start -0.4064 0)
			(end 0.4064 0)
			(stroke
				(width 0.2286)
				(type default)
			)
			(layer "F.SilkS")
		)
		(fp_rect
			(start -0.635 1.1811)
			(end 0.635 -1.1811)
			(stroke
				(width 0)
				(type default)
			)
			(fill no)
			(layer "F.CrtYd")
		)
		(fp_rect
			(start -0.635 1.1811)
			(end 0.635 -1.1811)
			(stroke
				(width 0)
				(type default)
			)
			(fill no)
			(layer "F.Fab")
		)
		(pad "1" smd custom
			(at 0 -0.6604 180)
			(size 0.19685 0.19685)
			(layers "F.Cu" "F.Mask" "F.Paste")
			(net "P1V0")
			(options
				(clearance outline)
				(anchor circle)
			)
			(primitives
				(gr_poly
					(pts
						(arc
							(start 0.508 -0.2921)
							(mid 0.478242 -0.363942)
							(end 0.4064 -0.3937)
						)
						(arc
							(start -0.4064 -0.3937)
							(mid -0.478242 -0.363942)
							(end -0.508 -0.2921)
						)
						(arc
							(start -0.508 0.2921)
							(mid -0.478242 0.363942)
							(end -0.4064 0.3937)
						)
						(arc
							(start 0.4064 0.3937)
							(mid 0.478242 0.363942)
							(end 0.508 0.2921)
						)
					)
					(width 0)
					(fill yes)
				)
			)
		)
		(pad "2" smd custom
			(at 0 0.6604 180)
			(size 0.19685 0.19685)
			(layers "F.Cu" "F.Mask" "F.Paste")
			(net "GND")
			(options
				(clearance outline)
				(anchor circle)
			)
			(primitives
				(gr_poly
					(pts
						(arc
							(start 0.508 -0.2921)
							(mid 0.478242 -0.363942)
							(end 0.4064 -0.3937)
						)
						(arc
							(start -0.4064 -0.3937)
							(mid -0.478242 -0.363942)
							(end -0.508 -0.2921)
						)
						(arc
							(start -0.508 0.2921)
							(mid -0.478242 0.363942)
							(end -0.4064 0.3937)
						)
						(arc
							(start 0.4064 0.3937)
							(mid 0.478242 0.363942)
							(end 0.508 0.2921)
						)
					)
					(width 0)
					(fill yes)
				)
			)
		)
	)
	(footprint ""
		(layer "F.Cu")
		(at 116.967 -39.3954 90)
		(property "Reference" "C168"
			(at 0 0 90)
			(layer "F.SilkS")
			(hide yes)
			(effects
				(font
					(size 1.27 1.27)
				)
			)
		)
		(property "Value" "SC22U6D3V5MX-2GP"
			(at -0.0762 -6.1214 90)
			(unlocked yes)
			(layer "F.Fab")
			(hide yes)
			(effects
				(font
					(size 1.016 1.016)
					(thickness 0.1524)
				)
			)
		)
		(property "Device Type" "C805H58"
			(at -0.0762 -8.1534 90)
			(unlocked yes)
			(layer "F.Fab")
			(hide yes)
			(effects
				(font
					(size 1.016 1.016)
					(thickness 0.1524)
				)
			)
		)
		(duplicate_pad_numbers_are_jumpers no)
		(fp_line
			(start 0.6096 0)
			(end -0.6096 0)
			(stroke
				(width 0.3048)
				(type default)
			)
			(layer "F.SilkS")
		)
		(fp_poly
			(pts
				(xy -0.9017 1.4351) (xy 0.9017 1.4351) (xy 0.9017 -1.4351) (xy -0.9017 -1.4351)
			)
			(stroke
				(width 0)
				(type default)
			)
			(fill no)
			(layer "F.CrtYd")
		)
		(fp_poly
			(pts
				(xy 0.9271 1.4351) (xy 0.9271 -1.4351) (xy -0.8763 -1.4351) (xy -0.8763 1.4351)
			)
			(stroke
				(width 0)
				(type default)
			)
			(fill no)
			(layer "F.Fab")
		)
		(pad "1" smd rect
			(at 0 -0.8382 90)
			(size 1.5494 0.9398)
			(layers "F.Cu" "F.Mask" "F.Paste")
			(net "PVCCP")
		)
		(pad "2" smd rect
			(at 0 0.8382 90)
			(size 1.5494 0.9398)
			(layers "F.Cu" "F.Mask" "F.Paste")
			(net "GND")
		)
	)
	(footprint ""
		(layer "F.Cu")
		(at 58.0898 -13.7668)
		(property "Reference" "U34"
			(at 0 0 0)
			(layer "F.SilkS")
			(hide yes)
			(effects
				(font
					(size 1.27 1.27)
				)
			)
		)
		(property "Value" "2N7002DW-7F-GP"
			(at -2.5654 1.1049 0)
			(unlocked yes)
			(layer "F.Fab")
			(hide yes)
			(effects
				(font
					(size 1.016 1.016)
					(thickness 0.1524)
				)
			)
		)
		(property "Device Type" "SOT-363H44"
			(at -2.5654 -0.4191 0)
			(unlocked yes)
			(layer "F.Fab")
			(hide yes)
			(effects
				(font
					(size 1.016 1.016)
					(thickness 0.1524)
				)
			)
		)
		(duplicate_pad_numbers_are_jumpers no)
		(fp_poly
			(pts
				(xy -0.6731 1.4351) (xy -0.9779 1.7399) (xy -0.381 1.7399) (xy -0.3683 1.7399) (xy -0.381 1.7272)
			)
			(stroke
				(width 0)
				(type default)
			)
			(fill yes)
			(layer "F.SilkS")
		)
		(fp_poly
			(pts
				(xy 1.2573 0.8763) (xy 1.2573 -0.8763) (xy 0.9525 -0.8763) (xy 0.9525 -1.4351) (xy -0.9525 -1.4351)
				(xy -0.9525 -0.8763) (xy -1.2573 -0.8763) (xy -1.2573 0.8763) (xy -0.9525 0.8763) (xy -0.9525 1.4351)
				(xy 0.9525 1.4351) (xy 0.9525 0.8763)
			)
			(stroke
				(width 0)
				(type default)
			)
			(fill no)
			(layer "F.CrtYd")
		)
		(fp_poly
			(pts
				(xy 1.2573 0.8763) (xy 1.2573 -0.8763) (xy 0.9525 -0.8763) (xy 0.9525 -1.4351) (xy -0.9525 -1.4351)
				(xy -0.9525 -0.8763) (xy -1.2573 -0.8763) (xy -1.2573 0.8763) (xy -0.9525 0.8763) (xy -0.9525 1.4351)
				(xy 0.9525 1.4351) (xy 0.9525 0.8763)
			)
			(stroke
				(width 0)
				(type default)
			)
			(fill no)
			(layer "F.Fab")
		)
		(pad "1" smd rect
			(at -0.65024 0.8255)
			(size 0.3556 0.9652)
			(layers "F.Cu" "F.Mask" "F.Paste")
			(net "GBE_SMBCLK")
		)
		(pad "2" smd rect
			(at 0 0.8255)
			(size 0.3556 0.9652)
			(layers "F.Cu" "F.Mask" "F.Paste")
			(net "GF_GBE_SMB_SW_EN")
		)
		(pad "3" smd rect
			(at 0.65024 0.8255)
			(size 0.3556 0.9652)
			(layers "F.Cu" "F.Mask" "F.Paste")
			(net "GF_GBE_SMBDATA")
		)
		(pad "4" smd rect
			(at 0.65024 -0.8255)
			(size 0.3556 0.9652)
			(layers "F.Cu" "F.Mask" "F.Paste")
			(net "GBE_SMBDATA")
		)
		(pad "5" smd rect
			(at 0 -0.8255)
			(size 0.3556 0.9652)
			(layers "F.Cu" "F.Mask" "F.Paste")
			(net "GF_GBE_SMB_SW_EN")
		)
		(pad "6" smd rect
			(at -0.65024 -0.8255)
			(size 0.3556 0.9652)
			(layers "F.Cu" "F.Mask" "F.Paste")
			(net "GF_GBE_SMBCLK")
		)
	)
	(footprint ""
		(layer "F.Cu")
		(at 189.1538 -18.161 180)
		(property "Reference" "PC116"
			(at 0 0 180)
			(layer "F.SilkS")
			(hide yes)
			(effects
				(font
					(size 1.27 1.27)
				)
			)
		)
		(property "Value" "SCD1U16V2KX-3GP"
			(at 1.1811 -2.7051 180)
			(unlocked yes)
			(layer "F.Fab")
			(hide yes)
			(effects
				(font
					(size 1.016 1.016)
					(thickness 0.1524)
				)
			)
		)
		(property "Device Type" "C402H22"
			(at 1.1811 -4.2291 180)
			(unlocked yes)
			(layer "F.Fab")
			(hide yes)
			(effects
				(font
					(size 1.016 1.016)
					(thickness 0.1524)
				)
			)
		)
		(duplicate_pad_numbers_are_jumpers no)
		(fp_rect
			(start -0.381 0.7366)
			(end 0.381 -0.7366)
			(stroke
				(width 0)
				(type default)
			)
			(fill no)
			(layer "F.CrtYd")
		)
		(fp_rect
			(start -0.381 0.7366)
			(end 0.381 -0.7366)
			(stroke
				(width 0)
				(type default)
			)
			(fill no)
			(layer "F.Fab")
		)
		(pad "1" smd custom
			(at 0 -0.4572 180)
			(size 0.1143 0.1143)
			(layers "F.Cu" "F.Mask" "F.Paste")
			(net "PV_VTT_DDR_B_SNS")
			(options
				(clearance outline)
				(anchor circle)
			)
			(primitives
				(gr_poly
					(pts
						(arc
							(start -0.254 -0.1778)
							(mid -0.239121 -0.213721)
							(end -0.2032 -0.2286)
						)
						(arc
							(start 0.2032 -0.2286)
							(mid 0.239121 -0.213721)
							(end 0.254 -0.1778)
						)
						(arc
							(start 0.254 0.1778)
							(mid 0.239121 0.213721)
							(end 0.2032 0.2286)
						)
						(arc
							(start -0.2032 0.2286)
							(mid -0.239121 0.213721)
							(end -0.254 0.1778)
						)
					)
					(width 0)
					(fill yes)
				)
			)
		)
		(pad "2" smd custom
			(at 0 0.4572 180)
			(size 0.1143 0.1143)
			(layers "F.Cu" "F.Mask" "F.Paste")
			(net "GND")
			(options
				(clearance outline)
				(anchor circle)
			)
			(primitives
				(gr_poly
					(pts
						(arc
							(start -0.254 -0.1778)
							(mid -0.239121 -0.213721)
							(end -0.2032 -0.2286)
						)
						(arc
							(start 0.2032 -0.2286)
							(mid 0.239121 -0.213721)
							(end 0.254 -0.1778)
						)
						(arc
							(start 0.254 0.1778)
							(mid 0.239121 0.213721)
							(end 0.2032 0.2286)
						)
						(arc
							(start -0.2032 0.2286)
							(mid -0.239121 0.213721)
							(end -0.254 0.1778)
						)
					)
					(width 0)
					(fill yes)
				)
			)
		)
	)
	(footprint ""
		(layer "F.Cu")
		(at 21.9456 -52.0954)
		(property "Reference" "PC55"
			(at 0 0 0)
			(layer "F.SilkS")
			(hide yes)
			(effects
				(font
					(size 1.27 1.27)
				)
			)
		)
		(property "Value" "SCD22U10V2KX-1GP"
			(at 1.8923 -1.2065 0)
			(unlocked yes)
			(layer "F.Fab")
			(hide yes)
			(effects
				(font
					(size 1.016 1.016)
					(thickness 0.1524)
				)
			)
		)
		(property "Device Type" "C402H22"
			(at 1.8923 -2.7305 0)
			(unlocked yes)
			(layer "F.Fab")
			(hide yes)
			(effects
				(font
					(size 1.016 1.016)
					(thickness 0.1524)
				)
			)
		)
		(duplicate_pad_numbers_are_jumpers no)
		(fp_rect
			(start -0.381 0.7366)
			(end 0.381 -0.7366)
			(stroke
				(width 0)
				(type default)
			)
			(fill no)
			(layer "F.CrtYd")
		)
		(fp_rect
			(start -0.381 0.7366)
			(end 0.381 -0.7366)
			(stroke
				(width 0)
				(type default)
			)
			(fill no)
			(layer "F.Fab")
		)
		(pad "1" smd custom
			(at 0 -0.4572)
			(size 0.1143 0.1143)
			(layers "F.Cu" "F.Mask" "F.Paste")
			(net "VR_PVCCP_ISEN1_R")
			(options
				(clearance outline)
				(anchor circle)
			)
			(primitives
				(gr_poly
					(pts
						(arc
							(start -0.254 -0.1778)
							(mid -0.239121 -0.213721)
							(end -0.2032 -0.2286)
						)
						(arc
							(start 0.2032 -0.2286)
							(mid 0.239121 -0.213721)
							(end 0.254 -0.1778)
						)
						(arc
							(start 0.254 0.1778)
							(mid 0.239121 0.213721)
							(end 0.2032 0.2286)
						)
						(arc
							(start -0.2032 0.2286)
							(mid -0.239121 0.213721)
							(end -0.254 0.1778)
						)
					)
					(width 0)
					(fill yes)
				)
			)
		)
		(pad "2" smd custom
			(at 0 0.4572)
			(size 0.1143 0.1143)
			(layers "F.Cu" "F.Mask" "F.Paste")
			(net "VR_PVCCP_ISUMN")
			(options
				(clearance outline)
				(anchor circle)
			)
			(primitives
				(gr_poly
					(pts
						(arc
							(start -0.254 -0.1778)
							(mid -0.239121 -0.213721)
							(end -0.2032 -0.2286)
						)
						(arc
							(start 0.2032 -0.2286)
							(mid 0.239121 -0.213721)
							(end 0.254 -0.1778)
						)
						(arc
							(start 0.254 0.1778)
							(mid 0.239121 0.213721)
							(end 0.2032 0.2286)
						)
						(arc
							(start -0.2032 0.2286)
							(mid -0.239121 0.213721)
							(end -0.254 0.1778)
						)
					)
					(width 0)
					(fill yes)
				)
			)
		)
	)
	(footprint ""
		(layer "F.Cu")
		(at 189.0522 -27.4574 90)
		(property "Reference" "PC191"
			(at 0 0 90)
			(layer "F.SilkS")
			(hide yes)
			(effects
				(font
					(size 1.27 1.27)
				)
			)
		)
		(property "Value" "SC330P50V2KX-3GP"
			(at 1.8923 -1.2065 90)
			(unlocked yes)
			(layer "F.Fab")
			(hide yes)
			(effects
				(font
					(size 1.016 1.016)
					(thickness 0.1524)
				)
			)
		)
		(property "Device Type" "C402H22"
			(at 1.8923 -2.7305 90)
			(unlocked yes)
			(layer "F.Fab")
			(hide yes)
			(effects
				(font
					(size 1.016 1.016)
					(thickness 0.1524)
				)
			)
		)
		(duplicate_pad_numbers_are_jumpers no)
		(fp_rect
			(start -0.381 0.7366)
			(end 0.381 -0.7366)
			(stroke
				(width 0)
				(type default)
			)
			(fill no)
			(layer "F.CrtYd")
		)
		(fp_rect
			(start -0.381 0.7366)
			(end 0.381 -0.7366)
			(stroke
				(width 0)
				(type default)
			)
			(fill no)
			(layer "F.Fab")
		)
		(pad "1" smd custom
			(at 0 -0.4572 90)
			(size 0.1143 0.1143)
			(layers "F.Cu" "F.Mask" "F.Paste")
			(net "VR_PVDDR_A_SUMN")
			(options
				(clearance outline)
				(anchor circle)
			)
			(primitives
				(gr_poly
					(pts
						(arc
							(start -0.254 -0.1778)
							(mid -0.239121 -0.213721)
							(end -0.2032 -0.2286)
						)
						(arc
							(start 0.2032 -0.2286)
							(mid 0.239121 -0.213721)
							(end 0.254 -0.1778)
						)
						(arc
							(start 0.254 0.1778)
							(mid 0.239121 0.213721)
							(end 0.2032 0.2286)
						)
						(arc
							(start -0.2032 0.2286)
							(mid -0.239121 0.213721)
							(end -0.254 0.1778)
						)
					)
					(width 0)
					(fill yes)
				)
			)
		)
		(pad "2" smd custom
			(at 0 0.4572 90)
			(size 0.1143 0.1143)
			(layers "F.Cu" "F.Mask" "F.Paste")
			(net "VR_PVDDR_A_SUMN_C")
			(options
				(clearance outline)
				(anchor circle)
			)
			(primitives
				(gr_poly
					(pts
						(arc
							(start -0.254 -0.1778)
							(mid -0.239121 -0.213721)
							(end -0.2032 -0.2286)
						)
						(arc
							(start 0.2032 -0.2286)
							(mid 0.239121 -0.213721)
							(end 0.254 -0.1778)
						)
						(arc
							(start 0.254 0.1778)
							(mid 0.239121 0.213721)
							(end 0.2032 0.2286)
						)
						(arc
							(start -0.2032 0.2286)
							(mid -0.239121 0.213721)
							(end -0.254 0.1778)
						)
					)
					(width 0)
					(fill yes)
				)
			)
		)
	)
	(footprint ""
		(layer "F.Cu")
		(at 17.018 -21.463)
		(property "Reference" "PR106"
			(at 0 0 0)
			(layer "F.SilkS")
			(hide yes)
			(effects
				(font
					(size 1.27 1.27)
				)
			)
		)
		(property "Value" "10KR2D-GP"
			(at 1.7907 -1.1176 0)
			(unlocked yes)
			(layer "F.Fab")
			(hide yes)
			(effects
				(font
					(size 1.016 1.016)
					(thickness 0.1524)
				)
			)
		)
		(property "Device Type" "R402H16"
			(at 1.7907 -2.6416 0)
			(unlocked yes)
			(layer "F.Fab")
			(hide yes)
			(effects
				(font
					(size 1.016 1.016)
					(thickness 0.1524)
				)
			)
		)
		(duplicate_pad_numbers_are_jumpers no)
		(fp_rect
			(start -0.381 0.8382)
			(end 0.381 -0.8382)
			(stroke
				(width 0)
				(type default)
			)
			(fill no)
			(layer "F.CrtYd")
		)
		(fp_rect
			(start -0.381 0.8382)
			(end 0.381 -0.8382)
			(stroke
				(width 0)
				(type default)
			)
			(fill no)
			(layer "F.Fab")
		)
		(pad "1" smd custom
			(at 0 -0.4318)
			(size 0.127 0.127)
			(layers "F.Cu" "F.Mask" "F.Paste")
			(net "P1V0_VFB")
			(options
				(clearance outline)
				(anchor circle)
			)
			(primitives
				(gr_poly
					(pts
						(arc
							(start -0.2032 -0.2794)
							(mid -0.239121 -0.264521)
							(end -0.254 -0.2286)
						)
						(arc
							(start -0.254 0.2286)
							(mid -0.239121 0.264521)
							(end -0.2032 0.2794)
						)
						(arc
							(start 0.2032 0.2794)
							(mid 0.239121 0.264521)
							(end 0.254 0.2286)
						)
						(arc
							(start 0.254 -0.2286)
							(mid 0.239121 -0.264521)
							(end 0.2032 -0.2794)
						)
					)
					(width 0)
					(fill yes)
				)
			)
		)
		(pad "2" smd custom
			(at 0 0.4318)
			(size 0.127 0.127)
			(layers "F.Cu" "F.Mask" "F.Paste")
			(net "AGND_P1V0")
			(options
				(clearance outline)
				(anchor circle)
			)
			(primitives
				(gr_poly
					(pts
						(arc
							(start -0.2032 -0.2794)
							(mid -0.239121 -0.264521)
							(end -0.254 -0.2286)
						)
						(arc
							(start -0.254 0.2286)
							(mid -0.239121 0.264521)
							(end -0.2032 0.2794)
						)
						(arc
							(start 0.2032 0.2794)
							(mid 0.239121 0.264521)
							(end 0.254 0.2286)
						)
						(arc
							(start 0.254 -0.2286)
							(mid 0.239121 -0.264521)
							(end 0.2032 -0.2794)
						)
					)
					(width 0)
					(fill yes)
				)
			)
		)
	)
	(footprint ""
		(layer "F.Cu")
		(at 203.962 -67.4624 90)
		(property "Reference" "PC179"
			(at 0 0 90)
			(layer "F.SilkS")
			(hide yes)
			(effects
				(font
					(size 1.27 1.27)
				)
			)
		)
		(property "Value" "SC10U6D3V3MX-GP"
			(at -0.0254 -2.0193 90)
			(unlocked yes)
			(layer "F.Fab")
			(hide yes)
			(effects
				(font
					(size 1.016 1.016)
					(thickness 0.1524)
				)
			)
		)
		(property "Device Type" "C603H38"
			(at -0.0254 -3.5433 90)
			(unlocked yes)
			(layer "F.Fab")
			(hide yes)
			(effects
				(font
					(size 1.016 1.016)
					(thickness 0.1524)
				)
			)
		)
		(duplicate_pad_numbers_are_jumpers no)
		(fp_line
			(start -0.4064 0)
			(end 0.4064 0)
			(stroke
				(width 0.2286)
				(type default)
			)
			(layer "F.SilkS")
		)
		(fp_rect
			(start -0.635 1.1811)
			(end 0.635 -1.1811)
			(stroke
				(width 0)
				(type default)
			)
			(fill no)
			(layer "F.CrtYd")
		)
		(fp_rect
			(start -0.635 1.1811)
			(end 0.635 -1.1811)
			(stroke
				(width 0)
				(type default)
			)
			(fill no)
			(layer "F.Fab")
		)
		(pad "1" smd custom
			(at 0 -0.6604 90)
			(size 0.19685 0.19685)
			(layers "F.Cu" "F.Mask" "F.Paste")
			(net "PV_VDDR")
			(options
				(clearance outline)
				(anchor circle)
			)
			(primitives
				(gr_poly
					(pts
						(arc
							(start 0.508 -0.2921)
							(mid 0.478242 -0.363942)
							(end 0.4064 -0.3937)
						)
						(arc
							(start -0.4064 -0.3937)
							(mid -0.478242 -0.363942)
							(end -0.508 -0.2921)
						)
						(arc
							(start -0.508 0.2921)
							(mid -0.478242 0.363942)
							(end -0.4064 0.3937)
						)
						(arc
							(start 0.4064 0.3937)
							(mid 0.478242 0.363942)
							(end 0.508 0.2921)
						)
					)
					(width 0)
					(fill yes)
				)
			)
		)
		(pad "2" smd custom
			(at 0 0.6604 90)
			(size 0.19685 0.19685)
			(layers "F.Cu" "F.Mask" "F.Paste")
			(net "GND")
			(options
				(clearance outline)
				(anchor circle)
			)
			(primitives
				(gr_poly
					(pts
						(arc
							(start 0.508 -0.2921)
							(mid 0.478242 -0.363942)
							(end 0.4064 -0.3937)
						)
						(arc
							(start -0.4064 -0.3937)
							(mid -0.478242 -0.363942)
							(end -0.508 -0.2921)
						)
						(arc
							(start -0.508 0.2921)
							(mid -0.478242 0.363942)
							(end -0.4064 0.3937)
						)
						(arc
							(start 0.4064 0.3937)
							(mid 0.478242 0.363942)
							(end 0.508 0.2921)
						)
					)
					(width 0)
					(fill yes)
				)
			)
		)
	)
	(footprint ""
		(layer "F.Cu")
		(at 74.041 -29.972 90)
		(property "Reference" "R117"
			(at 0 0 90)
			(layer "F.SilkS")
			(hide yes)
			(effects
				(font
					(size 1.27 1.27)
				)
			)
		)
		(property "Value" "10KR2F-2-GP"
			(at 0.064008 -3.993896 90)
			(unlocked yes)
			(layer "F.Fab")
			(hide yes)
			(effects
				(font
					(size 1.016 1.016)
					(thickness 0.1524)
				)
			)
		)
		(property "Device Type" "R402H16"
			(at 0.064008 -5.517896 90)
			(unlocked yes)
			(layer "F.Fab")
			(hide yes)
			(effects
				(font
					(size 1.016 1.016)
					(thickness 0.1524)
				)
			)
		)
		(duplicate_pad_numbers_are_jumpers no)
		(fp_rect
			(start -0.381 0.8382)
			(end 0.381 -0.8382)
			(stroke
				(width 0)
				(type default)
			)
			(fill no)
			(layer "F.CrtYd")
		)
		(fp_rect
			(start -0.381 0.8382)
			(end 0.381 -0.8382)
			(stroke
				(width 0)
				(type default)
			)
			(fill no)
			(layer "F.Fab")
		)
		(pad "1" smd custom
			(at 0 -0.4318 90)
			(size 0.127 0.127)
			(layers "F.Cu" "F.Mask" "F.Paste")
			(net "P3V3_CPU")
			(options
				(clearance outline)
				(anchor circle)
			)
			(primitives
				(gr_poly
					(pts
						(arc
							(start -0.2032 -0.2794)
							(mid -0.239121 -0.264521)
							(end -0.254 -0.2286)
						)
						(arc
							(start -0.254 0.2286)
							(mid -0.239121 0.264521)
							(end -0.2032 0.2794)
						)
						(arc
							(start 0.2032 0.2794)
							(mid 0.239121 0.264521)
							(end 0.254 0.2286)
						)
						(arc
							(start 0.254 -0.2286)
							(mid 0.239121 -0.264521)
							(end 0.2032 -0.2794)
						)
					)
					(width 0)
					(fill yes)
				)
			)
		)
		(pad "2" smd custom
			(at 0 0.4318 90)
			(size 0.127 0.127)
			(layers "F.Cu" "F.Mask" "F.Paste")
			(net "PMU_SLP_S45#")
			(options
				(clearance outline)
				(anchor circle)
			)
			(primitives
				(gr_poly
					(pts
						(arc
							(start -0.2032 -0.2794)
							(mid -0.239121 -0.264521)
							(end -0.254 -0.2286)
						)
						(arc
							(start -0.254 0.2286)
							(mid -0.239121 0.264521)
							(end -0.2032 0.2794)
						)
						(arc
							(start 0.2032 0.2794)
							(mid 0.239121 0.264521)
							(end 0.254 0.2286)
						)
						(arc
							(start 0.254 -0.2286)
							(mid 0.239121 -0.264521)
							(end 0.2032 -0.2794)
						)
					)
					(width 0)
					(fill yes)
				)
			)
		)
	)
	(footprint ""
		(layer "F.Cu")
		(at 175.006 -51.816 180)
		(property "Reference" "U22"
			(at 0 0 180)
			(layer "F.SilkS")
			(hide yes)
			(effects
				(font
					(size 1.27 1.27)
				)
			)
		)
		(property "Value" "M24128-BWMN6TP-GP"
			(at 4.064 -7.5692 180)
			(unlocked yes)
			(layer "F.Fab")
			(hide yes)
			(effects
				(font
					(size 1.016 1.016)
					(thickness 0.1524)
				)
			)
		)
		(property "Device Type" "SOIC8H69"
			(at 4.064 -6.0452 180)
			(unlocked yes)
			(layer "F.Fab")
			(hide yes)
			(effects
				(font
					(size 1.016 1.016)
					(thickness 0.1524)
				)
			)
		)
		(duplicate_pad_numbers_are_jumpers no)
		(fp_line
			(start 2.1463 1.4351)
			(end 2.1463 -1.4351)
			(stroke
				(width 0.1524)
				(type default)
			)
			(layer "F.SilkS")
		)
		(fp_line
			(start 2.1463 -1.4351)
			(end -2.6797 -1.4351)
			(stroke
				(width 0.1524)
				(type default)
			)
			(layer "F.SilkS")
		)
		(fp_line
			(start -2.1717 0)
			(end -2.6797 -0.508)
			(stroke
				(width 0.1524)
				(type default)
			)
			(layer "F.SilkS")
		)
		(fp_line
			(start -2.502154 1.4224)
			(end -2.502154 3.1115)
			(stroke
				(width 0.508)
				(type default)
			)
			(layer "F.SilkS")
		)
		(fp_line
			(start -2.6797 1.4351)
			(end 2.1463 1.4351)
			(stroke
				(width 0.1524)
				(type default)
			)
			(layer "F.SilkS")
		)
		(fp_line
			(start -2.6797 0.508)
			(end -2.1717 0)
			(stroke
				(width 0.1524)
				(type default)
			)
			(layer "F.SilkS")
		)
		(fp_line
			(start -2.6797 -0.508)
			(end -2.6797 0.508)
			(stroke
				(width 0.1524)
				(type default)
			)
			(layer "F.SilkS")
		)
		(fp_line
			(start -2.6797 -1.4351)
			(end -2.6797 1.4351)
			(stroke
				(width 0.1524)
				(type default)
			)
			(layer "F.SilkS")
		)
		(fp_poly
			(pts
				(xy -2.2225 -1.4351) (xy -2.2225 1.4351) (xy 2.1463 1.4351) (xy 2.1463 -1.4351)
			)
			(stroke
				(width 0)
				(type default)
			)
			(fill yes)
			(layer "F.SilkS")
		)
		(fp_rect
			(start -2.7559 3.3655)
			(end 2.7559 -3.3655)
			(stroke
				(width 0)
				(type default)
			)
			(fill no)
			(layer "F.CrtYd")
		)
		(fp_rect
			(start -2.7559 3.3655)
			(end 2.7559 -3.3655)
			(stroke
				(width 0)
				(type default)
			)
			(fill no)
			(layer "F.Fab")
		)
		(pad "1" smd rect
			(at -1.905 2.4765 180)
			(size 0.635 1.524)
			(layers "F.Cu" "F.Mask" "F.Paste")
			(net "EEPROM_A0")
		)
		(pad "2" smd rect
			(at -0.635 2.4765 180)
			(size 0.635 1.524)
			(layers "F.Cu" "F.Mask" "F.Paste")
			(net "EEPROM_A1")
		)
		(pad "3" smd rect
			(at 0.635 2.4765 180)
			(size 0.635 1.524)
			(layers "F.Cu" "F.Mask" "F.Paste")
			(net "EEPROM_A2")
		)
		(pad "4" smd rect
			(at 1.905 2.4765 180)
			(size 0.635 1.524)
			(layers "F.Cu" "F.Mask" "F.Paste")
			(net "GND")
		)
		(pad "5" smd rect
			(at 1.905 -2.4765 180)
			(size 0.635 1.524)
			(layers "F.Cu" "F.Mask" "F.Paste")
			(net "EEPROM_DATA")
		)
		(pad "6" smd rect
			(at 0.635 -2.4765 180)
			(size 0.635 1.524)
			(layers "F.Cu" "F.Mask" "F.Paste")
			(net "EEPROM_CLK")
		)
		(pad "7" smd rect
			(at -0.635 -2.4765 180)
			(size 0.635 1.524)
			(layers "F.Cu" "F.Mask" "F.Paste")
			(net "EEPROM_WP")
		)
		(pad "8" smd rect
			(at -1.905 -2.4765 180)
			(size 0.635 1.524)
			(layers "F.Cu" "F.Mask" "F.Paste")
			(net "P3V3_STBY")
		)
	)
	(footprint ""
		(layer "F.Cu")
		(at 111.631984 -58.944002 90)
		(property "Reference" "R22"
			(at 0 0 90)
			(layer "F.SilkS")
			(hide yes)
			(effects
				(font
					(size 1.27 1.27)
				)
			)
		)
		(property "Value" "100R3F-1-GP"
			(at -0.0254 -2.5146 90)
			(unlocked yes)
			(layer "F.Fab")
			(hide yes)
			(effects
				(font
					(size 1.016 1.016)
					(thickness 0.1524)
				)
			)
		)
		(property "Device Type" "R603H22"
			(at -0.0254 -4.0386 90)
			(unlocked yes)
			(layer "F.Fab")
			(hide yes)
			(effects
				(font
					(size 1.016 1.016)
					(thickness 0.1524)
				)
			)
		)
		(duplicate_pad_numbers_are_jumpers no)
		(fp_line
			(start 0.4318 0)
			(end 0.2032 0)
			(stroke
				(width 0.2032)
				(type default)
			)
			(layer "F.SilkS")
		)
		(fp_line
			(start -0.2032 0)
			(end -0.4191 0)
			(stroke
				(width 0.2032)
				(type default)
			)
			(layer "F.SilkS")
		)
		(fp_rect
			(start -0.635 1.1811)
			(end 0.635 -1.1811)
			(stroke
				(width 0)
				(type default)
			)
			(fill no)
			(layer "F.CrtYd")
		)
		(fp_rect
			(start -0.635 1.1811)
			(end 0.635 -1.1811)
			(stroke
				(width 0)
				(type default)
			)
			(fill no)
			(layer "F.Fab")
		)
		(pad "1" smd custom
			(at 0 -0.6604 90)
			(size 0.19685 0.19685)
			(layers "F.Cu" "F.Mask" "F.Paste")
			(net "M_A_MON2_P")
			(options
				(clearance outline)
				(anchor circle)
			)
			(primitives
				(gr_poly
					(pts
						(arc
							(start 0.508 -0.2921)
							(mid 0.478242 -0.363942)
							(end 0.4064 -0.3937)
						)
						(arc
							(start -0.4064 -0.3937)
							(mid -0.478242 -0.363942)
							(end -0.508 -0.2921)
						)
						(arc
							(start -0.508 0.2921)
							(mid -0.478242 0.363942)
							(end -0.4064 0.3937)
						)
						(arc
							(start 0.4064 0.3937)
							(mid 0.478242 0.363942)
							(end 0.508 0.2921)
						)
					)
					(width 0)
					(fill yes)
				)
			)
		)
		(pad "2" smd custom
			(at 0 0.6604 90)
			(size 0.19685 0.19685)
			(layers "F.Cu" "F.Mask" "F.Paste")
			(net "M_A_MON2_N")
			(options
				(clearance outline)
				(anchor circle)
			)
			(primitives
				(gr_poly
					(pts
						(arc
							(start 0.508 -0.2921)
							(mid 0.478242 -0.363942)
							(end 0.4064 -0.3937)
						)
						(arc
							(start -0.4064 -0.3937)
							(mid -0.478242 -0.363942)
							(end -0.508 -0.2921)
						)
						(arc
							(start -0.508 0.2921)
							(mid -0.478242 0.363942)
							(end -0.4064 0.3937)
						)
						(arc
							(start 0.4064 0.3937)
							(mid 0.478242 0.363942)
							(end 0.508 0.2921)
						)
					)
					(width 0)
					(fill yes)
				)
			)
		)
	)
	(footprint ""
		(layer "F.Cu")
		(at 53.34 -53.467 -90)
		(property "Reference" "PG4"
			(at 0 0 270)
			(layer "F.SilkS")
			(hide yes)
			(effects
				(font
					(size 1.27 1.27)
				)
			)
		)
		(property "Value" "COPPER-CLOSE-GP-U"
			(at 0.0762 -2.8702 270)
			(unlocked yes)
			(layer "F.Fab")
			(hide yes)
			(effects
				(font
					(size 1.016 1.016)
					(thickness 0.1524)
				)
			)
		)
		(property "Device Type" "CON2C-U"
			(at 0.0762 -4.3942 270)
			(unlocked yes)
			(layer "F.Fab")
			(hide yes)
			(effects
				(font
					(size 1.016 1.016)
					(thickness 0.1524)
				)
			)
		)
		(duplicate_pad_numbers_are_jumpers no)
		(fp_rect
			(start -0.9398 0.9652)
			(end 0.9398 -0.9652)
			(stroke
				(width 0)
				(type default)
			)
			(fill no)
			(layer "F.CrtYd")
		)
		(fp_rect
			(start -0.9398 0.9652)
			(end 0.9398 -0.9652)
			(stroke
				(width 0)
				(type default)
			)
			(fill no)
			(layer "F.Fab")
		)
		(pad "1" smd custom
			(at 0 -0.5334 270)
			(size 0.17145 0.17145)
			(layers "F.Cu" "F.Mask" "F.Paste")
			(net "AGND_P1V0_STBY")
			(options
				(clearance outline)
				(anchor circle)
			)
			(primitives
				(gr_poly
					(pts
						(xy -0.127 0.3429) (xy -0.127 0.1651) (xy -0.635 -0.3429) (xy 0.635 -0.3429) (xy 0.127 0.1651)
						(xy 0.127 0.3429)
					)
					(width 0)
					(fill yes)
				)
			)
		)
		(pad "2" smd custom
			(at 0 0.5334 270)
			(size 0.17145 0.17145)
			(layers "F.Cu" "F.Mask" "F.Paste")
			(net "GND")
			(options
				(clearance outline)
				(anchor circle)
			)
			(primitives
				(gr_poly
					(pts
						(xy -0.635 0.3429) (xy -0.127 -0.1651) (xy -0.127 -0.3429) (xy 0.127 -0.3429) (xy 0.127 -0.1651)
						(xy 0.635 0.3429)
					)
					(width 0)
					(fill yes)
				)
			)
		)
	)
	(footprint ""
		(layer "F.Cu")
		(at 188.976 -41.529 180)
		(property "Reference" "PR115"
			(at 0 0 180)
			(layer "F.SilkS")
			(hide yes)
			(effects
				(font
					(size 1.27 1.27)
				)
			)
		)
		(property "Value" "10KR2F-2-GP"
			(at 1.7907 -1.1176 180)
			(unlocked yes)
			(layer "F.Fab")
			(hide yes)
			(effects
				(font
					(size 1.016 1.016)
					(thickness 0.1524)
				)
			)
		)
		(property "Device Type" "R402H16"
			(at 1.7907 -2.6416 180)
			(unlocked yes)
			(layer "F.Fab")
			(hide yes)
			(effects
				(font
					(size 1.016 1.016)
					(thickness 0.1524)
				)
			)
		)
		(duplicate_pad_numbers_are_jumpers no)
		(fp_rect
			(start -0.381 0.8382)
			(end 0.381 -0.8382)
			(stroke
				(width 0)
				(type default)
			)
			(fill no)
			(layer "F.CrtYd")
		)
		(fp_rect
			(start -0.381 0.8382)
			(end 0.381 -0.8382)
			(stroke
				(width 0)
				(type default)
			)
			(fill no)
			(layer "F.Fab")
		)
		(pad "1" smd custom
			(at 0 -0.4318 180)
			(size 0.127 0.127)
			(layers "F.Cu" "F.Mask" "F.Paste")
			(net "VR_PVDDR_A_VAUTO")
			(options
				(clearance outline)
				(anchor circle)
			)
			(primitives
				(gr_poly
					(pts
						(arc
							(start -0.2032 -0.2794)
							(mid -0.239121 -0.264521)
							(end -0.254 -0.2286)
						)
						(arc
							(start -0.254 0.2286)
							(mid -0.239121 0.264521)
							(end -0.2032 0.2794)
						)
						(arc
							(start 0.2032 0.2794)
							(mid 0.239121 0.264521)
							(end 0.254 0.2286)
						)
						(arc
							(start 0.254 -0.2286)
							(mid 0.239121 -0.264521)
							(end 0.2032 -0.2794)
						)
					)
					(width 0)
					(fill yes)
				)
			)
		)
		(pad "2" smd custom
			(at 0 0.4318 180)
			(size 0.127 0.127)
			(layers "F.Cu" "F.Mask" "F.Paste")
			(net "PV_VDDR")
			(options
				(clearance outline)
				(anchor circle)
			)
			(primitives
				(gr_poly
					(pts
						(arc
							(start -0.2032 -0.2794)
							(mid -0.239121 -0.264521)
							(end -0.254 -0.2286)
						)
						(arc
							(start -0.254 0.2286)
							(mid -0.239121 0.264521)
							(end -0.2032 0.2794)
						)
						(arc
							(start 0.2032 0.2794)
							(mid 0.239121 0.264521)
							(end 0.254 0.2286)
						)
						(arc
							(start 0.254 -0.2286)
							(mid 0.239121 -0.264521)
							(end 0.2032 -0.2794)
						)
					)
					(width 0)
					(fill yes)
				)
			)
		)
	)
	(footprint ""
		(layer "F.Cu")
		(at 12.954 -31.877)
		(property "Reference" "PR199"
			(at 0 0 0)
			(layer "F.SilkS")
			(hide yes)
			(effects
				(font
					(size 1.27 1.27)
				)
			)
		)
		(property "Value" "10KR2F-2-GP"
			(at 1.7907 -1.1176 0)
			(unlocked yes)
			(layer "F.Fab")
			(hide yes)
			(effects
				(font
					(size 1.016 1.016)
					(thickness 0.1524)
				)
			)
		)
		(property "Device Type" "R402H16"
			(at 1.7907 -2.6416 0)
			(unlocked yes)
			(layer "F.Fab")
			(hide yes)
			(effects
				(font
					(size 1.016 1.016)
					(thickness 0.1524)
				)
			)
		)
		(duplicate_pad_numbers_are_jumpers no)
		(fp_rect
			(start -0.381 0.8382)
			(end 0.381 -0.8382)
			(stroke
				(width 0)
				(type default)
			)
			(fill no)
			(layer "F.CrtYd")
		)
		(fp_rect
			(start -0.381 0.8382)
			(end 0.381 -0.8382)
			(stroke
				(width 0)
				(type default)
			)
			(fill no)
			(layer "F.Fab")
		)
		(pad "1" smd custom
			(at 0 -0.4318)
			(size 0.127 0.127)
			(layers "F.Cu" "F.Mask" "F.Paste")
			(net "P3V3_STBY_VFB")
			(options
				(clearance outline)
				(anchor circle)
			)
			(primitives
				(gr_poly
					(pts
						(arc
							(start -0.2032 -0.2794)
							(mid -0.239121 -0.264521)
							(end -0.254 -0.2286)
						)
						(arc
							(start -0.254 0.2286)
							(mid -0.239121 0.264521)
							(end -0.2032 0.2794)
						)
						(arc
							(start 0.2032 0.2794)
							(mid 0.239121 0.264521)
							(end 0.254 0.2286)
						)
						(arc
							(start 0.254 -0.2286)
							(mid 0.239121 -0.264521)
							(end 0.2032 -0.2794)
						)
					)
					(width 0)
					(fill yes)
				)
			)
		)
		(pad "2" smd custom
			(at 0 0.4318)
			(size 0.127 0.127)
			(layers "F.Cu" "F.Mask" "F.Paste")
			(net "AGND_P3V3_STBY")
			(options
				(clearance outline)
				(anchor circle)
			)
			(primitives
				(gr_poly
					(pts
						(arc
							(start -0.2032 -0.2794)
							(mid -0.239121 -0.264521)
							(end -0.254 -0.2286)
						)
						(arc
							(start -0.254 0.2286)
							(mid -0.239121 0.264521)
							(end -0.2032 0.2794)
						)
						(arc
							(start 0.2032 0.2794)
							(mid 0.239121 0.264521)
							(end 0.254 0.2286)
						)
						(arc
							(start 0.254 -0.2286)
							(mid 0.239121 -0.264521)
							(end 0.2032 -0.2794)
						)
					)
					(width 0)
					(fill yes)
				)
			)
		)
	)
	(footprint ""
		(layer "F.Cu")
		(at 47.5488 -35.5854 180)
		(property "Reference" "C116"
			(at 0 0 180)
			(layer "F.SilkS")
			(hide yes)
			(effects
				(font
					(size 1.27 1.27)
				)
			)
		)
		(property "Value" "SC10U6D3V3MX-GP"
			(at -0.0254 -2.0193 180)
			(unlocked yes)
			(layer "F.Fab")
			(hide yes)
			(effects
				(font
					(size 1.016 1.016)
					(thickness 0.1524)
				)
			)
		)
		(property "Device Type" "C603H38"
			(at -0.0254 -3.5433 180)
			(unlocked yes)
			(layer "F.Fab")
			(hide yes)
			(effects
				(font
					(size 1.016 1.016)
					(thickness 0.1524)
				)
			)
		)
		(duplicate_pad_numbers_are_jumpers no)
		(fp_line
			(start -0.4064 0)
			(end 0.4064 0)
			(stroke
				(width 0.2286)
				(type default)
			)
			(layer "F.SilkS")
		)
		(fp_rect
			(start -0.635 1.1811)
			(end 0.635 -1.1811)
			(stroke
				(width 0)
				(type default)
			)
			(fill no)
			(layer "F.CrtYd")
		)
		(fp_rect
			(start -0.635 1.1811)
			(end 0.635 -1.1811)
			(stroke
				(width 0)
				(type default)
			)
			(fill no)
			(layer "F.Fab")
		)
		(pad "1" smd custom
			(at 0 -0.6604 180)
			(size 0.19685 0.19685)
			(layers "F.Cu" "F.Mask" "F.Paste")
			(net "XDP_RTEST#")
			(options
				(clearance outline)
				(anchor circle)
			)
			(primitives
				(gr_poly
					(pts
						(arc
							(start 0.508 -0.2921)
							(mid 0.478242 -0.363942)
							(end 0.4064 -0.3937)
						)
						(arc
							(start -0.4064 -0.3937)
							(mid -0.478242 -0.363942)
							(end -0.508 -0.2921)
						)
						(arc
							(start -0.508 0.2921)
							(mid -0.478242 0.363942)
							(end -0.4064 0.3937)
						)
						(arc
							(start 0.4064 0.3937)
							(mid 0.478242 0.363942)
							(end 0.508 0.2921)
						)
					)
					(width 0)
					(fill yes)
				)
			)
		)
		(pad "2" smd custom
			(at 0 0.6604 180)
			(size 0.19685 0.19685)
			(layers "F.Cu" "F.Mask" "F.Paste")
			(net "GND")
			(options
				(clearance outline)
				(anchor circle)
			)
			(primitives
				(gr_poly
					(pts
						(arc
							(start 0.508 -0.2921)
							(mid 0.478242 -0.363942)
							(end 0.4064 -0.3937)
						)
						(arc
							(start -0.4064 -0.3937)
							(mid -0.478242 -0.363942)
							(end -0.508 -0.2921)
						)
						(arc
							(start -0.508 0.2921)
							(mid -0.478242 0.363942)
							(end -0.4064 0.3937)
						)
						(arc
							(start 0.4064 0.3937)
							(mid 0.478242 0.363942)
							(end 0.508 0.2921)
						)
					)
					(width 0)
					(fill yes)
				)
			)
		)
	)
	(footprint ""
		(layer "F.Cu")
		(at 132.715 -51.689)
		(property "Reference" "R13"
			(at 0 0 0)
			(layer "F.SilkS")
			(hide yes)
			(effects
				(font
					(size 1.27 1.27)
				)
			)
		)
		(property "Value" "1KR2F-3-GP"
			(at 1.7907 -1.1176 0)
			(unlocked yes)
			(layer "F.Fab")
			(hide yes)
			(effects
				(font
					(size 1.016 1.016)
					(thickness 0.1524)
				)
			)
		)
		(property "Device Type" "R402H16"
			(at 1.7907 -2.6416 0)
			(unlocked yes)
			(layer "F.Fab")
			(hide yes)
			(effects
				(font
					(size 1.016 1.016)
					(thickness 0.1524)
				)
			)
		)
		(duplicate_pad_numbers_are_jumpers no)
		(fp_rect
			(start -0.381 0.8382)
			(end 0.381 -0.8382)
			(stroke
				(width 0)
				(type default)
			)
			(fill no)
			(layer "F.CrtYd")
		)
		(fp_rect
			(start -0.381 0.8382)
			(end 0.381 -0.8382)
			(stroke
				(width 0)
				(type default)
			)
			(fill no)
			(layer "F.Fab")
		)
		(pad "1" smd custom
			(at 0 -0.4318)
			(size 0.127 0.127)
			(layers "F.Cu" "F.Mask" "F.Paste")
			(net "P1V0")
			(options
				(clearance outline)
				(anchor circle)
			)
			(primitives
				(gr_poly
					(pts
						(arc
							(start -0.2032 -0.2794)
							(mid -0.239121 -0.264521)
							(end -0.254 -0.2286)
						)
						(arc
							(start -0.254 0.2286)
							(mid -0.239121 0.264521)
							(end -0.2032 0.2794)
						)
						(arc
							(start 0.2032 0.2794)
							(mid 0.239121 0.264521)
							(end 0.254 0.2286)
						)
						(arc
							(start 0.254 -0.2286)
							(mid 0.239121 -0.264521)
							(end 0.2032 -0.2794)
						)
					)
					(width 0)
					(fill yes)
				)
			)
		)
		(pad "2" smd custom
			(at 0 0.4318)
			(size 0.127 0.127)
			(layers "F.Cu" "F.Mask" "F.Paste")
			(net "MEMORY_HOT_N_LV_B2")
			(options
				(clearance outline)
				(anchor circle)
			)
			(primitives
				(gr_poly
					(pts
						(arc
							(start -0.2032 -0.2794)
							(mid -0.239121 -0.264521)
							(end -0.254 -0.2286)
						)
						(arc
							(start -0.254 0.2286)
							(mid -0.239121 0.264521)
							(end -0.2032 0.2794)
						)
						(arc
							(start 0.2032 0.2794)
							(mid 0.239121 0.264521)
							(end 0.254 0.2286)
						)
						(arc
							(start 0.254 -0.2286)
							(mid 0.239121 -0.264521)
							(end 0.2032 -0.2794)
						)
					)
					(width 0)
					(fill yes)
				)
			)
		)
	)
	(footprint ""
		(layer "F.Cu")
		(at 6.7818 -52.5526 90)
		(property "Reference" "R9"
			(at 0 0 90)
			(layer "F.SilkS")
			(hide yes)
			(effects
				(font
					(size 1.27 1.27)
				)
			)
		)
		(property "Value" "4K7R2F-GP"
			(at 0.064008 -3.993896 90)
			(unlocked yes)
			(layer "F.Fab")
			(hide yes)
			(effects
				(font
					(size 1.016 1.016)
					(thickness 0.1524)
				)
			)
		)
		(property "Device Type" "R402H16"
			(at 0.064008 -5.517896 90)
			(unlocked yes)
			(layer "F.Fab")
			(hide yes)
			(effects
				(font
					(size 1.016 1.016)
					(thickness 0.1524)
				)
			)
		)
		(duplicate_pad_numbers_are_jumpers no)
		(fp_rect
			(start -0.381 0.8382)
			(end 0.381 -0.8382)
			(stroke
				(width 0)
				(type default)
			)
			(fill no)
			(layer "F.CrtYd")
		)
		(fp_rect
			(start -0.381 0.8382)
			(end 0.381 -0.8382)
			(stroke
				(width 0)
				(type default)
			)
			(fill no)
			(layer "F.Fab")
		)
		(pad "1" smd custom
			(at 0 -0.4318 90)
			(size 0.127 0.127)
			(layers "F.Cu" "F.Mask" "F.Paste")
			(net "P3V3_STBY")
			(options
				(clearance outline)
				(anchor circle)
			)
			(primitives
				(gr_poly
					(pts
						(arc
							(start -0.2032 -0.2794)
							(mid -0.239121 -0.264521)
							(end -0.254 -0.2286)
						)
						(arc
							(start -0.254 0.2286)
							(mid -0.239121 0.264521)
							(end -0.2032 0.2794)
						)
						(arc
							(start 0.2032 0.2794)
							(mid 0.239121 0.264521)
							(end 0.254 0.2286)
						)
						(arc
							(start 0.254 -0.2286)
							(mid 0.239121 -0.264521)
							(end 0.2032 -0.2794)
						)
					)
					(width 0)
					(fill yes)
				)
			)
		)
		(pad "2" smd custom
			(at 0 0.4318 90)
			(size 0.127 0.127)
			(layers "F.Cu" "F.Mask" "F.Paste")
			(net "TEMP_1_A1")
			(options
				(clearance outline)
				(anchor circle)
			)
			(primitives
				(gr_poly
					(pts
						(arc
							(start -0.2032 -0.2794)
							(mid -0.239121 -0.264521)
							(end -0.254 -0.2286)
						)
						(arc
							(start -0.254 0.2286)
							(mid -0.239121 0.264521)
							(end -0.2032 0.2794)
						)
						(arc
							(start 0.2032 0.2794)
							(mid 0.239121 0.264521)
							(end 0.254 0.2286)
						)
						(arc
							(start 0.254 -0.2286)
							(mid 0.239121 -0.264521)
							(end 0.2032 -0.2794)
						)
					)
					(width 0)
					(fill yes)
				)
			)
		)
	)
	(footprint ""
		(layer "F.Cu")
		(at 154.94 -12.447778 90)
		(property "Reference" "PR217"
			(at 0 0 90)
			(layer "F.SilkS")
			(hide yes)
			(effects
				(font
					(size 1.27 1.27)
				)
			)
		)
		(property "Value" "0R2J-2-GP"
			(at 1.7907 -1.1176 90)
			(unlocked yes)
			(layer "F.Fab")
			(hide yes)
			(effects
				(font
					(size 1.016 1.016)
					(thickness 0.1524)
				)
			)
		)
		(property "Device Type" "R402H16"
			(at 1.7907 -2.6416 90)
			(unlocked yes)
			(layer "F.Fab")
			(hide yes)
			(effects
				(font
					(size 1.016 1.016)
					(thickness 0.1524)
				)
			)
		)
		(duplicate_pad_numbers_are_jumpers no)
		(fp_rect
			(start -0.381 0.8382)
			(end 0.381 -0.8382)
			(stroke
				(width 0)
				(type default)
			)
			(fill no)
			(layer "F.CrtYd")
		)
		(fp_rect
			(start -0.381 0.8382)
			(end 0.381 -0.8382)
			(stroke
				(width 0)
				(type default)
			)
			(fill no)
			(layer "F.Fab")
		)
		(pad "1" smd custom
			(at 0 -0.4318 90)
			(size 0.127 0.127)
			(layers "F.Cu" "F.Mask" "F.Paste")
			(net "VR_PVDDR_A_VTT")
			(options
				(clearance outline)
				(anchor circle)
			)
			(primitives
				(gr_poly
					(pts
						(arc
							(start -0.2032 -0.2794)
							(mid -0.239121 -0.264521)
							(end -0.254 -0.2286)
						)
						(arc
							(start -0.254 0.2286)
							(mid -0.239121 0.264521)
							(end -0.2032 0.2794)
						)
						(arc
							(start 0.2032 0.2794)
							(mid 0.239121 0.264521)
							(end 0.254 0.2286)
						)
						(arc
							(start 0.254 -0.2286)
							(mid 0.239121 -0.264521)
							(end 0.2032 -0.2794)
						)
					)
					(width 0)
					(fill yes)
				)
			)
		)
		(pad "2" smd custom
			(at 0 0.4318 90)
			(size 0.127 0.127)
			(layers "F.Cu" "F.Mask" "F.Paste")
			(net "PV_VDDR")
			(options
				(clearance outline)
				(anchor circle)
			)
			(primitives
				(gr_poly
					(pts
						(arc
							(start -0.2032 -0.2794)
							(mid -0.239121 -0.264521)
							(end -0.254 -0.2286)
						)
						(arc
							(start -0.254 0.2286)
							(mid -0.239121 0.264521)
							(end -0.2032 0.2794)
						)
						(arc
							(start 0.2032 0.2794)
							(mid 0.239121 0.264521)
							(end 0.254 0.2286)
						)
						(arc
							(start 0.254 -0.2286)
							(mid 0.239121 -0.264521)
							(end 0.2032 -0.2794)
						)
					)
					(width 0)
					(fill yes)
				)
			)
		)
	)
	(footprint ""
		(layer "F.Cu")
		(at 156.464 -27.305)
		(property "Reference" "C236"
			(at 0 0 0)
			(layer "F.SilkS")
			(hide yes)
			(effects
				(font
					(size 1.27 1.27)
				)
			)
		)
		(property "Value" "SCD1U10V2KX-5GP"
			(at 1.1811 -2.7051 0)
			(unlocked yes)
			(layer "F.Fab")
			(hide yes)
			(effects
				(font
					(size 1.016 1.016)
					(thickness 0.1524)
				)
			)
		)
		(property "Device Type" "C402H22"
			(at 1.1811 -4.2291 0)
			(unlocked yes)
			(layer "F.Fab")
			(hide yes)
			(effects
				(font
					(size 1.016 1.016)
					(thickness 0.1524)
				)
			)
		)
		(duplicate_pad_numbers_are_jumpers no)
		(fp_rect
			(start -0.381 0.7366)
			(end 0.381 -0.7366)
			(stroke
				(width 0)
				(type default)
			)
			(fill no)
			(layer "F.CrtYd")
		)
		(fp_rect
			(start -0.381 0.7366)
			(end 0.381 -0.7366)
			(stroke
				(width 0)
				(type default)
			)
			(fill no)
			(layer "F.Fab")
		)
		(pad "1" smd custom
			(at 0 -0.4572)
			(size 0.1143 0.1143)
			(layers "F.Cu" "F.Mask" "F.Paste")
			(net "P3V3_STBY")
			(options
				(clearance outline)
				(anchor circle)
			)
			(primitives
				(gr_poly
					(pts
						(arc
							(start -0.254 -0.1778)
							(mid -0.239121 -0.213721)
							(end -0.2032 -0.2286)
						)
						(arc
							(start 0.2032 -0.2286)
							(mid 0.239121 -0.213721)
							(end 0.254 -0.1778)
						)
						(arc
							(start 0.254 0.1778)
							(mid 0.239121 0.213721)
							(end 0.2032 0.2286)
						)
						(arc
							(start -0.2032 0.2286)
							(mid -0.239121 0.213721)
							(end -0.254 0.1778)
						)
					)
					(width 0)
					(fill yes)
				)
			)
		)
		(pad "2" smd custom
			(at 0 0.4572)
			(size 0.1143 0.1143)
			(layers "F.Cu" "F.Mask" "F.Paste")
			(net "GND")
			(options
				(clearance outline)
				(anchor circle)
			)
			(primitives
				(gr_poly
					(pts
						(arc
							(start -0.254 -0.1778)
							(mid -0.239121 -0.213721)
							(end -0.2032 -0.2286)
						)
						(arc
							(start 0.2032 -0.2286)
							(mid 0.239121 -0.213721)
							(end 0.254 -0.1778)
						)
						(arc
							(start 0.254 0.1778)
							(mid 0.239121 0.213721)
							(end 0.2032 0.2286)
						)
						(arc
							(start -0.2032 0.2286)
							(mid -0.239121 0.213721)
							(end -0.254 0.1778)
						)
					)
					(width 0)
					(fill yes)
				)
			)
		)
	)
	(footprint ""
		(layer "F.Cu")
		(at 60.706 -25.527)
		(property "Reference" "R254"
			(at 0 0 0)
			(layer "F.SilkS")
			(hide yes)
			(effects
				(font
					(size 1.27 1.27)
				)
			)
		)
		(property "Value" "4K02R2F-GP"
			(at 0.064008 -3.993896 0)
			(unlocked yes)
			(layer "F.Fab")
			(hide yes)
			(effects
				(font
					(size 1.016 1.016)
					(thickness 0.1524)
				)
			)
		)
		(property "Device Type" "R402H16"
			(at 0.064008 -5.517896 0)
			(unlocked yes)
			(layer "F.Fab")
			(hide yes)
			(effects
				(font
					(size 1.016 1.016)
					(thickness 0.1524)
				)
			)
		)
		(duplicate_pad_numbers_are_jumpers no)
		(fp_rect
			(start -0.381 0.8382)
			(end 0.381 -0.8382)
			(stroke
				(width 0)
				(type default)
			)
			(fill no)
			(layer "F.CrtYd")
		)
		(fp_rect
			(start -0.381 0.8382)
			(end 0.381 -0.8382)
			(stroke
				(width 0)
				(type default)
			)
			(fill no)
			(layer "F.Fab")
		)
		(pad "1" smd custom
			(at 0 -0.4318)
			(size 0.127 0.127)
			(layers "F.Cu" "F.Mask" "F.Paste")
			(net "SW_P1V8_EN_G")
			(options
				(clearance outline)
				(anchor circle)
			)
			(primitives
				(gr_poly
					(pts
						(arc
							(start -0.2032 -0.2794)
							(mid -0.239121 -0.264521)
							(end -0.254 -0.2286)
						)
						(arc
							(start -0.254 0.2286)
							(mid -0.239121 0.264521)
							(end -0.2032 0.2794)
						)
						(arc
							(start 0.2032 0.2794)
							(mid 0.239121 0.264521)
							(end 0.254 0.2286)
						)
						(arc
							(start 0.254 -0.2286)
							(mid 0.239121 -0.264521)
							(end 0.2032 -0.2794)
						)
					)
					(width 0)
					(fill yes)
				)
			)
		)
		(pad "2" smd custom
			(at 0 0.4318)
			(size 0.127 0.127)
			(layers "F.Cu" "F.Mask" "F.Paste")
			(net "P3V3_STBY")
			(options
				(clearance outline)
				(anchor circle)
			)
			(primitives
				(gr_poly
					(pts
						(arc
							(start -0.2032 -0.2794)
							(mid -0.239121 -0.264521)
							(end -0.254 -0.2286)
						)
						(arc
							(start -0.254 0.2286)
							(mid -0.239121 0.264521)
							(end -0.2032 0.2794)
						)
						(arc
							(start 0.2032 0.2794)
							(mid 0.239121 0.264521)
							(end 0.254 0.2286)
						)
						(arc
							(start 0.254 -0.2286)
							(mid 0.239121 -0.264521)
							(end 0.2032 -0.2794)
						)
					)
					(width 0)
					(fill yes)
				)
			)
		)
	)
	(footprint ""
		(layer "F.Cu")
		(at 29.3243 -35.433)
		(property "Reference" "R489"
			(at 0 0 0)
			(layer "F.SilkS")
			(hide yes)
			(effects
				(font
					(size 1.27 1.27)
				)
			)
		)
		(property "Value" "51R2F-2-GP"
			(at 1.7907 -1.1176 0)
			(unlocked yes)
			(layer "F.Fab")
			(hide yes)
			(effects
				(font
					(size 1.016 1.016)
					(thickness 0.1524)
				)
			)
		)
		(property "Device Type" "R402H16"
			(at 1.7907 -2.6416 0)
			(unlocked yes)
			(layer "F.Fab")
			(hide yes)
			(effects
				(font
					(size 1.016 1.016)
					(thickness 0.1524)
				)
			)
		)
		(duplicate_pad_numbers_are_jumpers no)
		(fp_rect
			(start -0.381 0.8382)
			(end 0.381 -0.8382)
			(stroke
				(width 0)
				(type default)
			)
			(fill no)
			(layer "F.CrtYd")
		)
		(fp_rect
			(start -0.381 0.8382)
			(end 0.381 -0.8382)
			(stroke
				(width 0)
				(type default)
			)
			(fill no)
			(layer "F.Fab")
		)
		(pad "1" smd custom
			(at 0 -0.4318)
			(size 0.127 0.127)
			(layers "F.Cu" "F.Mask" "F.Paste")
			(net "XDP_SOC_CPU_TDI")
			(options
				(clearance outline)
				(anchor circle)
			)
			(primitives
				(gr_poly
					(pts
						(arc
							(start -0.2032 -0.2794)
							(mid -0.239121 -0.264521)
							(end -0.254 -0.2286)
						)
						(arc
							(start -0.254 0.2286)
							(mid -0.239121 0.264521)
							(end -0.2032 0.2794)
						)
						(arc
							(start 0.2032 0.2794)
							(mid 0.239121 0.264521)
							(end 0.254 0.2286)
						)
						(arc
							(start 0.254 -0.2286)
							(mid 0.239121 -0.264521)
							(end 0.2032 -0.2794)
						)
					)
					(width 0)
					(fill yes)
				)
			)
		)
		(pad "2" smd custom
			(at 0 0.4318)
			(size 0.127 0.127)
			(layers "F.Cu" "F.Mask" "F.Paste")
			(net "GND")
			(options
				(clearance outline)
				(anchor circle)
			)
			(primitives
				(gr_poly
					(pts
						(arc
							(start -0.2032 -0.2794)
							(mid -0.239121 -0.264521)
							(end -0.254 -0.2286)
						)
						(arc
							(start -0.254 0.2286)
							(mid -0.239121 0.264521)
							(end -0.2032 0.2794)
						)
						(arc
							(start 0.2032 0.2794)
							(mid 0.239121 0.264521)
							(end 0.254 0.2286)
						)
						(arc
							(start 0.254 -0.2286)
							(mid 0.239121 -0.264521)
							(end 0.2032 -0.2794)
						)
					)
					(width 0)
					(fill yes)
				)
			)
		)
	)
	(footprint ""
		(layer "F.Cu")
		(at 73.279 -41.656 -90)
		(property "Reference" "R306"
			(at 0 0 270)
			(layer "F.SilkS")
			(hide yes)
			(effects
				(font
					(size 1.27 1.27)
				)
			)
		)
		(property "Value" "4K7R2F-GP"
			(at 0.064008 -3.993896 270)
			(unlocked yes)
			(layer "F.Fab")
			(hide yes)
			(effects
				(font
					(size 1.016 1.016)
					(thickness 0.1524)
				)
			)
		)
		(property "Device Type" "R402H16"
			(at 0.064008 -5.517896 270)
			(unlocked yes)
			(layer "F.Fab")
			(hide yes)
			(effects
				(font
					(size 1.016 1.016)
					(thickness 0.1524)
				)
			)
		)
		(duplicate_pad_numbers_are_jumpers no)
		(fp_rect
			(start -0.381 0.8382)
			(end 0.381 -0.8382)
			(stroke
				(width 0)
				(type default)
			)
			(fill no)
			(layer "F.CrtYd")
		)
		(fp_rect
			(start -0.381 0.8382)
			(end 0.381 -0.8382)
			(stroke
				(width 0)
				(type default)
			)
			(fill no)
			(layer "F.Fab")
		)
		(pad "1" smd custom
			(at 0 -0.4318 270)
			(size 0.127 0.127)
			(layers "F.Cu" "F.Mask" "F.Paste")
			(net "P3V3")
			(options
				(clearance outline)
				(anchor circle)
			)
			(primitives
				(gr_poly
					(pts
						(arc
							(start -0.2032 -0.2794)
							(mid -0.239121 -0.264521)
							(end -0.254 -0.2286)
						)
						(arc
							(start -0.254 0.2286)
							(mid -0.239121 0.264521)
							(end -0.2032 0.2794)
						)
						(arc
							(start 0.2032 0.2794)
							(mid 0.239121 0.264521)
							(end 0.254 0.2286)
						)
						(arc
							(start 0.254 -0.2286)
							(mid 0.239121 -0.264521)
							(end 0.2032 -0.2794)
						)
					)
					(width 0)
					(fill yes)
				)
			)
		)
		(pad "2" smd custom
			(at 0 0.4318 270)
			(size 0.127 0.127)
			(layers "F.Cu" "F.Mask" "F.Paste")
			(net "SMBUS_SW_EN")
			(options
				(clearance outline)
				(anchor circle)
			)
			(primitives
				(gr_poly
					(pts
						(arc
							(start -0.2032 -0.2794)
							(mid -0.239121 -0.264521)
							(end -0.254 -0.2286)
						)
						(arc
							(start -0.254 0.2286)
							(mid -0.239121 0.264521)
							(end -0.2032 0.2794)
						)
						(arc
							(start 0.2032 0.2794)
							(mid 0.239121 0.264521)
							(end 0.254 0.2286)
						)
						(arc
							(start 0.254 -0.2286)
							(mid 0.239121 -0.264521)
							(end 0.2032 -0.2794)
						)
					)
					(width 0)
					(fill yes)
				)
			)
		)
	)
	(footprint ""
		(layer "F.Cu")
		(at 163.9062 -12.828778 180)
		(property "Reference" "C342"
			(at 0 0 180)
			(layer "F.SilkS")
			(hide yes)
			(effects
				(font
					(size 1.27 1.27)
				)
			)
		)
		(property "Value" "SCD1U16V2KX-3GP"
			(at 1.8923 -1.2065 180)
			(unlocked yes)
			(layer "F.Fab")
			(hide yes)
			(effects
				(font
					(size 1.016 1.016)
					(thickness 0.1524)
				)
			)
		)
		(property "Device Type" "C402H22"
			(at 1.8923 -2.7305 180)
			(unlocked yes)
			(layer "F.Fab")
			(hide yes)
			(effects
				(font
					(size 1.016 1.016)
					(thickness 0.1524)
				)
			)
		)
		(duplicate_pad_numbers_are_jumpers no)
		(fp_rect
			(start -0.381 0.7366)
			(end 0.381 -0.7366)
			(stroke
				(width 0)
				(type default)
			)
			(fill no)
			(layer "F.CrtYd")
		)
		(fp_rect
			(start -0.381 0.7366)
			(end 0.381 -0.7366)
			(stroke
				(width 0)
				(type default)
			)
			(fill no)
			(layer "F.Fab")
		)
		(pad "1" smd custom
			(at 0 -0.4572 180)
			(size 0.1143 0.1143)
			(layers "F.Cu" "F.Mask" "F.Paste")
			(net "PV_VDDR")
			(options
				(clearance outline)
				(anchor circle)
			)
			(primitives
				(gr_poly
					(pts
						(arc
							(start -0.254 -0.1778)
							(mid -0.239121 -0.213721)
							(end -0.2032 -0.2286)
						)
						(arc
							(start 0.2032 -0.2286)
							(mid 0.239121 -0.213721)
							(end 0.254 -0.1778)
						)
						(arc
							(start 0.254 0.1778)
							(mid 0.239121 0.213721)
							(end 0.2032 0.2286)
						)
						(arc
							(start -0.2032 0.2286)
							(mid -0.239121 0.213721)
							(end -0.254 0.1778)
						)
					)
					(width 0)
					(fill yes)
				)
			)
		)
		(pad "2" smd custom
			(at 0 0.4572 180)
			(size 0.1143 0.1143)
			(layers "F.Cu" "F.Mask" "F.Paste")
			(net "GND")
			(options
				(clearance outline)
				(anchor circle)
			)
			(primitives
				(gr_poly
					(pts
						(arc
							(start -0.254 -0.1778)
							(mid -0.239121 -0.213721)
							(end -0.2032 -0.2286)
						)
						(arc
							(start 0.2032 -0.2286)
							(mid 0.239121 -0.213721)
							(end 0.254 -0.1778)
						)
						(arc
							(start 0.254 0.1778)
							(mid 0.239121 0.213721)
							(end 0.2032 0.2286)
						)
						(arc
							(start -0.2032 0.2286)
							(mid -0.239121 0.213721)
							(end -0.254 0.1778)
						)
					)
					(width 0)
					(fill yes)
				)
			)
		)
	)
	(footprint ""
		(layer "F.Cu")
		(at 18.9738 -35.3568 90)
		(property "Reference" "PR192"
			(at 0 0 90)
			(layer "F.SilkS")
			(hide yes)
			(effects
				(font
					(size 1.27 1.27)
				)
			)
		)
		(property "Value" "3K9R2F-GP"
			(at 1.7907 -1.1176 90)
			(unlocked yes)
			(layer "F.Fab")
			(hide yes)
			(effects
				(font
					(size 1.016 1.016)
					(thickness 0.1524)
				)
			)
		)
		(property "Device Type" "R402H16"
			(at 1.7907 -2.6416 90)
			(unlocked yes)
			(layer "F.Fab")
			(hide yes)
			(effects
				(font
					(size 1.016 1.016)
					(thickness 0.1524)
				)
			)
		)
		(duplicate_pad_numbers_are_jumpers no)
		(fp_rect
			(start -0.381 0.8382)
			(end 0.381 -0.8382)
			(stroke
				(width 0)
				(type default)
			)
			(fill no)
			(layer "F.CrtYd")
		)
		(fp_rect
			(start -0.381 0.8382)
			(end 0.381 -0.8382)
			(stroke
				(width 0)
				(type default)
			)
			(fill no)
			(layer "F.Fab")
		)
		(pad "1" smd custom
			(at 0 -0.4318 90)
			(size 0.127 0.127)
			(layers "F.Cu" "F.Mask" "F.Paste")
			(net "P3V3_STBY_LL")
			(options
				(clearance outline)
				(anchor circle)
			)
			(primitives
				(gr_poly
					(pts
						(arc
							(start -0.2032 -0.2794)
							(mid -0.239121 -0.264521)
							(end -0.254 -0.2286)
						)
						(arc
							(start -0.254 0.2286)
							(mid -0.239121 0.264521)
							(end -0.2032 0.2794)
						)
						(arc
							(start 0.2032 0.2794)
							(mid 0.239121 0.264521)
							(end 0.254 0.2286)
						)
						(arc
							(start 0.254 -0.2286)
							(mid 0.239121 -0.264521)
							(end 0.2032 -0.2794)
						)
					)
					(width 0)
					(fill yes)
				)
			)
		)
		(pad "2" smd custom
			(at 0 0.4318 90)
			(size 0.127 0.127)
			(layers "F.Cu" "F.Mask" "F.Paste")
			(net "P3V3_STBY_LL_R")
			(options
				(clearance outline)
				(anchor circle)
			)
			(primitives
				(gr_poly
					(pts
						(arc
							(start -0.2032 -0.2794)
							(mid -0.239121 -0.264521)
							(end -0.254 -0.2286)
						)
						(arc
							(start -0.254 0.2286)
							(mid -0.239121 0.264521)
							(end -0.2032 0.2794)
						)
						(arc
							(start 0.2032 0.2794)
							(mid 0.239121 0.264521)
							(end 0.254 0.2286)
						)
						(arc
							(start 0.254 -0.2286)
							(mid 0.239121 -0.264521)
							(end 0.2032 -0.2794)
						)
					)
					(width 0)
					(fill yes)
				)
			)
		)
	)
	(footprint ""
		(layer "F.Cu")
		(at 112.9284 -64.2874)
		(property "Reference" "R18"
			(at 0 0 0)
			(layer "F.SilkS")
			(hide yes)
			(effects
				(font
					(size 1.27 1.27)
				)
			)
		)
		(property "Value" "150KR2F-L-GP"
			(at 1.7907 -1.1176 0)
			(unlocked yes)
			(layer "F.Fab")
			(hide yes)
			(effects
				(font
					(size 1.016 1.016)
					(thickness 0.1524)
				)
			)
		)
		(property "Device Type" "R402H16"
			(at 1.7907 -2.6416 0)
			(unlocked yes)
			(layer "F.Fab")
			(hide yes)
			(effects
				(font
					(size 1.016 1.016)
					(thickness 0.1524)
				)
			)
		)
		(duplicate_pad_numbers_are_jumpers no)
		(fp_rect
			(start -0.381 0.8382)
			(end 0.381 -0.8382)
			(stroke
				(width 0)
				(type default)
			)
			(fill no)
			(layer "F.CrtYd")
		)
		(fp_rect
			(start -0.381 0.8382)
			(end 0.381 -0.8382)
			(stroke
				(width 0)
				(type default)
			)
			(fill no)
			(layer "F.Fab")
		)
		(pad "1" smd custom
			(at 0 -0.4318)
			(size 0.127 0.127)
			(layers "F.Cu" "F.Mask" "F.Paste")
			(net "CLK_GEN_INA_PG")
			(options
				(clearance outline)
				(anchor circle)
			)
			(primitives
				(gr_poly
					(pts
						(arc
							(start -0.2032 -0.2794)
							(mid -0.239121 -0.264521)
							(end -0.254 -0.2286)
						)
						(arc
							(start -0.254 0.2286)
							(mid -0.239121 0.264521)
							(end -0.2032 0.2794)
						)
						(arc
							(start 0.2032 0.2794)
							(mid 0.239121 0.264521)
							(end 0.254 0.2286)
						)
						(arc
							(start 0.254 -0.2286)
							(mid 0.239121 -0.264521)
							(end 0.2032 -0.2794)
						)
					)
					(width 0)
					(fill yes)
				)
			)
		)
		(pad "2" smd custom
			(at 0 0.4318)
			(size 0.127 0.127)
			(layers "F.Cu" "F.Mask" "F.Paste")
			(net "GND")
			(options
				(clearance outline)
				(anchor circle)
			)
			(primitives
				(gr_poly
					(pts
						(arc
							(start -0.2032 -0.2794)
							(mid -0.239121 -0.264521)
							(end -0.254 -0.2286)
						)
						(arc
							(start -0.254 0.2286)
							(mid -0.239121 0.264521)
							(end -0.2032 0.2794)
						)
						(arc
							(start 0.2032 0.2794)
							(mid 0.239121 0.264521)
							(end 0.254 0.2286)
						)
						(arc
							(start 0.254 -0.2286)
							(mid 0.239121 -0.264521)
							(end 0.2032 -0.2794)
						)
					)
					(width 0)
					(fill yes)
				)
			)
		)
	)
	(footprint ""
		(layer "F.Cu")
		(at 71.374 -30.734 -90)
		(property "Reference" "R342"
			(at 0 0 270)
			(layer "F.SilkS")
			(hide yes)
			(effects
				(font
					(size 1.27 1.27)
				)
			)
		)
		(property "Value" "1KR2F-3-GP"
			(at 0.064008 -3.993896 270)
			(unlocked yes)
			(layer "F.Fab")
			(hide yes)
			(effects
				(font
					(size 1.016 1.016)
					(thickness 0.1524)
				)
			)
		)
		(property "Device Type" "R402H16"
			(at 0.064008 -5.517896 270)
			(unlocked yes)
			(layer "F.Fab")
			(hide yes)
			(effects
				(font
					(size 1.016 1.016)
					(thickness 0.1524)
				)
			)
		)
		(duplicate_pad_numbers_are_jumpers no)
		(fp_rect
			(start -0.381 0.8382)
			(end 0.381 -0.8382)
			(stroke
				(width 0)
				(type default)
			)
			(fill no)
			(layer "F.CrtYd")
		)
		(fp_rect
			(start -0.381 0.8382)
			(end 0.381 -0.8382)
			(stroke
				(width 0)
				(type default)
			)
			(fill no)
			(layer "F.Fab")
		)
		(pad "1" smd custom
			(at 0 -0.4318 270)
			(size 0.127 0.127)
			(layers "F.Cu" "F.Mask" "F.Paste")
			(net "DDR3_DRAM_PWROK")
			(options
				(clearance outline)
				(anchor circle)
			)
			(primitives
				(gr_poly
					(pts
						(arc
							(start -0.2032 -0.2794)
							(mid -0.239121 -0.264521)
							(end -0.254 -0.2286)
						)
						(arc
							(start -0.254 0.2286)
							(mid -0.239121 0.264521)
							(end -0.2032 0.2794)
						)
						(arc
							(start 0.2032 0.2794)
							(mid 0.239121 0.264521)
							(end 0.254 0.2286)
						)
						(arc
							(start 0.254 -0.2286)
							(mid 0.239121 -0.264521)
							(end 0.2032 -0.2794)
						)
					)
					(width 0)
					(fill yes)
				)
			)
		)
		(pad "2" smd custom
			(at 0 0.4318 270)
			(size 0.127 0.127)
			(layers "F.Cu" "F.Mask" "F.Paste")
			(net "PWRGD_PVDDR_PG")
			(options
				(clearance outline)
				(anchor circle)
			)
			(primitives
				(gr_poly
					(pts
						(arc
							(start -0.2032 -0.2794)
							(mid -0.239121 -0.264521)
							(end -0.254 -0.2286)
						)
						(arc
							(start -0.254 0.2286)
							(mid -0.239121 0.264521)
							(end -0.2032 0.2794)
						)
						(arc
							(start 0.2032 0.2794)
							(mid 0.239121 0.264521)
							(end 0.254 0.2286)
						)
						(arc
							(start 0.254 -0.2286)
							(mid 0.239121 -0.264521)
							(end 0.2032 -0.2794)
						)
					)
					(width 0)
					(fill yes)
				)
			)
		)
	)
	(footprint ""
		(layer "F.Cu")
		(at 7.6708 -32.004 180)
		(property "Reference" "PR201"
			(at 0 0 180)
			(layer "F.SilkS")
			(hide yes)
			(effects
				(font
					(size 1.27 1.27)
				)
			)
		)
		(property "Value" "619KR2F-GP"
			(at 1.7907 -1.1176 180)
			(unlocked yes)
			(layer "F.Fab")
			(hide yes)
			(effects
				(font
					(size 1.016 1.016)
					(thickness 0.1524)
				)
			)
		)
		(property "Device Type" "R402H16"
			(at 1.7907 -2.6416 180)
			(unlocked yes)
			(layer "F.Fab")
			(hide yes)
			(effects
				(font
					(size 1.016 1.016)
					(thickness 0.1524)
				)
			)
		)
		(duplicate_pad_numbers_are_jumpers no)
		(fp_rect
			(start -0.381 0.8382)
			(end 0.381 -0.8382)
			(stroke
				(width 0)
				(type default)
			)
			(fill no)
			(layer "F.CrtYd")
		)
		(fp_rect
			(start -0.381 0.8382)
			(end 0.381 -0.8382)
			(stroke
				(width 0)
				(type default)
			)
			(fill no)
			(layer "F.Fab")
		)
		(pad "1" smd custom
			(at 0 -0.4318 180)
			(size 0.127 0.127)
			(layers "F.Cu" "F.Mask" "F.Paste")
			(net "AGND_P3V3_STBY")
			(options
				(clearance outline)
				(anchor circle)
			)
			(primitives
				(gr_poly
					(pts
						(arc
							(start -0.2032 -0.2794)
							(mid -0.239121 -0.264521)
							(end -0.254 -0.2286)
						)
						(arc
							(start -0.254 0.2286)
							(mid -0.239121 0.264521)
							(end -0.2032 0.2794)
						)
						(arc
							(start 0.2032 0.2794)
							(mid 0.239121 0.264521)
							(end 0.254 0.2286)
						)
						(arc
							(start 0.254 -0.2286)
							(mid 0.239121 -0.264521)
							(end 0.2032 -0.2794)
						)
					)
					(width 0)
					(fill yes)
				)
			)
		)
		(pad "2" smd custom
			(at 0 0.4318 180)
			(size 0.127 0.127)
			(layers "F.Cu" "F.Mask" "F.Paste")
			(net "P3V3_STBY_RF")
			(options
				(clearance outline)
				(anchor circle)
			)
			(primitives
				(gr_poly
					(pts
						(arc
							(start -0.2032 -0.2794)
							(mid -0.239121 -0.264521)
							(end -0.254 -0.2286)
						)
						(arc
							(start -0.254 0.2286)
							(mid -0.239121 0.264521)
							(end -0.2032 0.2794)
						)
						(arc
							(start 0.2032 0.2794)
							(mid 0.239121 0.264521)
							(end 0.254 0.2286)
						)
						(arc
							(start 0.254 -0.2286)
							(mid 0.239121 -0.264521)
							(end 0.2032 -0.2794)
						)
					)
					(width 0)
					(fill yes)
				)
			)
		)
	)
	(footprint ""
		(layer "F.Cu")
		(at 44.45 -40.132 90)
		(property "Reference" "U12"
			(at 0 0 90)
			(layer "F.SilkS")
			(hide yes)
			(effects
				(font
					(size 1.27 1.27)
				)
			)
		)
		(property "Value" "SN74LVC1G14DCKR-GP"
			(at 0 -8.0772 90)
			(unlocked yes)
			(layer "F.Fab")
			(hide yes)
			(effects
				(font
					(size 1.016 1.016)
					(thickness 0.1524)
				)
			)
		)
		(property "Device Type" "SC70-5H44"
			(at 0 -9.6012 90)
			(unlocked yes)
			(layer "F.Fab")
			(hide yes)
			(effects
				(font
					(size 1.016 1.016)
					(thickness 0.1524)
				)
			)
		)
		(duplicate_pad_numbers_are_jumpers no)
		(fp_line
			(start 1.0033 -0.3302)
			(end 1.0033 0.3302)
			(stroke
				(width 0.1524)
				(type default)
			)
			(layer "F.SilkS")
		)
		(fp_line
			(start -1.0033 -0.3302)
			(end 1.0033 -0.3302)
			(stroke
				(width 0.1524)
				(type default)
			)
			(layer "F.SilkS")
		)
		(fp_line
			(start 1.0033 0.3302)
			(end -1.0033 0.3302)
			(stroke
				(width 0.1524)
				(type default)
			)
			(layer "F.SilkS")
		)
		(fp_line
			(start -1.0033 0.3302)
			(end -1.0033 -0.3302)
			(stroke
				(width 0.1524)
				(type default)
			)
			(layer "F.SilkS")
		)
		(fp_poly
			(pts
				(xy -1.0033 1.4859) (xy -1.0033 0.8001) (xy -1.1811 0.8001) (xy -1.1811 -0.8001) (xy -1.0033 -0.8001)
				(xy -1.0033 -1.4859) (xy 1.0033 -1.4859) (xy 1.0033 -0.8001) (xy 1.1811 -0.8001) (xy 1.1811 0.8001)
				(xy 1.0033 0.8001) (xy 1.0033 1.4859) (xy 0.2921 1.4859) (xy 0.2921 0.8001) (xy -0.2921 0.8001)
				(xy -0.2921 1.4859)
			)
			(stroke
				(width 0)
				(type default)
			)
			(fill no)
			(layer "F.CrtYd")
		)
		(fp_poly
			(pts
				(xy -1.0033 1.4859) (xy -1.0033 0.8001) (xy -1.1811 0.8001) (xy -1.1811 -0.8001) (xy -1.0033 -0.8001)
				(xy -1.0033 -1.4859) (xy 1.0033 -1.4859) (xy 1.0033 -0.8001) (xy 1.1811 -0.8001) (xy 1.1811 0.8001)
				(xy 1.0033 0.8001) (xy 1.0033 1.4859) (xy 0.2921 1.4859) (xy 0.2921 0.8001) (xy -0.2921 0.8001)
				(xy -0.2921 1.4859)
			)
			(stroke
				(width 0)
				(type default)
			)
			(fill no)
			(layer "F.Fab")
		)
		(pad "1" smd rect
			(at 0.65024 -0.93472 90)
			(size 0.3556 0.762)
			(layers "F.Cu" "F.Mask" "F.Paste")
			(net "Net_406")
		)
		(pad "2" smd rect
			(at 0 -0.93472 90)
			(size 0.3556 0.762)
			(layers "F.Cu" "F.Mask" "F.Paste")
			(net "CLK_GEN_DELAY0_PG")
		)
		(pad "3" smd rect
			(at -0.65024 -0.93472 90)
			(size 0.3556 0.762)
			(layers "F.Cu" "F.Mask" "F.Paste")
			(net "GND")
		)
		(pad "4" smd rect
			(at -0.65024 0.93472 90)
			(size 0.3556 0.762)
			(layers "F.Cu" "F.Mask" "F.Paste")
			(net "CLK_GEN_DELAY1_PG")
		)
		(pad "5" smd rect
			(at 0.65024 0.93472 90)
			(size 0.3556 0.762)
			(layers "F.Cu" "F.Mask" "F.Paste")
			(net "P3V3")
		)
	)
	(footprint ""
		(layer "F.Cu")
		(at 161.7472 -12.828778 180)
		(property "Reference" "C343"
			(at 0 0 180)
			(layer "F.SilkS")
			(hide yes)
			(effects
				(font
					(size 1.27 1.27)
				)
			)
		)
		(property "Value" "SCD1U16V2KX-3GP"
			(at 1.8923 -1.2065 180)
			(unlocked yes)
			(layer "F.Fab")
			(hide yes)
			(effects
				(font
					(size 1.016 1.016)
					(thickness 0.1524)
				)
			)
		)
		(property "Device Type" "C402H22"
			(at 1.8923 -2.7305 180)
			(unlocked yes)
			(layer "F.Fab")
			(hide yes)
			(effects
				(font
					(size 1.016 1.016)
					(thickness 0.1524)
				)
			)
		)
		(duplicate_pad_numbers_are_jumpers no)
		(fp_rect
			(start -0.381 0.7366)
			(end 0.381 -0.7366)
			(stroke
				(width 0)
				(type default)
			)
			(fill no)
			(layer "F.CrtYd")
		)
		(fp_rect
			(start -0.381 0.7366)
			(end 0.381 -0.7366)
			(stroke
				(width 0)
				(type default)
			)
			(fill no)
			(layer "F.Fab")
		)
		(pad "1" smd custom
			(at 0 -0.4572 180)
			(size 0.1143 0.1143)
			(layers "F.Cu" "F.Mask" "F.Paste")
			(net "PV_VDDR")
			(options
				(clearance outline)
				(anchor circle)
			)
			(primitives
				(gr_poly
					(pts
						(arc
							(start -0.254 -0.1778)
							(mid -0.239121 -0.213721)
							(end -0.2032 -0.2286)
						)
						(arc
							(start 0.2032 -0.2286)
							(mid 0.239121 -0.213721)
							(end 0.254 -0.1778)
						)
						(arc
							(start 0.254 0.1778)
							(mid 0.239121 0.213721)
							(end 0.2032 0.2286)
						)
						(arc
							(start -0.2032 0.2286)
							(mid -0.239121 0.213721)
							(end -0.254 0.1778)
						)
					)
					(width 0)
					(fill yes)
				)
			)
		)
		(pad "2" smd custom
			(at 0 0.4572 180)
			(size 0.1143 0.1143)
			(layers "F.Cu" "F.Mask" "F.Paste")
			(net "GND")
			(options
				(clearance outline)
				(anchor circle)
			)
			(primitives
				(gr_poly
					(pts
						(arc
							(start -0.254 -0.1778)
							(mid -0.239121 -0.213721)
							(end -0.2032 -0.2286)
						)
						(arc
							(start 0.2032 -0.2286)
							(mid 0.239121 -0.213721)
							(end 0.254 -0.1778)
						)
						(arc
							(start 0.254 0.1778)
							(mid 0.239121 0.213721)
							(end 0.2032 0.2286)
						)
						(arc
							(start -0.2032 0.2286)
							(mid -0.239121 0.213721)
							(end -0.254 0.1778)
						)
					)
					(width 0)
					(fill yes)
				)
			)
		)
	)
	(footprint ""
		(layer "F.Cu")
		(at 56.007 -36.068 -90)
		(property "Reference" "R106"
			(at 0 0 270)
			(layer "F.SilkS")
			(hide yes)
			(effects
				(font
					(size 1.27 1.27)
				)
			)
		)
		(property "Value" "33R2F-3-GP"
			(at 0.064008 -3.993896 270)
			(unlocked yes)
			(layer "F.Fab")
			(hide yes)
			(effects
				(font
					(size 1.016 1.016)
					(thickness 0.1524)
				)
			)
		)
		(property "Device Type" "R402H16"
			(at 0.064008 -5.517896 270)
			(unlocked yes)
			(layer "F.Fab")
			(hide yes)
			(effects
				(font
					(size 1.016 1.016)
					(thickness 0.1524)
				)
			)
		)
		(duplicate_pad_numbers_are_jumpers no)
		(fp_rect
			(start -0.381 0.8382)
			(end 0.381 -0.8382)
			(stroke
				(width 0)
				(type default)
			)
			(fill no)
			(layer "F.CrtYd")
		)
		(fp_rect
			(start -0.381 0.8382)
			(end 0.381 -0.8382)
			(stroke
				(width 0)
				(type default)
			)
			(fill no)
			(layer "F.Fab")
		)
		(pad "1" smd custom
			(at 0 -0.4318 270)
			(size 0.127 0.127)
			(layers "F.Cu" "F.Mask" "F.Paste")
			(net "SPI_CPU_MISO")
			(options
				(clearance outline)
				(anchor circle)
			)
			(primitives
				(gr_poly
					(pts
						(arc
							(start -0.2032 -0.2794)
							(mid -0.239121 -0.264521)
							(end -0.254 -0.2286)
						)
						(arc
							(start -0.254 0.2286)
							(mid -0.239121 0.264521)
							(end -0.2032 0.2794)
						)
						(arc
							(start 0.2032 0.2794)
							(mid 0.239121 0.264521)
							(end 0.254 0.2286)
						)
						(arc
							(start 0.254 -0.2286)
							(mid 0.239121 -0.264521)
							(end 0.2032 -0.2794)
						)
					)
					(width 0)
					(fill yes)
				)
			)
		)
		(pad "2" smd custom
			(at 0 0.4318 270)
			(size 0.127 0.127)
			(layers "F.Cu" "F.Mask" "F.Paste")
			(net "SPI_MISO_R_1")
			(options
				(clearance outline)
				(anchor circle)
			)
			(primitives
				(gr_poly
					(pts
						(arc
							(start -0.2032 -0.2794)
							(mid -0.239121 -0.264521)
							(end -0.254 -0.2286)
						)
						(arc
							(start -0.254 0.2286)
							(mid -0.239121 0.264521)
							(end -0.2032 0.2794)
						)
						(arc
							(start 0.2032 0.2794)
							(mid 0.239121 0.264521)
							(end 0.254 0.2286)
						)
						(arc
							(start 0.254 -0.2286)
							(mid 0.239121 -0.264521)
							(end 0.2032 -0.2794)
						)
					)
					(width 0)
					(fill yes)
				)
			)
		)
	)
	(footprint ""
		(layer "F.Cu")
		(at 21.9456 -65.1764)
		(property "Reference" "PR28"
			(at 0 0 0)
			(layer "F.SilkS")
			(hide yes)
			(effects
				(font
					(size 1.27 1.27)
				)
			)
		)
		(property "Value" "1K3R2F-1-GP"
			(at 1.7907 -1.1176 0)
			(unlocked yes)
			(layer "F.Fab")
			(hide yes)
			(effects
				(font
					(size 1.016 1.016)
					(thickness 0.1524)
				)
			)
		)
		(property "Device Type" "R402H16"
			(at 1.7907 -2.6416 0)
			(unlocked yes)
			(layer "F.Fab")
			(hide yes)
			(effects
				(font
					(size 1.016 1.016)
					(thickness 0.1524)
				)
			)
		)
		(duplicate_pad_numbers_are_jumpers no)
		(fp_rect
			(start -0.381 0.8382)
			(end 0.381 -0.8382)
			(stroke
				(width 0)
				(type default)
			)
			(fill no)
			(layer "F.CrtYd")
		)
		(fp_rect
			(start -0.381 0.8382)
			(end 0.381 -0.8382)
			(stroke
				(width 0)
				(type default)
			)
			(fill no)
			(layer "F.Fab")
		)
		(pad "1" smd custom
			(at 0 -0.4318)
			(size 0.127 0.127)
			(layers "F.Cu" "F.Mask" "F.Paste")
			(net "VR_PVNN_ISUMN")
			(options
				(clearance outline)
				(anchor circle)
			)
			(primitives
				(gr_poly
					(pts
						(arc
							(start -0.2032 -0.2794)
							(mid -0.239121 -0.264521)
							(end -0.254 -0.2286)
						)
						(arc
							(start -0.254 0.2286)
							(mid -0.239121 0.264521)
							(end -0.2032 0.2794)
						)
						(arc
							(start 0.2032 0.2794)
							(mid 0.239121 0.264521)
							(end 0.254 0.2286)
						)
						(arc
							(start 0.254 -0.2286)
							(mid 0.239121 -0.264521)
							(end 0.2032 -0.2794)
						)
					)
					(width 0)
					(fill yes)
				)
			)
		)
		(pad "2" smd custom
			(at 0 0.4318)
			(size 0.127 0.127)
			(layers "F.Cu" "F.Mask" "F.Paste")
			(net "VR_PVNN_ISUMN_R")
			(options
				(clearance outline)
				(anchor circle)
			)
			(primitives
				(gr_poly
					(pts
						(arc
							(start -0.2032 -0.2794)
							(mid -0.239121 -0.264521)
							(end -0.254 -0.2286)
						)
						(arc
							(start -0.254 0.2286)
							(mid -0.239121 0.264521)
							(end -0.2032 0.2794)
						)
						(arc
							(start 0.2032 0.2794)
							(mid 0.239121 0.264521)
							(end 0.254 0.2286)
						)
						(arc
							(start 0.254 -0.2286)
							(mid 0.239121 -0.264521)
							(end 0.2032 -0.2794)
						)
					)
					(width 0)
					(fill yes)
				)
			)
		)
	)
	(footprint ""
		(layer "F.Cu")
		(at 154.94 -23.622 90)
		(property "Reference" "C73"
			(at 0 0 90)
			(layer "F.SilkS")
			(hide yes)
			(effects
				(font
					(size 1.27 1.27)
				)
			)
		)
		(property "Value" "SCD1U10V2KX-5GP"
			(at 1.1811 -2.7051 90)
			(unlocked yes)
			(layer "F.Fab")
			(hide yes)
			(effects
				(font
					(size 1.016 1.016)
					(thickness 0.1524)
				)
			)
		)
		(property "Device Type" "C402H22"
			(at 1.1811 -4.2291 90)
			(unlocked yes)
			(layer "F.Fab")
			(hide yes)
			(effects
				(font
					(size 1.016 1.016)
					(thickness 0.1524)
				)
			)
		)
		(duplicate_pad_numbers_are_jumpers no)
		(fp_rect
			(start -0.381 0.7366)
			(end 0.381 -0.7366)
			(stroke
				(width 0)
				(type default)
			)
			(fill no)
			(layer "F.CrtYd")
		)
		(fp_rect
			(start -0.381 0.7366)
			(end 0.381 -0.7366)
			(stroke
				(width 0)
				(type default)
			)
			(fill no)
			(layer "F.Fab")
		)
		(pad "1" smd custom
			(at 0 -0.4572 90)
			(size 0.1143 0.1143)
			(layers "F.Cu" "F.Mask" "F.Paste")
			(net "P1V2_FPGA_A")
			(options
				(clearance outline)
				(anchor circle)
			)
			(primitives
				(gr_poly
					(pts
						(arc
							(start -0.254 -0.1778)
							(mid -0.239121 -0.213721)
							(end -0.2032 -0.2286)
						)
						(arc
							(start 0.2032 -0.2286)
							(mid 0.239121 -0.213721)
							(end 0.254 -0.1778)
						)
						(arc
							(start 0.254 0.1778)
							(mid 0.239121 0.213721)
							(end 0.2032 0.2286)
						)
						(arc
							(start -0.2032 0.2286)
							(mid -0.239121 0.213721)
							(end -0.254 0.1778)
						)
					)
					(width 0)
					(fill yes)
				)
			)
		)
		(pad "2" smd custom
			(at 0 0.4572 90)
			(size 0.1143 0.1143)
			(layers "F.Cu" "F.Mask" "F.Paste")
			(net "GND")
			(options
				(clearance outline)
				(anchor circle)
			)
			(primitives
				(gr_poly
					(pts
						(arc
							(start -0.254 -0.1778)
							(mid -0.239121 -0.213721)
							(end -0.2032 -0.2286)
						)
						(arc
							(start 0.2032 -0.2286)
							(mid 0.239121 -0.213721)
							(end 0.254 -0.1778)
						)
						(arc
							(start 0.254 0.1778)
							(mid 0.239121 0.213721)
							(end 0.2032 0.2286)
						)
						(arc
							(start -0.2032 0.2286)
							(mid -0.239121 0.213721)
							(end -0.254 0.1778)
						)
					)
					(width 0)
					(fill yes)
				)
			)
		)
	)
	(footprint ""
		(layer "F.Cu")
		(at 161.798 -42.545 90)
		(property "Reference" "LED3"
			(at 0 0 90)
			(layer "F.SilkS")
			(hide yes)
			(effects
				(font
					(size 1.27 1.27)
				)
			)
		)
		(property "Value" "LED-YG-51-GP"
			(at -2.6924 -1.4224 90)
			(unlocked yes)
			(layer "F.Fab")
			(hide yes)
			(effects
				(font
					(size 1.016 1.016)
					(thickness 0.1524)
				)
			)
		)
		(property "Device Type" "LED1608AKH40"
			(at -2.6924 -2.9464 90)
			(unlocked yes)
			(layer "F.Fab")
			(hide yes)
			(effects
				(font
					(size 1.016 1.016)
					(thickness 0.1524)
				)
			)
		)
		(duplicate_pad_numbers_are_jumpers no)
		(fp_line
			(start -0.5334 1.3081)
			(end 0.5334 1.3081)
			(stroke
				(width 0.254)
				(type default)
			)
			(layer "F.SilkS")
		)
		(fp_rect
			(start -0.6604 1.1811)
			(end 0.6604 -1.1811)
			(stroke
				(width 0)
				(type default)
			)
			(fill no)
			(layer "F.CrtYd")
		)
		(fp_rect
			(start -0.6604 1.1811)
			(end 0.6604 -1.1811)
			(stroke
				(width 0)
				(type default)
			)
			(fill no)
			(layer "F.Fab")
		)
		(pad "A" smd rect
			(at 0 -0.652526 90)
			(size 1.0668 0.8128)
			(layers "F.Cu" "F.Mask" "F.Paste")
			(net "C_LED_NSTATUS#")
		)
		(pad "K" smd rect
			(at 0 0.652526 90)
			(size 1.0668 0.8128)
			(layers "F.Cu" "F.Mask" "F.Paste")
			(net "C_NSTATUS#")
		)
	)
	(footprint ""
		(layer "F.Cu")
		(at 4.699 -46.228)
		(property "Reference" "R8"
			(at 0 0 0)
			(layer "F.SilkS")
			(hide yes)
			(effects
				(font
					(size 1.27 1.27)
				)
			)
		)
		(property "Value" "0R2J-2-GP"
			(at 0.064008 -3.993896 0)
			(unlocked yes)
			(layer "F.Fab")
			(hide yes)
			(effects
				(font
					(size 1.016 1.016)
					(thickness 0.1524)
				)
			)
		)
		(property "Device Type" "R402H16"
			(at 0.064008 -5.517896 0)
			(unlocked yes)
			(layer "F.Fab")
			(hide yes)
			(effects
				(font
					(size 1.016 1.016)
					(thickness 0.1524)
				)
			)
		)
		(duplicate_pad_numbers_are_jumpers no)
		(fp_rect
			(start -0.381 0.8382)
			(end 0.381 -0.8382)
			(stroke
				(width 0)
				(type default)
			)
			(fill no)
			(layer "F.CrtYd")
		)
		(fp_rect
			(start -0.381 0.8382)
			(end 0.381 -0.8382)
			(stroke
				(width 0)
				(type default)
			)
			(fill no)
			(layer "F.Fab")
		)
		(pad "1" smd custom
			(at 0 -0.4318)
			(size 0.127 0.127)
			(layers "F.Cu" "F.Mask" "F.Paste")
			(net "SMB_HOST_LV_CLK")
			(options
				(clearance outline)
				(anchor circle)
			)
			(primitives
				(gr_poly
					(pts
						(arc
							(start -0.2032 -0.2794)
							(mid -0.239121 -0.264521)
							(end -0.254 -0.2286)
						)
						(arc
							(start -0.254 0.2286)
							(mid -0.239121 0.264521)
							(end -0.2032 0.2794)
						)
						(arc
							(start 0.2032 0.2794)
							(mid 0.239121 0.264521)
							(end 0.254 0.2286)
						)
						(arc
							(start 0.254 -0.2286)
							(mid 0.239121 -0.264521)
							(end 0.2032 -0.2794)
						)
					)
					(width 0)
					(fill yes)
				)
			)
		)
		(pad "2" smd custom
			(at 0 0.4318)
			(size 0.127 0.127)
			(layers "F.Cu" "F.Mask" "F.Paste")
			(net "TEMP_1_CLK")
			(options
				(clearance outline)
				(anchor circle)
			)
			(primitives
				(gr_poly
					(pts
						(arc
							(start -0.2032 -0.2794)
							(mid -0.239121 -0.264521)
							(end -0.254 -0.2286)
						)
						(arc
							(start -0.254 0.2286)
							(mid -0.239121 0.264521)
							(end -0.2032 0.2794)
						)
						(arc
							(start 0.2032 0.2794)
							(mid 0.239121 0.264521)
							(end 0.254 0.2286)
						)
						(arc
							(start 0.254 -0.2286)
							(mid 0.239121 -0.264521)
							(end 0.2032 -0.2794)
						)
					)
					(width 0)
					(fill yes)
				)
			)
		)
	)
	(footprint ""
		(layer "F.Cu")
		(at 161.036 -33.274)
		(property "Reference" "R163"
			(at 0 0 0)
			(layer "F.SilkS")
			(hide yes)
			(effects
				(font
					(size 1.27 1.27)
				)
			)
		)
		(property "Value" "1KR2F-3-GP"
			(at 0.064008 -3.993896 0)
			(unlocked yes)
			(layer "F.Fab")
			(hide yes)
			(effects
				(font
					(size 1.016 1.016)
					(thickness 0.1524)
				)
			)
		)
		(property "Device Type" "R402H16"
			(at 0.064008 -5.517896 0)
			(unlocked yes)
			(layer "F.Fab")
			(hide yes)
			(effects
				(font
					(size 1.016 1.016)
					(thickness 0.1524)
				)
			)
		)
		(duplicate_pad_numbers_are_jumpers no)
		(fp_rect
			(start -0.381 0.8382)
			(end 0.381 -0.8382)
			(stroke
				(width 0)
				(type default)
			)
			(fill no)
			(layer "F.CrtYd")
		)
		(fp_rect
			(start -0.381 0.8382)
			(end 0.381 -0.8382)
			(stroke
				(width 0)
				(type default)
			)
			(fill no)
			(layer "F.Fab")
		)
		(pad "1" smd custom
			(at 0 -0.4318)
			(size 0.127 0.127)
			(layers "F.Cu" "F.Mask" "F.Paste")
			(net "P3V3_STBY")
			(options
				(clearance outline)
				(anchor circle)
			)
			(primitives
				(gr_poly
					(pts
						(arc
							(start -0.2032 -0.2794)
							(mid -0.239121 -0.264521)
							(end -0.254 -0.2286)
						)
						(arc
							(start -0.254 0.2286)
							(mid -0.239121 0.264521)
							(end -0.2032 0.2794)
						)
						(arc
							(start 0.2032 0.2794)
							(mid 0.239121 0.264521)
							(end 0.254 0.2286)
						)
						(arc
							(start 0.254 -0.2286)
							(mid 0.239121 -0.264521)
							(end 0.2032 -0.2794)
						)
					)
					(width 0)
					(fill yes)
				)
			)
		)
		(pad "2" smd custom
			(at 0 0.4318)
			(size 0.127 0.127)
			(layers "F.Cu" "F.Mask" "F.Paste")
			(net "DISABLE_H")
			(options
				(clearance outline)
				(anchor circle)
			)
			(primitives
				(gr_poly
					(pts
						(arc
							(start -0.2032 -0.2794)
							(mid -0.239121 -0.264521)
							(end -0.254 -0.2286)
						)
						(arc
							(start -0.254 0.2286)
							(mid -0.239121 0.264521)
							(end -0.2032 0.2794)
						)
						(arc
							(start 0.2032 0.2794)
							(mid 0.239121 0.264521)
							(end 0.254 0.2286)
						)
						(arc
							(start 0.254 -0.2286)
							(mid 0.239121 -0.264521)
							(end 0.2032 -0.2794)
						)
					)
					(width 0)
					(fill yes)
				)
			)
		)
	)
	(footprint ""
		(layer "F.Cu")
		(at 189.103 -60.325)
		(property "Reference" "C2"
			(at 0 0 0)
			(layer "F.SilkS")
			(hide yes)
			(effects
				(font
					(size 1.27 1.27)
				)
			)
		)
		(property "Value" "SCD1U16V2KX-3GP"
			(at 1.1811 -2.7051 0)
			(unlocked yes)
			(layer "F.Fab")
			(hide yes)
			(effects
				(font
					(size 1.016 1.016)
					(thickness 0.1524)
				)
			)
		)
		(property "Device Type" "C402H22"
			(at 1.1811 -4.2291 0)
			(unlocked yes)
			(layer "F.Fab")
			(hide yes)
			(effects
				(font
					(size 1.016 1.016)
					(thickness 0.1524)
				)
			)
		)
		(duplicate_pad_numbers_are_jumpers no)
		(fp_rect
			(start -0.381 0.7366)
			(end 0.381 -0.7366)
			(stroke
				(width 0)
				(type default)
			)
			(fill no)
			(layer "F.CrtYd")
		)
		(fp_rect
			(start -0.381 0.7366)
			(end 0.381 -0.7366)
			(stroke
				(width 0)
				(type default)
			)
			(fill no)
			(layer "F.Fab")
		)
		(pad "1" smd custom
			(at 0 -0.4572)
			(size 0.1143 0.1143)
			(layers "F.Cu" "F.Mask" "F.Paste")
			(net "DDR3_M_A_VREF_DQ1")
			(options
				(clearance outline)
				(anchor circle)
			)
			(primitives
				(gr_poly
					(pts
						(arc
							(start -0.254 -0.1778)
							(mid -0.239121 -0.213721)
							(end -0.2032 -0.2286)
						)
						(arc
							(start 0.2032 -0.2286)
							(mid 0.239121 -0.213721)
							(end 0.254 -0.1778)
						)
						(arc
							(start 0.254 0.1778)
							(mid 0.239121 0.213721)
							(end 0.2032 0.2286)
						)
						(arc
							(start -0.2032 0.2286)
							(mid -0.239121 0.213721)
							(end -0.254 0.1778)
						)
					)
					(width 0)
					(fill yes)
				)
			)
		)
		(pad "2" smd custom
			(at 0 0.4572)
			(size 0.1143 0.1143)
			(layers "F.Cu" "F.Mask" "F.Paste")
			(net "GND")
			(options
				(clearance outline)
				(anchor circle)
			)
			(primitives
				(gr_poly
					(pts
						(arc
							(start -0.254 -0.1778)
							(mid -0.239121 -0.213721)
							(end -0.2032 -0.2286)
						)
						(arc
							(start 0.2032 -0.2286)
							(mid 0.239121 -0.213721)
							(end 0.254 -0.1778)
						)
						(arc
							(start 0.254 0.1778)
							(mid 0.239121 0.213721)
							(end 0.2032 0.2286)
						)
						(arc
							(start -0.2032 0.2286)
							(mid -0.239121 0.213721)
							(end -0.254 0.1778)
						)
					)
					(width 0)
					(fill yes)
				)
			)
		)
	)
	(footprint ""
		(layer "F.Cu")
		(at 58.039 -63.754 180)
		(property "Reference" "PC37"
			(at 0 0 180)
			(layer "F.SilkS")
			(hide yes)
			(effects
				(font
					(size 1.27 1.27)
				)
			)
		)
		(property "Value" "SC47U6D3V5MX-1-GP"
			(at -0.0762 -6.1214 180)
			(unlocked yes)
			(layer "F.Fab")
			(hide yes)
			(effects
				(font
					(size 1.016 1.016)
					(thickness 0.1524)
				)
			)
		)
		(property "Device Type" "C805H54"
			(at -0.0762 -8.1534 180)
			(unlocked yes)
			(layer "F.Fab")
			(hide yes)
			(effects
				(font
					(size 1.016 1.016)
					(thickness 0.1524)
				)
			)
		)
		(duplicate_pad_numbers_are_jumpers no)
		(fp_line
			(start 0.6096 0)
			(end -0.6096 0)
			(stroke
				(width 0.3048)
				(type default)
			)
			(layer "F.SilkS")
		)
		(fp_poly
			(pts
				(xy -0.9017 1.4351) (xy 0.9017 1.4351) (xy 0.9017 -1.4351) (xy -0.9017 -1.4351)
			)
			(stroke
				(width 0)
				(type default)
			)
			(fill no)
			(layer "F.CrtYd")
		)
		(fp_poly
			(pts
				(xy 0.9017 1.4351) (xy 0.9017 -1.4351) (xy -0.9017 -1.4351) (xy -0.9017 1.4351)
			)
			(stroke
				(width 0)
				(type default)
			)
			(fill no)
			(layer "F.Fab")
		)
		(pad "1" smd rect
			(at 0 -0.8382 180)
			(size 1.5494 0.9398)
			(layers "F.Cu" "F.Mask" "F.Paste")
			(net "PVCCP")
		)
		(pad "2" smd rect
			(at 0 0.8382 180)
			(size 1.5494 0.9398)
			(layers "F.Cu" "F.Mask" "F.Paste")
			(net "GND")
		)
	)
	(footprint ""
		(layer "F.Cu")
		(at 198.755 -9.272778)
		(property "Reference" "R392"
			(at 0 0 0)
			(layer "F.SilkS")
			(hide yes)
			(effects
				(font
					(size 1.27 1.27)
				)
			)
		)
		(property "Value" "0R2J-2-GP"
			(at 0.064008 -3.993896 0)
			(unlocked yes)
			(layer "F.Fab")
			(hide yes)
			(effects
				(font
					(size 1.016 1.016)
					(thickness 0.1524)
				)
			)
		)
		(property "Device Type" "R402H16"
			(at 0.064008 -5.517896 0)
			(unlocked yes)
			(layer "F.Fab")
			(hide yes)
			(effects
				(font
					(size 1.016 1.016)
					(thickness 0.1524)
				)
			)
		)
		(duplicate_pad_numbers_are_jumpers no)
		(fp_rect
			(start -0.381 0.8382)
			(end 0.381 -0.8382)
			(stroke
				(width 0)
				(type default)
			)
			(fill no)
			(layer "F.CrtYd")
		)
		(fp_rect
			(start -0.381 0.8382)
			(end 0.381 -0.8382)
			(stroke
				(width 0)
				(type default)
			)
			(fill no)
			(layer "F.Fab")
		)
		(pad "1" smd custom
			(at 0 -0.4318)
			(size 0.127 0.127)
			(layers "F.Cu" "F.Mask" "F.Paste")
			(net "SMB_M_B1_R_CLK")
			(options
				(clearance outline)
				(anchor circle)
			)
			(primitives
				(gr_poly
					(pts
						(arc
							(start -0.2032 -0.2794)
							(mid -0.239121 -0.264521)
							(end -0.254 -0.2286)
						)
						(arc
							(start -0.254 0.2286)
							(mid -0.239121 0.264521)
							(end -0.2032 0.2794)
						)
						(arc
							(start 0.2032 0.2794)
							(mid 0.239121 0.264521)
							(end 0.254 0.2286)
						)
						(arc
							(start 0.254 -0.2286)
							(mid 0.239121 -0.264521)
							(end 0.2032 -0.2794)
						)
					)
					(width 0)
					(fill yes)
				)
			)
		)
		(pad "2" smd custom
			(at 0 0.4318)
			(size 0.127 0.127)
			(layers "F.Cu" "F.Mask" "F.Paste")
			(net "SMB_HOST_LV_CLK")
			(options
				(clearance outline)
				(anchor circle)
			)
			(primitives
				(gr_poly
					(pts
						(arc
							(start -0.2032 -0.2794)
							(mid -0.239121 -0.264521)
							(end -0.254 -0.2286)
						)
						(arc
							(start -0.254 0.2286)
							(mid -0.239121 0.264521)
							(end -0.2032 0.2794)
						)
						(arc
							(start 0.2032 0.2794)
							(mid 0.239121 0.264521)
							(end 0.254 0.2286)
						)
						(arc
							(start 0.254 -0.2286)
							(mid 0.239121 -0.264521)
							(end 0.2032 -0.2794)
						)
					)
					(width 0)
					(fill yes)
				)
			)
		)
	)
	(footprint ""
		(layer "F.Cu")
		(at 201.3966 -45.72 90)
		(property "Reference" "PG2"
			(at 0 0 90)
			(layer "F.SilkS")
			(hide yes)
			(effects
				(font
					(size 1.27 1.27)
				)
			)
		)
		(property "Value" "GAP-CLOSE-PWR-4-GP"
			(at -2.4638 -0.5461 90)
			(unlocked yes)
			(layer "F.Fab")
			(hide yes)
			(effects
				(font
					(size 1.016 1.016)
					(thickness 0.1524)
				)
			)
		)
		(property "Device Type" "GAP-CLOSE-PWR-4"
			(at -2.4638 -2.0701 90)
			(unlocked yes)
			(layer "F.Fab")
			(hide yes)
			(effects
				(font
					(size 1.016 1.016)
					(thickness 0.1524)
				)
			)
		)
		(duplicate_pad_numbers_are_jumpers no)
		(fp_rect
			(start -0.2794 0.254)
			(end 0.2794 -0.254)
			(stroke
				(width 0)
				(type default)
			)
			(fill no)
			(layer "F.CrtYd")
		)
		(fp_rect
			(start -0.2794 0.254)
			(end 0.2794 -0.254)
			(stroke
				(width 0)
				(type default)
			)
			(fill no)
			(layer "F.Fab")
		)
		(pad "1" smd rect
			(at -0.0635 0 90)
			(size 0.1778 0.254)
			(layers "F.Cu" "F.Mask" "F.Paste")
			(net "VR_PVDDR_A_VSW")
		)
		(pad "2" smd rect
			(at 0.0635 0 90)
			(size 0.1778 0.254)
			(layers "F.Cu" "F.Mask" "F.Paste")
			(net "VR_PVDDRA_R_IS")
		)
	)
	(footprint ""
		(layer "F.Cu")
		(at 132.842 -58.674 90)
		(property "Reference" "PC140"
			(at 0 0 90)
			(layer "F.SilkS")
			(hide yes)
			(effects
				(font
					(size 1.27 1.27)
				)
			)
		)
		(property "Value" "SC10U6D3V3MX-GP"
			(at 0 -2.8194 90)
			(unlocked yes)
			(layer "F.Fab")
			(hide yes)
			(effects
				(font
					(size 1.016 1.016)
					(thickness 0.1524)
				)
			)
		)
		(property "Device Type" "C603H38"
			(at 0 -4.3434 90)
			(unlocked yes)
			(layer "F.Fab")
			(hide yes)
			(effects
				(font
					(size 1.016 1.016)
					(thickness 0.1524)
				)
			)
		)
		(duplicate_pad_numbers_are_jumpers no)
		(fp_line
			(start -0.4064 0)
			(end 0.4064 0)
			(stroke
				(width 0.2286)
				(type default)
			)
			(layer "F.SilkS")
		)
		(fp_rect
			(start -0.635 1.1811)
			(end 0.635 -1.1811)
			(stroke
				(width 0)
				(type default)
			)
			(fill no)
			(layer "F.CrtYd")
		)
		(fp_rect
			(start -0.635 1.1811)
			(end 0.635 -1.1811)
			(stroke
				(width 0)
				(type default)
			)
			(fill no)
			(layer "F.Fab")
		)
		(pad "1" smd custom
			(at 0 -0.6604 90)
			(size 0.19685 0.19685)
			(layers "F.Cu" "F.Mask" "F.Paste")
			(net "GND")
			(options
				(clearance outline)
				(anchor circle)
			)
			(primitives
				(gr_poly
					(pts
						(arc
							(start 0.508 -0.2921)
							(mid 0.478242 -0.363942)
							(end 0.4064 -0.3937)
						)
						(arc
							(start -0.4064 -0.3937)
							(mid -0.478242 -0.363942)
							(end -0.508 -0.2921)
						)
						(arc
							(start -0.508 0.2921)
							(mid -0.478242 0.363942)
							(end -0.4064 0.3937)
						)
						(arc
							(start 0.4064 0.3937)
							(mid 0.478242 0.363942)
							(end 0.508 0.2921)
						)
					)
					(width 0)
					(fill yes)
				)
			)
		)
		(pad "2" smd custom
			(at 0 0.6604 90)
			(size 0.19685 0.19685)
			(layers "F.Cu" "F.Mask" "F.Paste")
			(net "PV_VDDR")
			(options
				(clearance outline)
				(anchor circle)
			)
			(primitives
				(gr_poly
					(pts
						(arc
							(start 0.508 -0.2921)
							(mid 0.478242 -0.363942)
							(end 0.4064 -0.3937)
						)
						(arc
							(start -0.4064 -0.3937)
							(mid -0.478242 -0.363942)
							(end -0.508 -0.2921)
						)
						(arc
							(start -0.508 0.2921)
							(mid -0.478242 0.363942)
							(end -0.4064 0.3937)
						)
						(arc
							(start 0.4064 0.3937)
							(mid 0.478242 0.363942)
							(end 0.508 0.2921)
						)
					)
					(width 0)
					(fill yes)
				)
			)
		)
	)
	(footprint ""
		(layer "F.Cu")
		(at 18.669 -39.243 90)
		(property "Reference" "PL6"
			(at 0 0 90)
			(layer "F.SilkS")
			(hide yes)
			(effects
				(font
					(size 1.27 1.27)
				)
			)
		)
		(property "Value" "IND-2D2UH-122-GP"
			(at -4.8895 -4.2672 90)
			(unlocked yes)
			(layer "F.Fab")
			(hide yes)
			(effects
				(font
					(size 1.016 1.016)
					(thickness 0.1524)
				)
			)
		)
		(property "Device Type" "L686647H119"
			(at -4.8895 -5.7912 90)
			(unlocked yes)
			(layer "F.Fab")
			(hide yes)
			(effects
				(font
					(size 1.016 1.016)
					(thickness 0.1524)
				)
			)
		)
		(duplicate_pad_numbers_are_jumpers no)
		(fp_rect
			(start -3.4925 3.937)
			(end 3.4925 -3.937)
			(stroke
				(width 0)
				(type default)
			)
			(fill no)
			(layer "F.CrtYd")
		)
		(fp_rect
			(start -3.4925 3.937)
			(end 3.4925 -3.937)
			(stroke
				(width 0)
				(type default)
			)
			(fill no)
			(layer "F.Fab")
		)
		(pad "1" smd rect
			(at 0 -2.858516 90)
			(size 3.429 1.905)
			(layers "F.Cu" "F.Mask" "F.Paste")
			(net "P3V3_STBY_LL")
		)
		(pad "2" smd rect
			(at 0 2.858516 90)
			(size 3.429 1.905)
			(layers "F.Cu" "F.Mask" "F.Paste")
			(net "P3V3_STBY_OUT")
		)
	)
	(footprint ""
		(layer "F.Cu")
		(at 77.2922 -35.9156 180)
		(property "Reference" "TP7"
			(at 0 0 180)
			(layer "F.SilkS")
			(hide yes)
			(effects
				(font
					(size 1.27 1.27)
				)
			)
		)
		(property "Value" "TPAD28-1-GP-U"
			(at 0.0508 -1.9304 180)
			(unlocked yes)
			(layer "F.Fab")
			(hide yes)
			(effects
				(font
					(size 1.016 1.016)
					(thickness 0.1524)
				)
			)
		)
		(property "Device Type" "TPAD28-1-U"
			(at 0.0508 -3.4544 180)
			(unlocked yes)
			(layer "F.Fab")
			(hide yes)
			(effects
				(font
					(size 1.016 1.016)
					(thickness 0.1524)
				)
			)
		)
		(duplicate_pad_numbers_are_jumpers no)
		(fp_poly
			(pts
				(arc
					(start -0.3556 0)
					(mid 0.3556 0)
					(end -0.3556 0)
				)
			)
			(stroke
				(width 0)
				(type default)
			)
			(fill no)
			(layer "F.CrtYd")
		)
		(fp_poly
			(pts
				(arc
					(start -0.9525 0)
					(mid 0.9525 0)
					(end -0.9525 0)
				)
			)
			(stroke
				(width 0)
				(type default)
			)
			(fill no)
			(layer "F.Fab")
		)
		(pad "1" smd circle
			(at 0 0 180)
			(size 0.7112 0.7112)
			(layers "F.Cu" "F.Mask" "F.Paste")
			(net "SUS_STAT#")
		)
	)
	(footprint ""
		(layer "F.Cu")
		(at 107.823 -66.167 -90)
		(property "Reference" "C7"
			(at 0 0 270)
			(layer "F.SilkS")
			(hide yes)
			(effects
				(font
					(size 1.27 1.27)
				)
			)
		)
		(property "Value" "SCD1U10V2KX-5GP"
			(at 1.1811 -2.7051 270)
			(unlocked yes)
			(layer "F.Fab")
			(hide yes)
			(effects
				(font
					(size 1.016 1.016)
					(thickness 0.1524)
				)
			)
		)
		(property "Device Type" "C402H22"
			(at 1.1811 -4.2291 270)
			(unlocked yes)
			(layer "F.Fab")
			(hide yes)
			(effects
				(font
					(size 1.016 1.016)
					(thickness 0.1524)
				)
			)
		)
		(duplicate_pad_numbers_are_jumpers no)
		(fp_rect
			(start -0.381 0.7366)
			(end 0.381 -0.7366)
			(stroke
				(width 0)
				(type default)
			)
			(fill no)
			(layer "F.CrtYd")
		)
		(fp_rect
			(start -0.381 0.7366)
			(end 0.381 -0.7366)
			(stroke
				(width 0)
				(type default)
			)
			(fill no)
			(layer "F.Fab")
		)
		(pad "1" smd custom
			(at 0 -0.4572 270)
			(size 0.1143 0.1143)
			(layers "F.Cu" "F.Mask" "F.Paste")
			(net "M_DRAM_PWROK")
			(options
				(clearance outline)
				(anchor circle)
			)
			(primitives
				(gr_poly
					(pts
						(arc
							(start -0.254 -0.1778)
							(mid -0.239121 -0.213721)
							(end -0.2032 -0.2286)
						)
						(arc
							(start 0.2032 -0.2286)
							(mid 0.239121 -0.213721)
							(end 0.254 -0.1778)
						)
						(arc
							(start 0.254 0.1778)
							(mid 0.239121 0.213721)
							(end 0.2032 0.2286)
						)
						(arc
							(start -0.2032 0.2286)
							(mid -0.239121 0.213721)
							(end -0.254 0.1778)
						)
					)
					(width 0)
					(fill yes)
				)
			)
		)
		(pad "2" smd custom
			(at 0 0.4572 270)
			(size 0.1143 0.1143)
			(layers "F.Cu" "F.Mask" "F.Paste")
			(net "GND")
			(options
				(clearance outline)
				(anchor circle)
			)
			(primitives
				(gr_poly
					(pts
						(arc
							(start -0.254 -0.1778)
							(mid -0.239121 -0.213721)
							(end -0.2032 -0.2286)
						)
						(arc
							(start 0.2032 -0.2286)
							(mid 0.239121 -0.213721)
							(end 0.254 -0.1778)
						)
						(arc
							(start 0.254 0.1778)
							(mid 0.239121 0.213721)
							(end 0.2032 0.2286)
						)
						(arc
							(start -0.2032 0.2286)
							(mid -0.239121 0.213721)
							(end -0.254 0.1778)
						)
					)
					(width 0)
					(fill yes)
				)
			)
		)
	)
	(footprint ""
		(layer "F.Cu")
		(at 66.802 -45.72 -90)
		(property "Reference" "U9"
			(at 0 0 270)
			(layer "F.SilkS")
			(hide yes)
			(effects
				(font
					(size 1.27 1.27)
				)
			)
		)
		(property "Value" "2N7002DW-7F-GP"
			(at -2.3622 -8.2042 270)
			(unlocked yes)
			(layer "F.Fab")
			(hide yes)
			(effects
				(font
					(size 1.016 1.016)
					(thickness 0.1524)
				)
			)
		)
		(property "Device Type" "SOT-363H44"
			(at -2.3622 -10.1092 270)
			(unlocked yes)
			(layer "F.Fab")
			(hide yes)
			(effects
				(font
					(size 1.016 1.016)
					(thickness 0.1524)
				)
			)
		)
		(duplicate_pad_numbers_are_jumpers no)
		(fp_poly
			(pts
				(xy -0.6731 1.4351) (xy -0.9779 1.7399) (xy -0.381 1.7399) (xy -0.3683 1.7399) (xy -0.381 1.7272)
			)
			(stroke
				(width 0)
				(type default)
			)
			(fill yes)
			(layer "F.SilkS")
		)
		(fp_poly
			(pts
				(xy 1.2573 0.8763) (xy 1.2573 -0.8763) (xy 0.9525 -0.8763) (xy 0.9525 -1.4351) (xy -0.9525 -1.4351)
				(xy -0.9525 -0.8763) (xy -1.2573 -0.8763) (xy -1.2573 0.8763) (xy -0.9525 0.8763) (xy -0.9525 1.4351)
				(xy 0.9525 1.4351) (xy 0.9525 0.8763)
			)
			(stroke
				(width 0)
				(type default)
			)
			(fill no)
			(layer "F.CrtYd")
		)
		(fp_poly
			(pts
				(xy 1.2573 0.8763) (xy 1.2573 -0.8763) (xy 0.9525 -0.8763) (xy 0.9525 -1.4351) (xy -0.9525 -1.4351)
				(xy -0.9525 -0.8763) (xy -1.2573 -0.8763) (xy -1.2573 0.8763) (xy -0.9525 0.8763) (xy -0.9525 1.4351)
				(xy 0.9525 1.4351) (xy 0.9525 0.8763)
			)
			(stroke
				(width 0)
				(type default)
			)
			(fill no)
			(layer "F.Fab")
		)
		(pad "1" smd rect
			(at -0.65024 0.8255 270)
			(size 0.3556 0.9652)
			(layers "F.Cu" "F.Mask" "F.Paste")
			(net "SMBUS_PECI_R_DATA")
		)
		(pad "2" smd rect
			(at 0 0.8255 270)
			(size 0.3556 0.9652)
			(layers "F.Cu" "F.Mask" "F.Paste")
			(net "SMBUS_PECI_SW_EN")
		)
		(pad "3" smd rect
			(at 0.65024 0.8255 270)
			(size 0.3556 0.9652)
			(layers "F.Cu" "F.Mask" "F.Paste")
			(net "SMB_PECI_LV_R_CLK")
		)
		(pad "4" smd rect
			(at 0.65024 -0.8255 270)
			(size 0.3556 0.9652)
			(layers "F.Cu" "F.Mask" "F.Paste")
			(net "SMBUS_PECI_R_CLK")
		)
		(pad "5" smd rect
			(at 0 -0.8255 270)
			(size 0.3556 0.9652)
			(layers "F.Cu" "F.Mask" "F.Paste")
			(net "SMBUS_PECI_SW_EN")
		)
		(pad "6" smd rect
			(at -0.65024 -0.8255 270)
			(size 0.3556 0.9652)
			(layers "F.Cu" "F.Mask" "F.Paste")
			(net "SMB_PECI_LV_R_DATA")
		)
	)
	(footprint ""
		(layer "F.Cu")
		(at 55.626 -46.609 -90)
		(property "Reference" "R41"
			(at 0 0 270)
			(layer "F.SilkS")
			(hide yes)
			(effects
				(font
					(size 1.27 1.27)
				)
			)
		)
		(property "Value" "4K7R2F-GP"
			(at 1.7907 -1.1176 270)
			(unlocked yes)
			(layer "F.Fab")
			(hide yes)
			(effects
				(font
					(size 1.016 1.016)
					(thickness 0.1524)
				)
			)
		)
		(property "Device Type" "R402H16"
			(at 1.7907 -2.6416 270)
			(unlocked yes)
			(layer "F.Fab")
			(hide yes)
			(effects
				(font
					(size 1.016 1.016)
					(thickness 0.1524)
				)
			)
		)
		(duplicate_pad_numbers_are_jumpers no)
		(fp_rect
			(start -0.381 0.8382)
			(end 0.381 -0.8382)
			(stroke
				(width 0)
				(type default)
			)
			(fill no)
			(layer "F.CrtYd")
		)
		(fp_rect
			(start -0.381 0.8382)
			(end 0.381 -0.8382)
			(stroke
				(width 0)
				(type default)
			)
			(fill no)
			(layer "F.Fab")
		)
		(pad "1" smd custom
			(at 0 -0.4318 270)
			(size 0.127 0.127)
			(layers "F.Cu" "F.Mask" "F.Paste")
			(net "P12V")
			(options
				(clearance outline)
				(anchor circle)
			)
			(primitives
				(gr_poly
					(pts
						(arc
							(start -0.2032 -0.2794)
							(mid -0.239121 -0.264521)
							(end -0.254 -0.2286)
						)
						(arc
							(start -0.254 0.2286)
							(mid -0.239121 0.264521)
							(end -0.2032 0.2794)
						)
						(arc
							(start 0.2032 0.2794)
							(mid 0.239121 0.264521)
							(end 0.254 0.2286)
						)
						(arc
							(start 0.254 -0.2286)
							(mid 0.239121 -0.264521)
							(end 0.2032 -0.2794)
						)
					)
					(width 0)
					(fill yes)
				)
			)
		)
		(pad "2" smd custom
			(at 0 0.4318 270)
			(size 0.127 0.127)
			(layers "F.Cu" "F.Mask" "F.Paste")
			(net "SW_P3V3_CPU_LV_G5")
			(options
				(clearance outline)
				(anchor circle)
			)
			(primitives
				(gr_poly
					(pts
						(arc
							(start -0.2032 -0.2794)
							(mid -0.239121 -0.264521)
							(end -0.254 -0.2286)
						)
						(arc
							(start -0.254 0.2286)
							(mid -0.239121 0.264521)
							(end -0.2032 0.2794)
						)
						(arc
							(start 0.2032 0.2794)
							(mid 0.239121 0.264521)
							(end 0.254 0.2286)
						)
						(arc
							(start 0.254 -0.2286)
							(mid 0.239121 -0.264521)
							(end 0.2032 -0.2794)
						)
					)
					(width 0)
					(fill yes)
				)
			)
		)
	)
	(footprint ""
		(layer "F.Cu")
		(at 130.175 -56.388 180)
		(property "Reference" "PC52"
			(at 0 0 180)
			(layer "F.SilkS")
			(hide yes)
			(effects
				(font
					(size 1.27 1.27)
				)
			)
		)
		(property "Value" "SC10U6D3V3MX-GP"
			(at 0 -2.8194 180)
			(unlocked yes)
			(layer "F.Fab")
			(hide yes)
			(effects
				(font
					(size 1.016 1.016)
					(thickness 0.1524)
				)
			)
		)
		(property "Device Type" "C603H38"
			(at 0 -4.3434 180)
			(unlocked yes)
			(layer "F.Fab")
			(hide yes)
			(effects
				(font
					(size 1.016 1.016)
					(thickness 0.1524)
				)
			)
		)
		(duplicate_pad_numbers_are_jumpers no)
		(fp_line
			(start -0.4064 0)
			(end 0.4064 0)
			(stroke
				(width 0.2286)
				(type default)
			)
			(layer "F.SilkS")
		)
		(fp_rect
			(start -0.635 1.1811)
			(end 0.635 -1.1811)
			(stroke
				(width 0)
				(type default)
			)
			(fill no)
			(layer "F.CrtYd")
		)
		(fp_rect
			(start -0.635 1.1811)
			(end 0.635 -1.1811)
			(stroke
				(width 0)
				(type default)
			)
			(fill no)
			(layer "F.Fab")
		)
		(pad "1" smd custom
			(at 0 -0.6604 180)
			(size 0.19685 0.19685)
			(layers "F.Cu" "F.Mask" "F.Paste")
			(net "GND")
			(options
				(clearance outline)
				(anchor circle)
			)
			(primitives
				(gr_poly
					(pts
						(arc
							(start 0.508 -0.2921)
							(mid 0.478242 -0.363942)
							(end 0.4064 -0.3937)
						)
						(arc
							(start -0.4064 -0.3937)
							(mid -0.478242 -0.363942)
							(end -0.508 -0.2921)
						)
						(arc
							(start -0.508 0.2921)
							(mid -0.478242 0.363942)
							(end -0.4064 0.3937)
						)
						(arc
							(start 0.4064 0.3937)
							(mid 0.478242 0.363942)
							(end 0.508 0.2921)
						)
					)
					(width 0)
					(fill yes)
				)
			)
		)
		(pad "2" smd custom
			(at 0 0.6604 180)
			(size 0.19685 0.19685)
			(layers "F.Cu" "F.Mask" "F.Paste")
			(net "PV_VTT_DDR_A")
			(options
				(clearance outline)
				(anchor circle)
			)
			(primitives
				(gr_poly
					(pts
						(arc
							(start 0.508 -0.2921)
							(mid 0.478242 -0.363942)
							(end 0.4064 -0.3937)
						)
						(arc
							(start -0.4064 -0.3937)
							(mid -0.478242 -0.363942)
							(end -0.508 -0.2921)
						)
						(arc
							(start -0.508 0.2921)
							(mid -0.478242 0.363942)
							(end -0.4064 0.3937)
						)
						(arc
							(start 0.4064 0.3937)
							(mid 0.478242 0.363942)
							(end 0.508 0.2921)
						)
					)
					(width 0)
					(fill yes)
				)
			)
		)
	)
	(footprint ""
		(layer "F.Cu")
		(at 24.7142 -52.6034 90)
		(property "Reference" "PR69"
			(at 0 0 90)
			(layer "F.SilkS")
			(hide yes)
			(effects
				(font
					(size 1.27 1.27)
				)
			)
		)
		(property "Value" "140R2F-GP"
			(at 1.7907 -1.1176 90)
			(unlocked yes)
			(layer "F.Fab")
			(hide yes)
			(effects
				(font
					(size 1.016 1.016)
					(thickness 0.1524)
				)
			)
		)
		(property "Device Type" "R402H16"
			(at 1.7907 -2.6416 90)
			(unlocked yes)
			(layer "F.Fab")
			(hide yes)
			(effects
				(font
					(size 1.016 1.016)
					(thickness 0.1524)
				)
			)
		)
		(duplicate_pad_numbers_are_jumpers no)
		(fp_rect
			(start -0.381 0.8382)
			(end 0.381 -0.8382)
			(stroke
				(width 0)
				(type default)
			)
			(fill no)
			(layer "F.CrtYd")
		)
		(fp_rect
			(start -0.381 0.8382)
			(end 0.381 -0.8382)
			(stroke
				(width 0)
				(type default)
			)
			(fill no)
			(layer "F.Fab")
		)
		(pad "1" smd custom
			(at 0 -0.4318 90)
			(size 0.127 0.127)
			(layers "F.Cu" "F.Mask" "F.Paste")
			(net "VR_PVCCP_ISUMN_R")
			(options
				(clearance outline)
				(anchor circle)
			)
			(primitives
				(gr_poly
					(pts
						(arc
							(start -0.2032 -0.2794)
							(mid -0.239121 -0.264521)
							(end -0.254 -0.2286)
						)
						(arc
							(start -0.254 0.2286)
							(mid -0.239121 0.264521)
							(end -0.2032 0.2794)
						)
						(arc
							(start 0.2032 0.2794)
							(mid 0.239121 0.264521)
							(end 0.254 0.2286)
						)
						(arc
							(start 0.254 -0.2286)
							(mid 0.239121 -0.264521)
							(end 0.2032 -0.2794)
						)
					)
					(width 0)
					(fill yes)
				)
			)
		)
		(pad "2" smd custom
			(at 0 0.4318 90)
			(size 0.127 0.127)
			(layers "F.Cu" "F.Mask" "F.Paste")
			(net "VR_PVCCP_ISUMN_RC")
			(options
				(clearance outline)
				(anchor circle)
			)
			(primitives
				(gr_poly
					(pts
						(arc
							(start -0.2032 -0.2794)
							(mid -0.239121 -0.264521)
							(end -0.254 -0.2286)
						)
						(arc
							(start -0.254 0.2286)
							(mid -0.239121 0.264521)
							(end -0.2032 0.2794)
						)
						(arc
							(start 0.2032 0.2794)
							(mid 0.239121 0.264521)
							(end 0.254 0.2286)
						)
						(arc
							(start 0.254 -0.2286)
							(mid 0.239121 -0.264521)
							(end 0.2032 -0.2794)
						)
					)
					(width 0)
					(fill yes)
				)
			)
		)
	)
	(footprint ""
		(layer "F.Cu")
		(at 55.372 -23.495 -90)
		(property "Reference" "R145"
			(at 0 0 270)
			(layer "F.SilkS")
			(hide yes)
			(effects
				(font
					(size 1.27 1.27)
				)
			)
		)
		(property "Value" "4K7R2F-GP"
			(at 0.064008 -3.993896 270)
			(unlocked yes)
			(layer "F.Fab")
			(hide yes)
			(effects
				(font
					(size 1.016 1.016)
					(thickness 0.1524)
				)
			)
		)
		(property "Device Type" "R402H16"
			(at 0.064008 -5.517896 270)
			(unlocked yes)
			(layer "F.Fab")
			(hide yes)
			(effects
				(font
					(size 1.016 1.016)
					(thickness 0.1524)
				)
			)
		)
		(duplicate_pad_numbers_are_jumpers no)
		(fp_rect
			(start -0.381 0.8382)
			(end 0.381 -0.8382)
			(stroke
				(width 0)
				(type default)
			)
			(fill no)
			(layer "F.CrtYd")
		)
		(fp_rect
			(start -0.381 0.8382)
			(end 0.381 -0.8382)
			(stroke
				(width 0)
				(type default)
			)
			(fill no)
			(layer "F.Fab")
		)
		(pad "1" smd custom
			(at 0 -0.4318 270)
			(size 0.127 0.127)
			(layers "F.Cu" "F.Mask" "F.Paste")
			(net "P3V3_CPU")
			(options
				(clearance outline)
				(anchor circle)
			)
			(primitives
				(gr_poly
					(pts
						(arc
							(start -0.2032 -0.2794)
							(mid -0.239121 -0.264521)
							(end -0.254 -0.2286)
						)
						(arc
							(start -0.254 0.2286)
							(mid -0.239121 0.264521)
							(end -0.2032 0.2794)
						)
						(arc
							(start 0.2032 0.2794)
							(mid 0.239121 0.264521)
							(end 0.254 0.2286)
						)
						(arc
							(start 0.254 -0.2286)
							(mid 0.239121 -0.264521)
							(end 0.2032 -0.2794)
						)
					)
					(width 0)
					(fill yes)
				)
			)
		)
		(pad "2" smd custom
			(at 0 0.4318 270)
			(size 0.127 0.127)
			(layers "F.Cu" "F.Mask" "F.Paste")
			(net "SPI_GBE_HOLD#")
			(options
				(clearance outline)
				(anchor circle)
			)
			(primitives
				(gr_poly
					(pts
						(arc
							(start -0.2032 -0.2794)
							(mid -0.239121 -0.264521)
							(end -0.254 -0.2286)
						)
						(arc
							(start -0.254 0.2286)
							(mid -0.239121 0.264521)
							(end -0.2032 0.2794)
						)
						(arc
							(start 0.2032 0.2794)
							(mid 0.239121 0.264521)
							(end 0.254 0.2286)
						)
						(arc
							(start 0.254 -0.2286)
							(mid 0.239121 -0.264521)
							(end 0.2032 -0.2794)
						)
					)
					(width 0)
					(fill yes)
				)
			)
		)
	)
	(footprint ""
		(layer "F.Cu")
		(at 26.416 -50.038 -90)
		(property "Reference" "PC70"
			(at 0 0 270)
			(layer "F.SilkS")
			(hide yes)
			(effects
				(font
					(size 1.27 1.27)
				)
			)
		)
		(property "Value" "SCD22U10V2KX-1GP"
			(at 1.8923 -1.2065 270)
			(unlocked yes)
			(layer "F.Fab")
			(hide yes)
			(effects
				(font
					(size 1.016 1.016)
					(thickness 0.1524)
				)
			)
		)
		(property "Device Type" "C402H22"
			(at 1.8923 -2.7305 270)
			(unlocked yes)
			(layer "F.Fab")
			(hide yes)
			(effects
				(font
					(size 1.016 1.016)
					(thickness 0.1524)
				)
			)
		)
		(duplicate_pad_numbers_are_jumpers no)
		(fp_rect
			(start -0.381 0.7366)
			(end 0.381 -0.7366)
			(stroke
				(width 0)
				(type default)
			)
			(fill no)
			(layer "F.CrtYd")
		)
		(fp_rect
			(start -0.381 0.7366)
			(end 0.381 -0.7366)
			(stroke
				(width 0)
				(type default)
			)
			(fill no)
			(layer "F.Fab")
		)
		(pad "1" smd custom
			(at 0 -0.4572 270)
			(size 0.1143 0.1143)
			(layers "F.Cu" "F.Mask" "F.Paste")
			(net "VR_PVCCP_ISUMP")
			(options
				(clearance outline)
				(anchor circle)
			)
			(primitives
				(gr_poly
					(pts
						(arc
							(start -0.254 -0.1778)
							(mid -0.239121 -0.213721)
							(end -0.2032 -0.2286)
						)
						(arc
							(start 0.2032 -0.2286)
							(mid 0.239121 -0.213721)
							(end 0.254 -0.1778)
						)
						(arc
							(start 0.254 0.1778)
							(mid 0.239121 0.213721)
							(end 0.2032 0.2286)
						)
						(arc
							(start -0.2032 0.2286)
							(mid -0.239121 0.213721)
							(end -0.254 0.1778)
						)
					)
					(width 0)
					(fill yes)
				)
			)
		)
		(pad "2" smd custom
			(at 0 0.4572 270)
			(size 0.1143 0.1143)
			(layers "F.Cu" "F.Mask" "F.Paste")
			(net "VR_PVCCP_ISUMN")
			(options
				(clearance outline)
				(anchor circle)
			)
			(primitives
				(gr_poly
					(pts
						(arc
							(start -0.254 -0.1778)
							(mid -0.239121 -0.213721)
							(end -0.2032 -0.2286)
						)
						(arc
							(start 0.2032 -0.2286)
							(mid 0.239121 -0.213721)
							(end 0.254 -0.1778)
						)
						(arc
							(start 0.254 0.1778)
							(mid 0.239121 0.213721)
							(end 0.2032 0.2286)
						)
						(arc
							(start -0.2032 0.2286)
							(mid -0.239121 0.213721)
							(end -0.254 0.1778)
						)
					)
					(width 0)
					(fill yes)
				)
			)
		)
	)
	(footprint ""
		(layer "F.Cu")
		(at 66.929 -12.573 -90)
		(property "Reference" "C338"
			(at 0 0 270)
			(layer "F.SilkS")
			(hide yes)
			(effects
				(font
					(size 1.27 1.27)
				)
			)
		)
		(property "Value" "SCD1U10V2KX-5GP"
			(at 1.8923 -1.2065 270)
			(unlocked yes)
			(layer "F.Fab")
			(hide yes)
			(effects
				(font
					(size 1.016 1.016)
					(thickness 0.1524)
				)
			)
		)
		(property "Device Type" "C402H22"
			(at 1.8923 -2.7305 270)
			(unlocked yes)
			(layer "F.Fab")
			(hide yes)
			(effects
				(font
					(size 1.016 1.016)
					(thickness 0.1524)
				)
			)
		)
		(duplicate_pad_numbers_are_jumpers no)
		(fp_rect
			(start -0.381 0.7366)
			(end 0.381 -0.7366)
			(stroke
				(width 0)
				(type default)
			)
			(fill no)
			(layer "F.CrtYd")
		)
		(fp_rect
			(start -0.381 0.7366)
			(end 0.381 -0.7366)
			(stroke
				(width 0)
				(type default)
			)
			(fill no)
			(layer "F.Fab")
		)
		(pad "1" smd custom
			(at 0 -0.4572 270)
			(size 0.1143 0.1143)
			(layers "F.Cu" "F.Mask" "F.Paste")
			(net "P3V3")
			(options
				(clearance outline)
				(anchor circle)
			)
			(primitives
				(gr_poly
					(pts
						(arc
							(start -0.254 -0.1778)
							(mid -0.239121 -0.213721)
							(end -0.2032 -0.2286)
						)
						(arc
							(start 0.2032 -0.2286)
							(mid 0.239121 -0.213721)
							(end 0.254 -0.1778)
						)
						(arc
							(start 0.254 0.1778)
							(mid 0.239121 0.213721)
							(end 0.2032 0.2286)
						)
						(arc
							(start -0.2032 0.2286)
							(mid -0.239121 0.213721)
							(end -0.254 0.1778)
						)
					)
					(width 0)
					(fill yes)
				)
			)
		)
		(pad "2" smd custom
			(at 0 0.4572 270)
			(size 0.1143 0.1143)
			(layers "F.Cu" "F.Mask" "F.Paste")
			(net "GND")
			(options
				(clearance outline)
				(anchor circle)
			)
			(primitives
				(gr_poly
					(pts
						(arc
							(start -0.254 -0.1778)
							(mid -0.239121 -0.213721)
							(end -0.2032 -0.2286)
						)
						(arc
							(start 0.2032 -0.2286)
							(mid 0.239121 -0.213721)
							(end 0.254 -0.1778)
						)
						(arc
							(start 0.254 0.1778)
							(mid 0.239121 0.213721)
							(end 0.2032 0.2286)
						)
						(arc
							(start -0.2032 0.2286)
							(mid -0.239121 0.213721)
							(end -0.254 0.1778)
						)
					)
					(width 0)
					(fill yes)
				)
			)
		)
	)
	(footprint ""
		(layer "F.Cu")
		(at 19.939 -20.828 -90)
		(property "Reference" "PR103"
			(at 0 0 270)
			(layer "F.SilkS")
			(hide yes)
			(effects
				(font
					(size 1.27 1.27)
				)
			)
		)
		(property "Value" "6K49R2D-GP"
			(at 1.7907 -1.1176 270)
			(unlocked yes)
			(layer "F.Fab")
			(hide yes)
			(effects
				(font
					(size 1.016 1.016)
					(thickness 0.1524)
				)
			)
		)
		(property "Device Type" "R402H16"
			(at 1.7907 -2.6416 270)
			(unlocked yes)
			(layer "F.Fab")
			(hide yes)
			(effects
				(font
					(size 1.016 1.016)
					(thickness 0.1524)
				)
			)
		)
		(duplicate_pad_numbers_are_jumpers no)
		(fp_rect
			(start -0.381 0.8382)
			(end 0.381 -0.8382)
			(stroke
				(width 0)
				(type default)
			)
			(fill no)
			(layer "F.CrtYd")
		)
		(fp_rect
			(start -0.381 0.8382)
			(end 0.381 -0.8382)
			(stroke
				(width 0)
				(type default)
			)
			(fill no)
			(layer "F.Fab")
		)
		(pad "1" smd custom
			(at 0 -0.4318 270)
			(size 0.127 0.127)
			(layers "F.Cu" "F.Mask" "F.Paste")
			(net "P1V0_VFB_R")
			(options
				(clearance outline)
				(anchor circle)
			)
			(primitives
				(gr_poly
					(pts
						(arc
							(start -0.2032 -0.2794)
							(mid -0.239121 -0.264521)
							(end -0.254 -0.2286)
						)
						(arc
							(start -0.254 0.2286)
							(mid -0.239121 0.264521)
							(end -0.2032 0.2794)
						)
						(arc
							(start 0.2032 0.2794)
							(mid 0.239121 0.264521)
							(end 0.254 0.2286)
						)
						(arc
							(start 0.254 -0.2286)
							(mid 0.239121 -0.264521)
							(end 0.2032 -0.2794)
						)
					)
					(width 0)
					(fill yes)
				)
			)
		)
		(pad "2" smd custom
			(at 0 0.4318 270)
			(size 0.127 0.127)
			(layers "F.Cu" "F.Mask" "F.Paste")
			(net "P1V0_VFB")
			(options
				(clearance outline)
				(anchor circle)
			)
			(primitives
				(gr_poly
					(pts
						(arc
							(start -0.2032 -0.2794)
							(mid -0.239121 -0.264521)
							(end -0.254 -0.2286)
						)
						(arc
							(start -0.254 0.2286)
							(mid -0.239121 0.264521)
							(end -0.2032 0.2794)
						)
						(arc
							(start 0.2032 0.2794)
							(mid 0.239121 0.264521)
							(end 0.254 0.2286)
						)
						(arc
							(start 0.254 -0.2286)
							(mid 0.239121 -0.264521)
							(end 0.2032 -0.2794)
						)
					)
					(width 0)
					(fill yes)
				)
			)
		)
	)
	(footprint ""
		(layer "F.Cu")
		(at 75.4888 -37.084 180)
		(property "Reference" "TP33"
			(at 0 0 180)
			(layer "F.SilkS")
			(hide yes)
			(effects
				(font
					(size 1.27 1.27)
				)
			)
		)
		(property "Value" "TPAD28-1-GP-U"
			(at 0.0508 -1.9304 180)
			(unlocked yes)
			(layer "F.Fab")
			(hide yes)
			(effects
				(font
					(size 1.016 1.016)
					(thickness 0.1524)
				)
			)
		)
		(property "Device Type" "TPAD28-1-U"
			(at 0.0508 -3.4544 180)
			(unlocked yes)
			(layer "F.Fab")
			(hide yes)
			(effects
				(font
					(size 1.016 1.016)
					(thickness 0.1524)
				)
			)
		)
		(duplicate_pad_numbers_are_jumpers no)
		(fp_poly
			(pts
				(arc
					(start -0.3556 0)
					(mid 0.3556 0)
					(end -0.3556 0)
				)
			)
			(stroke
				(width 0)
				(type default)
			)
			(fill no)
			(layer "F.CrtYd")
		)
		(fp_poly
			(pts
				(arc
					(start -0.9525 0)
					(mid 0.9525 0)
					(end -0.9525 0)
				)
			)
			(stroke
				(width 0)
				(type default)
			)
			(fill no)
			(layer "F.Fab")
		)
		(pad "1" smd circle
			(at 0 0 180)
			(size 0.7112 0.7112)
			(layers "F.Cu" "F.Mask" "F.Paste")
			(net "USB_OC#")
		)
	)
	(footprint ""
		(layer "F.Cu")
		(at 31.75 -13.335)
		(property "Reference" "U29"
			(at 0 0 0)
			(layer "F.SilkS")
			(hide yes)
			(effects
				(font
					(size 1.27 1.27)
				)
			)
		)
		(property "Value" "2N7002DW-7F-GP"
			(at -2.5654 1.1049 0)
			(unlocked yes)
			(layer "F.Fab")
			(hide yes)
			(effects
				(font
					(size 1.016 1.016)
					(thickness 0.1524)
				)
			)
		)
		(property "Device Type" "SOT-363H44"
			(at -2.5654 -0.4191 0)
			(unlocked yes)
			(layer "F.Fab")
			(hide yes)
			(effects
				(font
					(size 1.016 1.016)
					(thickness 0.1524)
				)
			)
		)
		(duplicate_pad_numbers_are_jumpers no)
		(fp_poly
			(pts
				(xy -0.6731 1.4351) (xy -0.9779 1.7399) (xy -0.381 1.7399) (xy -0.3683 1.7399) (xy -0.381 1.7272)
			)
			(stroke
				(width 0)
				(type default)
			)
			(fill yes)
			(layer "F.SilkS")
		)
		(fp_poly
			(pts
				(xy 1.2573 0.8763) (xy 1.2573 -0.8763) (xy 0.9525 -0.8763) (xy 0.9525 -1.4351) (xy -0.9525 -1.4351)
				(xy -0.9525 -0.8763) (xy -1.2573 -0.8763) (xy -1.2573 0.8763) (xy -0.9525 0.8763) (xy -0.9525 1.4351)
				(xy 0.9525 1.4351) (xy 0.9525 0.8763)
			)
			(stroke
				(width 0)
				(type default)
			)
			(fill no)
			(layer "F.CrtYd")
		)
		(fp_poly
			(pts
				(xy 1.2573 0.8763) (xy 1.2573 -0.8763) (xy 0.9525 -0.8763) (xy 0.9525 -1.4351) (xy -0.9525 -1.4351)
				(xy -0.9525 -0.8763) (xy -1.2573 -0.8763) (xy -1.2573 0.8763) (xy -0.9525 0.8763) (xy -0.9525 1.4351)
				(xy 0.9525 1.4351) (xy 0.9525 0.8763)
			)
			(stroke
				(width 0)
				(type default)
			)
			(fill no)
			(layer "F.Fab")
		)
		(pad "1" smd rect
			(at -0.65024 0.8255)
			(size 0.3556 0.9652)
			(layers "F.Cu" "F.Mask" "F.Paste")
			(net "BMC_I2C_CLK")
		)
		(pad "2" smd rect
			(at 0 0.8255)
			(size 0.3556 0.9652)
			(layers "F.Cu" "F.Mask" "F.Paste")
			(net "PICE_GF_I2C_SW_EN")
		)
		(pad "3" smd rect
			(at 0.65024 0.8255)
			(size 0.3556 0.9652)
			(layers "F.Cu" "F.Mask" "F.Paste")
			(net "PCIE_GF_I2C_DATA")
		)
		(pad "4" smd rect
			(at 0.65024 -0.8255)
			(size 0.3556 0.9652)
			(layers "F.Cu" "F.Mask" "F.Paste")
			(net "BMC_I2C_DATA")
		)
		(pad "5" smd rect
			(at 0 -0.8255)
			(size 0.3556 0.9652)
			(layers "F.Cu" "F.Mask" "F.Paste")
			(net "PICE_GF_I2C_SW_EN")
		)
		(pad "6" smd rect
			(at -0.65024 -0.8255)
			(size 0.3556 0.9652)
			(layers "F.Cu" "F.Mask" "F.Paste")
			(net "PCIE_GF_I2C_CLK")
		)
	)
	(footprint ""
		(layer "F.Cu")
		(at 46.863 -37.5158)
		(property "Reference" "C314"
			(at 0 0 0)
			(layer "F.SilkS")
			(hide yes)
			(effects
				(font
					(size 1.27 1.27)
				)
			)
		)
		(property "Value" "SCD1U10V2KX-5GP"
			(at 1.8923 -1.2065 0)
			(unlocked yes)
			(layer "F.Fab")
			(hide yes)
			(effects
				(font
					(size 1.016 1.016)
					(thickness 0.1524)
				)
			)
		)
		(property "Device Type" "C402H22"
			(at 1.8923 -2.7305 0)
			(unlocked yes)
			(layer "F.Fab")
			(hide yes)
			(effects
				(font
					(size 1.016 1.016)
					(thickness 0.1524)
				)
			)
		)
		(duplicate_pad_numbers_are_jumpers no)
		(fp_rect
			(start -0.381 0.7366)
			(end 0.381 -0.7366)
			(stroke
				(width 0)
				(type default)
			)
			(fill no)
			(layer "F.CrtYd")
		)
		(fp_rect
			(start -0.381 0.7366)
			(end 0.381 -0.7366)
			(stroke
				(width 0)
				(type default)
			)
			(fill no)
			(layer "F.Fab")
		)
		(pad "1" smd custom
			(at 0 -0.4572)
			(size 0.1143 0.1143)
			(layers "F.Cu" "F.Mask" "F.Paste")
			(net "P3V3_STBY")
			(options
				(clearance outline)
				(anchor circle)
			)
			(primitives
				(gr_poly
					(pts
						(arc
							(start -0.254 -0.1778)
							(mid -0.239121 -0.213721)
							(end -0.2032 -0.2286)
						)
						(arc
							(start 0.2032 -0.2286)
							(mid 0.239121 -0.213721)
							(end 0.254 -0.1778)
						)
						(arc
							(start 0.254 0.1778)
							(mid 0.239121 0.213721)
							(end 0.2032 0.2286)
						)
						(arc
							(start -0.2032 0.2286)
							(mid -0.239121 0.213721)
							(end -0.254 0.1778)
						)
					)
					(width 0)
					(fill yes)
				)
			)
		)
		(pad "2" smd custom
			(at 0 0.4572)
			(size 0.1143 0.1143)
			(layers "F.Cu" "F.Mask" "F.Paste")
			(net "GND")
			(options
				(clearance outline)
				(anchor circle)
			)
			(primitives
				(gr_poly
					(pts
						(arc
							(start -0.254 -0.1778)
							(mid -0.239121 -0.213721)
							(end -0.2032 -0.2286)
						)
						(arc
							(start 0.2032 -0.2286)
							(mid 0.239121 -0.213721)
							(end 0.254 -0.1778)
						)
						(arc
							(start 0.254 0.1778)
							(mid 0.239121 0.213721)
							(end 0.2032 0.2286)
						)
						(arc
							(start -0.2032 0.2286)
							(mid -0.239121 0.213721)
							(end -0.254 0.1778)
						)
					)
					(width 0)
					(fill yes)
				)
			)
		)
	)
	(footprint ""
		(layer "F.Cu")
		(at 73.025 -40.005)
		(property "Reference" "R92"
			(at 0 0 0)
			(layer "F.SilkS")
			(hide yes)
			(effects
				(font
					(size 1.27 1.27)
				)
			)
		)
		(property "Value" "10MR3F-GP"
			(at -0.0254 -2.5146 0)
			(unlocked yes)
			(layer "F.Fab")
			(hide yes)
			(effects
				(font
					(size 1.016 1.016)
					(thickness 0.1524)
				)
			)
		)
		(property "Device Type" "R603H22"
			(at -0.0254 -4.0386 0)
			(unlocked yes)
			(layer "F.Fab")
			(hide yes)
			(effects
				(font
					(size 1.016 1.016)
					(thickness 0.1524)
				)
			)
		)
		(duplicate_pad_numbers_are_jumpers no)
		(fp_line
			(start -0.2032 0)
			(end -0.4191 0)
			(stroke
				(width 0.2032)
				(type default)
			)
			(layer "F.SilkS")
		)
		(fp_line
			(start 0.4318 0)
			(end 0.2032 0)
			(stroke
				(width 0.2032)
				(type default)
			)
			(layer "F.SilkS")
		)
		(fp_rect
			(start -0.635 1.1811)
			(end 0.635 -1.1811)
			(stroke
				(width 0)
				(type default)
			)
			(fill no)
			(layer "F.CrtYd")
		)
		(fp_rect
			(start -0.635 1.1811)
			(end 0.635 -1.1811)
			(stroke
				(width 0)
				(type default)
			)
			(fill no)
			(layer "F.Fab")
		)
		(pad "1" smd custom
			(at 0 -0.6604)
			(size 0.19685 0.19685)
			(layers "F.Cu" "F.Mask" "F.Paste")
			(net "RTC_X1PAD")
			(options
				(clearance outline)
				(anchor circle)
			)
			(primitives
				(gr_poly
					(pts
						(arc
							(start 0.508 -0.2921)
							(mid 0.478242 -0.363942)
							(end 0.4064 -0.3937)
						)
						(arc
							(start -0.4064 -0.3937)
							(mid -0.478242 -0.363942)
							(end -0.508 -0.2921)
						)
						(arc
							(start -0.508 0.2921)
							(mid -0.478242 0.363942)
							(end -0.4064 0.3937)
						)
						(arc
							(start 0.4064 0.3937)
							(mid 0.478242 0.363942)
							(end 0.508 0.2921)
						)
					)
					(width 0)
					(fill yes)
				)
			)
		)
		(pad "2" smd custom
			(at 0 0.6604)
			(size 0.19685 0.19685)
			(layers "F.Cu" "F.Mask" "F.Paste")
			(net "RTC_X2PAD")
			(options
				(clearance outline)
				(anchor circle)
			)
			(primitives
				(gr_poly
					(pts
						(arc
							(start 0.508 -0.2921)
							(mid 0.478242 -0.363942)
							(end 0.4064 -0.3937)
						)
						(arc
							(start -0.4064 -0.3937)
							(mid -0.478242 -0.363942)
							(end -0.508 -0.2921)
						)
						(arc
							(start -0.508 0.2921)
							(mid -0.478242 0.363942)
							(end -0.4064 0.3937)
						)
						(arc
							(start 0.4064 0.3937)
							(mid 0.478242 0.363942)
							(end 0.508 0.2921)
						)
					)
					(width 0)
					(fill yes)
				)
			)
		)
	)
	(footprint ""
		(layer "F.Cu")
		(at 15.494 -21.4122 90)
		(property "Reference" "PSP1"
			(at 0 0 90)
			(layer "F.SilkS")
			(hide yes)
			(effects
				(font
					(size 1.27 1.27)
				)
			)
		)
		(property "Value" "COPPER-CLOSE-GP-U"
			(at 0.0762 -2.8702 90)
			(unlocked yes)
			(layer "F.Fab")
			(hide yes)
			(effects
				(font
					(size 1.016 1.016)
					(thickness 0.1524)
				)
			)
		)
		(property "Device Type" "CON2C-U"
			(at 0.0762 -4.3942 90)
			(unlocked yes)
			(layer "F.Fab")
			(hide yes)
			(effects
				(font
					(size 1.016 1.016)
					(thickness 0.1524)
				)
			)
		)
		(duplicate_pad_numbers_are_jumpers no)
		(fp_rect
			(start -0.9398 0.9652)
			(end 0.9398 -0.9652)
			(stroke
				(width 0)
				(type default)
			)
			(fill no)
			(layer "F.CrtYd")
		)
		(fp_rect
			(start -0.9398 0.9652)
			(end 0.9398 -0.9652)
			(stroke
				(width 0)
				(type default)
			)
			(fill no)
			(layer "F.Fab")
		)
		(pad "1" smd custom
			(at 0 -0.5334 90)
			(size 0.17145 0.17145)
			(layers "F.Cu" "F.Mask" "F.Paste")
			(net "GND")
			(options
				(clearance outline)
				(anchor circle)
			)
			(primitives
				(gr_poly
					(pts
						(xy -0.127 0.3429) (xy -0.127 0.1651) (xy -0.635 -0.3429) (xy 0.635 -0.3429) (xy 0.127 0.1651)
						(xy 0.127 0.3429)
					)
					(width 0)
					(fill yes)
				)
			)
		)
		(pad "2" smd custom
			(at 0 0.5334 90)
			(size 0.17145 0.17145)
			(layers "F.Cu" "F.Mask" "F.Paste")
			(net "AGND_P1V0")
			(options
				(clearance outline)
				(anchor circle)
			)
			(primitives
				(gr_poly
					(pts
						(xy -0.635 0.3429) (xy -0.127 -0.1651) (xy -0.127 -0.3429) (xy 0.127 -0.3429) (xy 0.127 -0.1651)
						(xy 0.635 0.3429)
					)
					(width 0)
					(fill yes)
				)
			)
		)
	)
	(footprint ""
		(layer "F.Cu")
		(at 72.136 -55.626 -90)
		(property "Reference" "C70"
			(at 0 0 270)
			(layer "F.SilkS")
			(hide yes)
			(effects
				(font
					(size 1.27 1.27)
				)
			)
		)
		(property "Value" "SCD1U16V2KX-3GP"
			(at 1.1811 -2.7051 270)
			(unlocked yes)
			(layer "F.Fab")
			(hide yes)
			(effects
				(font
					(size 1.016 1.016)
					(thickness 0.1524)
				)
			)
		)
		(property "Device Type" "C402H22"
			(at 1.1811 -4.2291 270)
			(unlocked yes)
			(layer "F.Fab")
			(hide yes)
			(effects
				(font
					(size 1.016 1.016)
					(thickness 0.1524)
				)
			)
		)
		(duplicate_pad_numbers_are_jumpers no)
		(fp_rect
			(start -0.381 0.7366)
			(end 0.381 -0.7366)
			(stroke
				(width 0)
				(type default)
			)
			(fill no)
			(layer "F.CrtYd")
		)
		(fp_rect
			(start -0.381 0.7366)
			(end 0.381 -0.7366)
			(stroke
				(width 0)
				(type default)
			)
			(fill no)
			(layer "F.Fab")
		)
		(pad "1" smd custom
			(at 0 -0.4572 270)
			(size 0.1143 0.1143)
			(layers "F.Cu" "F.Mask" "F.Paste")
			(net "P1V0_SENSE")
			(options
				(clearance outline)
				(anchor circle)
			)
			(primitives
				(gr_poly
					(pts
						(arc
							(start -0.254 -0.1778)
							(mid -0.239121 -0.213721)
							(end -0.2032 -0.2286)
						)
						(arc
							(start 0.2032 -0.2286)
							(mid 0.239121 -0.213721)
							(end 0.254 -0.1778)
						)
						(arc
							(start 0.254 0.1778)
							(mid 0.239121 0.213721)
							(end 0.2032 0.2286)
						)
						(arc
							(start -0.2032 0.2286)
							(mid -0.239121 0.213721)
							(end -0.254 0.1778)
						)
					)
					(width 0)
					(fill yes)
				)
			)
		)
		(pad "2" smd custom
			(at 0 0.4572 270)
			(size 0.1143 0.1143)
			(layers "F.Cu" "F.Mask" "F.Paste")
			(net "GND")
			(options
				(clearance outline)
				(anchor circle)
			)
			(primitives
				(gr_poly
					(pts
						(arc
							(start -0.254 -0.1778)
							(mid -0.239121 -0.213721)
							(end -0.2032 -0.2286)
						)
						(arc
							(start 0.2032 -0.2286)
							(mid 0.239121 -0.213721)
							(end 0.254 -0.1778)
						)
						(arc
							(start 0.254 0.1778)
							(mid 0.239121 0.213721)
							(end 0.2032 0.2286)
						)
						(arc
							(start -0.2032 0.2286)
							(mid -0.239121 0.213721)
							(end -0.254 0.1778)
						)
					)
					(width 0)
					(fill yes)
				)
			)
		)
	)
	(footprint ""
		(layer "F.Cu")
		(at 44.323 -25.7302 180)
		(property "Reference" "C208"
			(at 0 0 180)
			(layer "F.SilkS")
			(hide yes)
			(effects
				(font
					(size 1.27 1.27)
				)
			)
		)
		(property "Value" "SCD1U10V2KX-5GP"
			(at 1.1811 -2.7051 180)
			(unlocked yes)
			(layer "F.Fab")
			(hide yes)
			(effects
				(font
					(size 1.016 1.016)
					(thickness 0.1524)
				)
			)
		)
		(property "Device Type" "C402H22"
			(at 1.1811 -4.2291 180)
			(unlocked yes)
			(layer "F.Fab")
			(hide yes)
			(effects
				(font
					(size 1.016 1.016)
					(thickness 0.1524)
				)
			)
		)
		(duplicate_pad_numbers_are_jumpers no)
		(fp_rect
			(start -0.381 0.7366)
			(end 0.381 -0.7366)
			(stroke
				(width 0)
				(type default)
			)
			(fill no)
			(layer "F.CrtYd")
		)
		(fp_rect
			(start -0.381 0.7366)
			(end 0.381 -0.7366)
			(stroke
				(width 0)
				(type default)
			)
			(fill no)
			(layer "F.Fab")
		)
		(pad "1" smd custom
			(at 0 -0.4572 180)
			(size 0.1143 0.1143)
			(layers "F.Cu" "F.Mask" "F.Paste")
			(net "P3V3_VDD_CLKBUFF")
			(options
				(clearance outline)
				(anchor circle)
			)
			(primitives
				(gr_poly
					(pts
						(arc
							(start -0.254 -0.1778)
							(mid -0.239121 -0.213721)
							(end -0.2032 -0.2286)
						)
						(arc
							(start 0.2032 -0.2286)
							(mid 0.239121 -0.213721)
							(end 0.254 -0.1778)
						)
						(arc
							(start 0.254 0.1778)
							(mid 0.239121 0.213721)
							(end 0.2032 0.2286)
						)
						(arc
							(start -0.2032 0.2286)
							(mid -0.239121 0.213721)
							(end -0.254 0.1778)
						)
					)
					(width 0)
					(fill yes)
				)
			)
		)
		(pad "2" smd custom
			(at 0 0.4572 180)
			(size 0.1143 0.1143)
			(layers "F.Cu" "F.Mask" "F.Paste")
			(net "GND")
			(options
				(clearance outline)
				(anchor circle)
			)
			(primitives
				(gr_poly
					(pts
						(arc
							(start -0.254 -0.1778)
							(mid -0.239121 -0.213721)
							(end -0.2032 -0.2286)
						)
						(arc
							(start 0.2032 -0.2286)
							(mid 0.239121 -0.213721)
							(end 0.254 -0.1778)
						)
						(arc
							(start 0.254 0.1778)
							(mid 0.239121 0.213721)
							(end 0.2032 0.2286)
						)
						(arc
							(start -0.2032 0.2286)
							(mid -0.239121 0.213721)
							(end -0.254 0.1778)
						)
					)
					(width 0)
					(fill yes)
				)
			)
		)
	)
	(footprint ""
		(layer "F.Cu")
		(at 74.4982 -41.148 180)
		(property "Reference" "C26"
			(at 0 0 180)
			(layer "F.SilkS")
			(hide yes)
			(effects
				(font
					(size 1.27 1.27)
				)
			)
		)
		(property "Value" "SC6P50V2CN-1GP"
			(at 1.1811 -2.7051 180)
			(unlocked yes)
			(layer "F.Fab")
			(hide yes)
			(effects
				(font
					(size 1.016 1.016)
					(thickness 0.1524)
				)
			)
		)
		(property "Device Type" "C402H22"
			(at 1.1811 -4.2291 180)
			(unlocked yes)
			(layer "F.Fab")
			(hide yes)
			(effects
				(font
					(size 1.016 1.016)
					(thickness 0.1524)
				)
			)
		)
		(duplicate_pad_numbers_are_jumpers no)
		(fp_rect
			(start -0.381 0.7366)
			(end 0.381 -0.7366)
			(stroke
				(width 0)
				(type default)
			)
			(fill no)
			(layer "F.CrtYd")
		)
		(fp_rect
			(start -0.381 0.7366)
			(end 0.381 -0.7366)
			(stroke
				(width 0)
				(type default)
			)
			(fill no)
			(layer "F.Fab")
		)
		(pad "1" smd custom
			(at 0 -0.4572 180)
			(size 0.1143 0.1143)
			(layers "F.Cu" "F.Mask" "F.Paste")
			(net "RTC_X1PAD")
			(options
				(clearance outline)
				(anchor circle)
			)
			(primitives
				(gr_poly
					(pts
						(arc
							(start -0.254 -0.1778)
							(mid -0.239121 -0.213721)
							(end -0.2032 -0.2286)
						)
						(arc
							(start 0.2032 -0.2286)
							(mid 0.239121 -0.213721)
							(end 0.254 -0.1778)
						)
						(arc
							(start 0.254 0.1778)
							(mid 0.239121 0.213721)
							(end 0.2032 0.2286)
						)
						(arc
							(start -0.2032 0.2286)
							(mid -0.239121 0.213721)
							(end -0.254 0.1778)
						)
					)
					(width 0)
					(fill yes)
				)
			)
		)
		(pad "2" smd custom
			(at 0 0.4572 180)
			(size 0.1143 0.1143)
			(layers "F.Cu" "F.Mask" "F.Paste")
			(net "GND")
			(options
				(clearance outline)
				(anchor circle)
			)
			(primitives
				(gr_poly
					(pts
						(arc
							(start -0.254 -0.1778)
							(mid -0.239121 -0.213721)
							(end -0.2032 -0.2286)
						)
						(arc
							(start 0.2032 -0.2286)
							(mid 0.239121 -0.213721)
							(end 0.254 -0.1778)
						)
						(arc
							(start 0.254 0.1778)
							(mid 0.239121 0.213721)
							(end 0.2032 0.2286)
						)
						(arc
							(start -0.2032 0.2286)
							(mid -0.239121 0.213721)
							(end -0.254 0.1778)
						)
					)
					(width 0)
					(fill yes)
				)
			)
		)
	)
	(footprint ""
		(layer "F.Cu")
		(at 70.612 -53.467 90)
		(property "Reference" "Q16"
			(at 0 0 90)
			(layer "F.SilkS")
			(hide yes)
			(effects
				(font
					(size 1.27 1.27)
				)
			)
		)
		(property "Value" "2N7002A-7-GP"
			(at -4.3561 -5.7912 90)
			(unlocked yes)
			(layer "F.Fab")
			(hide yes)
			(effects
				(font
					(size 1.016 1.016)
					(thickness 0.1524)
				)
			)
		)
		(property "Device Type" "SOT23DGS2D4H48"
			(at -4.3561 -7.3152 90)
			(unlocked yes)
			(layer "F.Fab")
			(hide yes)
			(effects
				(font
					(size 1.016 1.016)
					(thickness 0.1524)
				)
			)
		)
		(duplicate_pad_numbers_are_jumpers no)
		(fp_line
			(start 1.7145 -0.4445)
			(end -1.7145 -0.4445)
			(stroke
				(width 0.1524)
				(type default)
			)
			(layer "F.SilkS")
		)
		(fp_line
			(start -1.7145 -0.4445)
			(end -1.7145 0.4445)
			(stroke
				(width 0.1524)
				(type default)
			)
			(layer "F.SilkS")
		)
		(fp_line
			(start 1.7145 0.4445)
			(end 1.7145 -0.4445)
			(stroke
				(width 0.1524)
				(type default)
			)
			(layer "F.SilkS")
		)
		(fp_line
			(start -1.7145 0.4445)
			(end 1.7145 0.4445)
			(stroke
				(width 0.1524)
				(type default)
			)
			(layer "F.SilkS")
		)
		(fp_poly
			(pts
				(xy -1.4224 1.5621) (xy -1.4224 0.9017) (xy -1.7145 0.9017) (xy -1.7145 -0.9017) (xy -0.4699 -0.9017)
				(xy -0.4699 -1.5621) (xy 0.4699 -1.5621) (xy 0.4699 -0.9017) (xy 1.7145 -0.9017) (xy 1.7145 0.9017)
				(xy 1.4224 0.9017) (xy 1.4224 1.5621) (xy 0.4826 1.5621) (xy 0.4826 0.9017) (xy -0.4826 0.9017)
				(xy -0.4826 1.5621)
			)
			(stroke
				(width 0)
				(type default)
			)
			(fill no)
			(layer "F.CrtYd")
		)
		(fp_poly
			(pts
				(xy -1.4224 1.5621) (xy -1.4224 0.9017) (xy -1.7145 0.9017) (xy -1.7145 -0.9017) (xy -0.4699 -0.9017)
				(xy -0.4699 -1.5621) (xy 0.4699 -1.5621) (xy 0.4699 -0.9017) (xy 1.7145 -0.9017) (xy 1.7145 0.9017)
				(xy 1.4224 0.9017) (xy 1.4224 1.5621) (xy 0.4826 1.5621) (xy 0.4826 0.9017) (xy -0.4826 0.9017)
				(xy -0.4826 1.5621)
			)
			(stroke
				(width 0)
				(type default)
			)
			(fill no)
			(layer "F.Fab")
		)
		(pad "D" smd custom
			(at 0 -1.069086 90)
			(size 0.17145 0.17145)
			(layers "F.Cu" "F.Mask" "F.Paste")
			(net "SMBUS_SW_INV_D")
			(options
				(clearance outline)
				(anchor circle)
			)
			(primitives
				(gr_poly
					(pts
						(arc
							(start -0.1397 0.3683)
							(mid -0.283384 0.308784)
							(end -0.3429 0.1651)
						)
						(arc
							(start -0.3429 -0.1651)
							(mid -0.283384 -0.308784)
							(end -0.1397 -0.3683)
						)
						(arc
							(start 0.1397 -0.3683)
							(mid 0.283384 -0.308784)
							(end 0.3429 -0.1651)
						)
						(arc
							(start 0.3429 0.1651)
							(mid 0.283384 0.308784)
							(end 0.1397 0.3683)
						)
					)
					(width 0)
					(fill yes)
				)
			)
		)
		(pad "G" smd custom
			(at -0.94996 1.069086 90)
			(size 0.17145 0.17145)
			(layers "F.Cu" "F.Mask" "F.Paste")
			(net "SMBUS_SW_EN")
			(options
				(clearance outline)
				(anchor circle)
			)
			(primitives
				(gr_poly
					(pts
						(arc
							(start -0.1397 0.3683)
							(mid -0.283384 0.308784)
							(end -0.3429 0.1651)
						)
						(arc
							(start -0.3429 -0.1651)
							(mid -0.283384 -0.308784)
							(end -0.1397 -0.3683)
						)
						(arc
							(start 0.1397 -0.3683)
							(mid 0.283384 -0.308784)
							(end 0.3429 -0.1651)
						)
						(arc
							(start 0.3429 0.1651)
							(mid 0.283384 0.308784)
							(end 0.1397 0.3683)
						)
					)
					(width 0)
					(fill yes)
				)
			)
		)
		(pad "S" smd custom
			(at 0.94996 1.069086 90)
			(size 0.17145 0.17145)
			(layers "F.Cu" "F.Mask" "F.Paste")
			(net "GND")
			(options
				(clearance outline)
				(anchor circle)
			)
			(primitives
				(gr_poly
					(pts
						(arc
							(start -0.1397 0.3683)
							(mid -0.283384 0.308784)
							(end -0.3429 0.1651)
						)
						(arc
							(start -0.3429 -0.1651)
							(mid -0.283384 -0.308784)
							(end -0.1397 -0.3683)
						)
						(arc
							(start 0.1397 -0.3683)
							(mid 0.283384 -0.308784)
							(end 0.3429 -0.1651)
						)
						(arc
							(start 0.3429 0.1651)
							(mid 0.283384 0.308784)
							(end 0.1397 0.3683)
						)
					)
					(width 0)
					(fill yes)
				)
			)
		)
	)
	(footprint ""
		(layer "F.Cu")
		(at 169.926 -40.894 -90)
		(property "Reference" "PC210"
			(at 0 0 270)
			(layer "F.SilkS")
			(hide yes)
			(effects
				(font
					(size 1.27 1.27)
				)
			)
		)
		(property "Value" "SC22P50V2GN-GP"
			(at 1.8923 -1.2065 270)
			(unlocked yes)
			(layer "F.Fab")
			(hide yes)
			(effects
				(font
					(size 1.016 1.016)
					(thickness 0.1524)
				)
			)
		)
		(property "Device Type" "C402H22"
			(at 1.8923 -2.7305 270)
			(unlocked yes)
			(layer "F.Fab")
			(hide yes)
			(effects
				(font
					(size 1.016 1.016)
					(thickness 0.1524)
				)
			)
		)
		(duplicate_pad_numbers_are_jumpers no)
		(fp_rect
			(start -0.381 0.7366)
			(end 0.381 -0.7366)
			(stroke
				(width 0)
				(type default)
			)
			(fill no)
			(layer "F.CrtYd")
		)
		(fp_rect
			(start -0.381 0.7366)
			(end 0.381 -0.7366)
			(stroke
				(width 0)
				(type default)
			)
			(fill no)
			(layer "F.Fab")
		)
		(pad "1" smd custom
			(at 0 -0.4572 270)
			(size 0.1143 0.1143)
			(layers "F.Cu" "F.Mask" "F.Paste")
			(net "P2V5_STBY_OUT")
			(options
				(clearance outline)
				(anchor circle)
			)
			(primitives
				(gr_poly
					(pts
						(arc
							(start -0.254 -0.1778)
							(mid -0.239121 -0.213721)
							(end -0.2032 -0.2286)
						)
						(arc
							(start 0.2032 -0.2286)
							(mid 0.239121 -0.213721)
							(end 0.254 -0.1778)
						)
						(arc
							(start 0.254 0.1778)
							(mid 0.239121 0.213721)
							(end 0.2032 0.2286)
						)
						(arc
							(start -0.2032 0.2286)
							(mid -0.239121 0.213721)
							(end -0.254 0.1778)
						)
					)
					(width 0)
					(fill yes)
				)
			)
		)
		(pad "2" smd custom
			(at 0 0.4572 270)
			(size 0.1143 0.1143)
			(layers "F.Cu" "F.Mask" "F.Paste")
			(net "P2V5_STBY_FB")
			(options
				(clearance outline)
				(anchor circle)
			)
			(primitives
				(gr_poly
					(pts
						(arc
							(start -0.254 -0.1778)
							(mid -0.239121 -0.213721)
							(end -0.2032 -0.2286)
						)
						(arc
							(start 0.2032 -0.2286)
							(mid 0.239121 -0.213721)
							(end 0.254 -0.1778)
						)
						(arc
							(start 0.254 0.1778)
							(mid 0.239121 0.213721)
							(end 0.2032 0.2286)
						)
						(arc
							(start -0.2032 0.2286)
							(mid -0.239121 0.213721)
							(end -0.254 0.1778)
						)
					)
					(width 0)
					(fill yes)
				)
			)
		)
	)
	(footprint ""
		(layer "F.Cu")
		(at 134.62 -15.367 -90)
		(property "Reference" "U30"
			(at 0 0 270)
			(layer "F.SilkS")
			(hide yes)
			(effects
				(font
					(size 1.27 1.27)
				)
			)
		)
		(property "Value" "2N7002DW-7F-GP"
			(at -2.5654 1.1049 270)
			(unlocked yes)
			(layer "F.Fab")
			(hide yes)
			(effects
				(font
					(size 1.016 1.016)
					(thickness 0.1524)
				)
			)
		)
		(property "Device Type" "SOT-363H44"
			(at -2.5654 -0.4191 270)
			(unlocked yes)
			(layer "F.Fab")
			(hide yes)
			(effects
				(font
					(size 1.016 1.016)
					(thickness 0.1524)
				)
			)
		)
		(duplicate_pad_numbers_are_jumpers no)
		(fp_poly
			(pts
				(xy -0.6731 1.4351) (xy -0.9779 1.7399) (xy -0.381 1.7399) (xy -0.3683 1.7399) (xy -0.381 1.7272)
			)
			(stroke
				(width 0)
				(type default)
			)
			(fill yes)
			(layer "F.SilkS")
		)
		(fp_poly
			(pts
				(xy 1.2573 0.8763) (xy 1.2573 -0.8763) (xy 0.9525 -0.8763) (xy 0.9525 -1.4351) (xy -0.9525 -1.4351)
				(xy -0.9525 -0.8763) (xy -1.2573 -0.8763) (xy -1.2573 0.8763) (xy -0.9525 0.8763) (xy -0.9525 1.4351)
				(xy 0.9525 1.4351) (xy 0.9525 0.8763)
			)
			(stroke
				(width 0)
				(type default)
			)
			(fill no)
			(layer "F.CrtYd")
		)
		(fp_poly
			(pts
				(xy 1.2573 0.8763) (xy 1.2573 -0.8763) (xy 0.9525 -0.8763) (xy 0.9525 -1.4351) (xy -0.9525 -1.4351)
				(xy -0.9525 -0.8763) (xy -1.2573 -0.8763) (xy -1.2573 0.8763) (xy -0.9525 0.8763) (xy -0.9525 1.4351)
				(xy 0.9525 1.4351) (xy 0.9525 0.8763)
			)
			(stroke
				(width 0)
				(type default)
			)
			(fill no)
			(layer "F.Fab")
		)
		(pad "1" smd rect
			(at -0.65024 0.8255 270)
			(size 0.3556 0.9652)
			(layers "F.Cu" "F.Mask" "F.Paste")
			(net "GND")
		)
		(pad "2" smd rect
			(at 0 0.8255 270)
			(size 0.3556 0.9652)
			(layers "F.Cu" "F.Mask" "F.Paste")
			(net "HOST_R_RSTBTN#")
		)
		(pad "3" smd rect
			(at 0.65024 0.8255 270)
			(size 0.3556 0.9652)
			(layers "F.Cu" "F.Mask" "F.Paste")
			(net "HOST_LV_RSTBTN#")
		)
		(pad "4" smd rect
			(at 0.65024 -0.8255 270)
			(size 0.3556 0.9652)
			(layers "F.Cu" "F.Mask" "F.Paste")
			(net "GND")
		)
		(pad "5" smd rect
			(at 0 -0.8255 270)
			(size 0.3556 0.9652)
			(layers "F.Cu" "F.Mask" "F.Paste")
			(net "HOST_LV_D_RSTBTN#")
		)
		(pad "6" smd rect
			(at -0.65024 -0.8255 270)
			(size 0.3556 0.9652)
			(layers "F.Cu" "F.Mask" "F.Paste")
			(net "HOST_LV_D_RSTBTN#")
		)
	)
	(footprint ""
		(layer "F.Cu")
		(at 55.626 -45.847 -90)
		(property "Reference" "R46"
			(at 0 0 270)
			(layer "F.SilkS")
			(hide yes)
			(effects
				(font
					(size 1.27 1.27)
				)
			)
		)
		(property "Value" "10KR2F-2-GP"
			(at 0.064008 -3.993896 270)
			(unlocked yes)
			(layer "F.Fab")
			(hide yes)
			(effects
				(font
					(size 1.016 1.016)
					(thickness 0.1524)
				)
			)
		)
		(property "Device Type" "R402H16"
			(at 0.064008 -5.517896 270)
			(unlocked yes)
			(layer "F.Fab")
			(hide yes)
			(effects
				(font
					(size 1.016 1.016)
					(thickness 0.1524)
				)
			)
		)
		(duplicate_pad_numbers_are_jumpers no)
		(fp_rect
			(start -0.381 0.8382)
			(end 0.381 -0.8382)
			(stroke
				(width 0)
				(type default)
			)
			(fill no)
			(layer "F.CrtYd")
		)
		(fp_rect
			(start -0.381 0.8382)
			(end 0.381 -0.8382)
			(stroke
				(width 0)
				(type default)
			)
			(fill no)
			(layer "F.Fab")
		)
		(pad "1" smd custom
			(at 0 -0.4318 270)
			(size 0.127 0.127)
			(layers "F.Cu" "F.Mask" "F.Paste")
			(net "P12V")
			(options
				(clearance outline)
				(anchor circle)
			)
			(primitives
				(gr_poly
					(pts
						(arc
							(start -0.2032 -0.2794)
							(mid -0.239121 -0.264521)
							(end -0.254 -0.2286)
						)
						(arc
							(start -0.254 0.2286)
							(mid -0.239121 0.264521)
							(end -0.2032 0.2794)
						)
						(arc
							(start 0.2032 0.2794)
							(mid 0.239121 0.264521)
							(end 0.254 0.2286)
						)
						(arc
							(start 0.254 -0.2286)
							(mid 0.239121 -0.264521)
							(end 0.2032 -0.2794)
						)
					)
					(width 0)
					(fill yes)
				)
			)
		)
		(pad "2" smd custom
			(at 0 0.4318 270)
			(size 0.127 0.127)
			(layers "F.Cu" "F.Mask" "F.Paste")
			(net "SW_P3V3_CPU_EN_LV_D")
			(options
				(clearance outline)
				(anchor circle)
			)
			(primitives
				(gr_poly
					(pts
						(arc
							(start -0.2032 -0.2794)
							(mid -0.239121 -0.264521)
							(end -0.254 -0.2286)
						)
						(arc
							(start -0.254 0.2286)
							(mid -0.239121 0.264521)
							(end -0.2032 0.2794)
						)
						(arc
							(start 0.2032 0.2794)
							(mid 0.239121 0.264521)
							(end 0.254 0.2286)
						)
						(arc
							(start 0.254 -0.2286)
							(mid 0.239121 -0.264521)
							(end 0.2032 -0.2794)
						)
					)
					(width 0)
					(fill yes)
				)
			)
		)
	)
	(footprint ""
		(layer "F.Cu")
		(at 183.007 -14.859 180)
		(property "Reference" "PC208"
			(at 0 0 180)
			(layer "F.SilkS")
			(hide yes)
			(effects
				(font
					(size 1.27 1.27)
				)
			)
		)
		(property "Value" "SC10U6D3V3MX-GP"
			(at 0 -2.8194 180)
			(unlocked yes)
			(layer "F.Fab")
			(hide yes)
			(effects
				(font
					(size 1.016 1.016)
					(thickness 0.1524)
				)
			)
		)
		(property "Device Type" "C603H38"
			(at 0 -4.3434 180)
			(unlocked yes)
			(layer "F.Fab")
			(hide yes)
			(effects
				(font
					(size 1.016 1.016)
					(thickness 0.1524)
				)
			)
		)
		(duplicate_pad_numbers_are_jumpers no)
		(fp_line
			(start -0.4064 0)
			(end 0.4064 0)
			(stroke
				(width 0.2286)
				(type default)
			)
			(layer "F.SilkS")
		)
		(fp_rect
			(start -0.635 1.1811)
			(end 0.635 -1.1811)
			(stroke
				(width 0)
				(type default)
			)
			(fill no)
			(layer "F.CrtYd")
		)
		(fp_rect
			(start -0.635 1.1811)
			(end 0.635 -1.1811)
			(stroke
				(width 0)
				(type default)
			)
			(fill no)
			(layer "F.Fab")
		)
		(pad "1" smd custom
			(at 0 -0.6604 180)
			(size 0.19685 0.19685)
			(layers "F.Cu" "F.Mask" "F.Paste")
			(net "GND")
			(options
				(clearance outline)
				(anchor circle)
			)
			(primitives
				(gr_poly
					(pts
						(arc
							(start 0.508 -0.2921)
							(mid 0.478242 -0.363942)
							(end 0.4064 -0.3937)
						)
						(arc
							(start -0.4064 -0.3937)
							(mid -0.478242 -0.363942)
							(end -0.508 -0.2921)
						)
						(arc
							(start -0.508 0.2921)
							(mid -0.478242 0.363942)
							(end -0.4064 0.3937)
						)
						(arc
							(start 0.4064 0.3937)
							(mid 0.478242 0.363942)
							(end 0.508 0.2921)
						)
					)
					(width 0)
					(fill yes)
				)
			)
		)
		(pad "2" smd custom
			(at 0 0.6604 180)
			(size 0.19685 0.19685)
			(layers "F.Cu" "F.Mask" "F.Paste")
			(net "PV_VDDR")
			(options
				(clearance outline)
				(anchor circle)
			)
			(primitives
				(gr_poly
					(pts
						(arc
							(start 0.508 -0.2921)
							(mid 0.478242 -0.363942)
							(end 0.4064 -0.3937)
						)
						(arc
							(start -0.4064 -0.3937)
							(mid -0.478242 -0.363942)
							(end -0.508 -0.2921)
						)
						(arc
							(start -0.508 0.2921)
							(mid -0.478242 0.363942)
							(end -0.4064 0.3937)
						)
						(arc
							(start 0.4064 0.3937)
							(mid 0.478242 0.363942)
							(end 0.508 0.2921)
						)
					)
					(width 0)
					(fill yes)
				)
			)
		)
	)
	(footprint ""
		(layer "F.Cu")
		(at 128.778 -56.388)
		(property "Reference" "C106"
			(at 0 0 0)
			(layer "F.SilkS")
			(hide yes)
			(effects
				(font
					(size 1.27 1.27)
				)
			)
		)
		(property "Value" "SC10U6D3V3MX-GP"
			(at 0 -2.8194 0)
			(unlocked yes)
			(layer "F.Fab")
			(hide yes)
			(effects
				(font
					(size 1.016 1.016)
					(thickness 0.1524)
				)
			)
		)
		(property "Device Type" "C603H38"
			(at 0 -4.3434 0)
			(unlocked yes)
			(layer "F.Fab")
			(hide yes)
			(effects
				(font
					(size 1.016 1.016)
					(thickness 0.1524)
				)
			)
		)
		(duplicate_pad_numbers_are_jumpers no)
		(fp_line
			(start -0.4064 0)
			(end 0.4064 0)
			(stroke
				(width 0.2286)
				(type default)
			)
			(layer "F.SilkS")
		)
		(fp_rect
			(start -0.635 1.1811)
			(end 0.635 -1.1811)
			(stroke
				(width 0)
				(type default)
			)
			(fill no)
			(layer "F.CrtYd")
		)
		(fp_rect
			(start -0.635 1.1811)
			(end 0.635 -1.1811)
			(stroke
				(width 0)
				(type default)
			)
			(fill no)
			(layer "F.Fab")
		)
		(pad "1" smd custom
			(at 0 -0.6604)
			(size 0.19685 0.19685)
			(layers "F.Cu" "F.Mask" "F.Paste")
			(net "PV_VTT_DDR_A")
			(options
				(clearance outline)
				(anchor circle)
			)
			(primitives
				(gr_poly
					(pts
						(arc
							(start 0.508 -0.2921)
							(mid 0.478242 -0.363942)
							(end 0.4064 -0.3937)
						)
						(arc
							(start -0.4064 -0.3937)
							(mid -0.478242 -0.363942)
							(end -0.508 -0.2921)
						)
						(arc
							(start -0.508 0.2921)
							(mid -0.478242 0.363942)
							(end -0.4064 0.3937)
						)
						(arc
							(start 0.4064 0.3937)
							(mid 0.478242 0.363942)
							(end 0.508 0.2921)
						)
					)
					(width 0)
					(fill yes)
				)
			)
		)
		(pad "2" smd custom
			(at 0 0.6604)
			(size 0.19685 0.19685)
			(layers "F.Cu" "F.Mask" "F.Paste")
			(net "GND")
			(options
				(clearance outline)
				(anchor circle)
			)
			(primitives
				(gr_poly
					(pts
						(arc
							(start 0.508 -0.2921)
							(mid 0.478242 -0.363942)
							(end 0.4064 -0.3937)
						)
						(arc
							(start -0.4064 -0.3937)
							(mid -0.478242 -0.363942)
							(end -0.508 -0.2921)
						)
						(arc
							(start -0.508 0.2921)
							(mid -0.478242 0.363942)
							(end -0.4064 0.3937)
						)
						(arc
							(start 0.4064 0.3937)
							(mid 0.478242 0.363942)
							(end 0.508 0.2921)
						)
					)
					(width 0)
					(fill yes)
				)
			)
		)
	)
	(footprint ""
		(layer "F.Cu")
		(at 56.007 -36.83 -90)
		(property "Reference" "R101"
			(at 0 0 270)
			(layer "F.SilkS")
			(hide yes)
			(effects
				(font
					(size 1.27 1.27)
				)
			)
		)
		(property "Value" "33R2F-3-GP"
			(at 0.064008 -3.993896 270)
			(unlocked yes)
			(layer "F.Fab")
			(hide yes)
			(effects
				(font
					(size 1.016 1.016)
					(thickness 0.1524)
				)
			)
		)
		(property "Device Type" "R402H16"
			(at 0.064008 -5.517896 270)
			(unlocked yes)
			(layer "F.Fab")
			(hide yes)
			(effects
				(font
					(size 1.016 1.016)
					(thickness 0.1524)
				)
			)
		)
		(duplicate_pad_numbers_are_jumpers no)
		(fp_rect
			(start -0.381 0.8382)
			(end 0.381 -0.8382)
			(stroke
				(width 0)
				(type default)
			)
			(fill no)
			(layer "F.CrtYd")
		)
		(fp_rect
			(start -0.381 0.8382)
			(end 0.381 -0.8382)
			(stroke
				(width 0)
				(type default)
			)
			(fill no)
			(layer "F.Fab")
		)
		(pad "1" smd custom
			(at 0 -0.4318 270)
			(size 0.127 0.127)
			(layers "F.Cu" "F.Mask" "F.Paste")
			(net "SPI_CPU_CS0#")
			(options
				(clearance outline)
				(anchor circle)
			)
			(primitives
				(gr_poly
					(pts
						(arc
							(start -0.2032 -0.2794)
							(mid -0.239121 -0.264521)
							(end -0.254 -0.2286)
						)
						(arc
							(start -0.254 0.2286)
							(mid -0.239121 0.264521)
							(end -0.2032 0.2794)
						)
						(arc
							(start 0.2032 0.2794)
							(mid 0.239121 0.264521)
							(end 0.254 0.2286)
						)
						(arc
							(start 0.254 -0.2286)
							(mid 0.239121 -0.264521)
							(end 0.2032 -0.2794)
						)
					)
					(width 0)
					(fill yes)
				)
			)
		)
		(pad "2" smd custom
			(at 0 0.4318 270)
			(size 0.127 0.127)
			(layers "F.Cu" "F.Mask" "F.Paste")
			(net "SPI_CS0_N_M_1")
			(options
				(clearance outline)
				(anchor circle)
			)
			(primitives
				(gr_poly
					(pts
						(arc
							(start -0.2032 -0.2794)
							(mid -0.239121 -0.264521)
							(end -0.254 -0.2286)
						)
						(arc
							(start -0.254 0.2286)
							(mid -0.239121 0.264521)
							(end -0.2032 0.2794)
						)
						(arc
							(start 0.2032 0.2794)
							(mid 0.239121 0.264521)
							(end 0.254 0.2286)
						)
						(arc
							(start 0.254 -0.2286)
							(mid 0.239121 -0.264521)
							(end 0.2032 -0.2794)
						)
					)
					(width 0)
					(fill yes)
				)
			)
		)
	)
	(footprint ""
		(layer "F.Cu")
		(at 71.374 -40.005)
		(property "Reference" "X1"
			(at 0 0 0)
			(layer "F.SilkS")
			(hide yes)
			(effects
				(font
					(size 1.27 1.27)
				)
			)
		)
		(property "Value" "X-32D768KHZ-56GP"
			(at 0 -5.0292 0)
			(unlocked yes)
			(layer "F.Fab")
			(hide yes)
			(effects
				(font
					(size 1.016 1.016)
					(thickness 0.1524)
				)
			)
		)
		(property "Device Type" "DST310SH34"
			(at 0 -6.5532 0)
			(unlocked yes)
			(layer "F.Fab")
			(hide yes)
			(effects
				(font
					(size 1.016 1.016)
					(thickness 0.1524)
				)
			)
		)
		(duplicate_pad_numbers_are_jumpers no)
		(fp_rect
			(start -1.0033 1.9939)
			(end 1.0033 -1.9939)
			(stroke
				(width 0)
				(type default)
			)
			(fill no)
			(layer "F.CrtYd")
		)
		(fp_rect
			(start -1.0033 1.9939)
			(end 1.0033 -1.9939)
			(stroke
				(width 0)
				(type default)
			)
			(fill no)
			(layer "F.Fab")
		)
		(pad "1" smd rect
			(at 0 -1.230884)
			(size 1.7526 1.27)
			(layers "F.Cu" "F.Mask" "F.Paste")
			(net "RTC_X1PAD")
		)
		(pad "2" smd rect
			(at 0 1.230884)
			(size 1.7526 1.27)
			(layers "F.Cu" "F.Mask" "F.Paste")
			(net "RTC_X2PAD")
		)
	)
	(footprint ""
		(layer "F.Cu")
		(at 42.5196 -39.1414)
		(property "Reference" "C22"
			(at 0 0 0)
			(layer "F.SilkS")
			(hide yes)
			(effects
				(font
					(size 1.27 1.27)
				)
			)
		)
		(property "Value" "SC1U10V2KX-1GP"
			(at 1.8923 -1.2065 0)
			(unlocked yes)
			(layer "F.Fab")
			(hide yes)
			(effects
				(font
					(size 1.016 1.016)
					(thickness 0.1524)
				)
			)
		)
		(property "Device Type" "C402H22"
			(at 1.8923 -2.7305 0)
			(unlocked yes)
			(layer "F.Fab")
			(hide yes)
			(effects
				(font
					(size 1.016 1.016)
					(thickness 0.1524)
				)
			)
		)
		(duplicate_pad_numbers_are_jumpers no)
		(fp_rect
			(start -0.381 0.7366)
			(end 0.381 -0.7366)
			(stroke
				(width 0)
				(type default)
			)
			(fill no)
			(layer "F.CrtYd")
		)
		(fp_rect
			(start -0.381 0.7366)
			(end 0.381 -0.7366)
			(stroke
				(width 0)
				(type default)
			)
			(fill no)
			(layer "F.Fab")
		)
		(pad "1" smd custom
			(at 0 -0.4572)
			(size 0.1143 0.1143)
			(layers "F.Cu" "F.Mask" "F.Paste")
			(net "CLK_GEN_DELAY0_PG")
			(options
				(clearance outline)
				(anchor circle)
			)
			(primitives
				(gr_poly
					(pts
						(arc
							(start -0.254 -0.1778)
							(mid -0.239121 -0.213721)
							(end -0.2032 -0.2286)
						)
						(arc
							(start 0.2032 -0.2286)
							(mid 0.239121 -0.213721)
							(end 0.254 -0.1778)
						)
						(arc
							(start 0.254 0.1778)
							(mid 0.239121 0.213721)
							(end 0.2032 0.2286)
						)
						(arc
							(start -0.2032 0.2286)
							(mid -0.239121 0.213721)
							(end -0.254 0.1778)
						)
					)
					(width 0)
					(fill yes)
				)
			)
		)
		(pad "2" smd custom
			(at 0 0.4572)
			(size 0.1143 0.1143)
			(layers "F.Cu" "F.Mask" "F.Paste")
			(net "GND")
			(options
				(clearance outline)
				(anchor circle)
			)
			(primitives
				(gr_poly
					(pts
						(arc
							(start -0.254 -0.1778)
							(mid -0.239121 -0.213721)
							(end -0.2032 -0.2286)
						)
						(arc
							(start 0.2032 -0.2286)
							(mid 0.239121 -0.213721)
							(end 0.254 -0.1778)
						)
						(arc
							(start 0.254 0.1778)
							(mid 0.239121 0.213721)
							(end 0.2032 0.2286)
						)
						(arc
							(start -0.2032 0.2286)
							(mid -0.239121 0.213721)
							(end -0.254 0.1778)
						)
					)
					(width 0)
					(fill yes)
				)
			)
		)
	)
	(footprint ""
		(layer "F.Cu")
		(at 8.4328 -28.7274 180)
		(property "Reference" "PC85"
			(at 0 0 180)
			(layer "F.SilkS")
			(hide yes)
			(effects
				(font
					(size 1.27 1.27)
				)
			)
		)
		(property "Value" "SC22U25V5MX-GP"
			(at 0 -4.9022 180)
			(unlocked yes)
			(layer "F.Fab")
			(hide yes)
			(effects
				(font
					(size 1.016 1.016)
					(thickness 0.1524)
				)
			)
		)
		(property "Device Type" "C805H58"
			(at 0 -6.8072 180)
			(unlocked yes)
			(layer "F.Fab")
			(hide yes)
			(effects
				(font
					(size 1.016 1.016)
					(thickness 0.1524)
				)
			)
		)
		(duplicate_pad_numbers_are_jumpers no)
		(fp_line
			(start 0.6096 0)
			(end -0.6096 0)
			(stroke
				(width 0.3048)
				(type default)
			)
			(layer "F.SilkS")
		)
		(fp_poly
			(pts
				(xy -0.9017 1.4351) (xy 0.9017 1.4351) (xy 0.9017 -1.4351) (xy -0.9017 -1.4351)
			)
			(stroke
				(width 0)
				(type default)
			)
			(fill no)
			(layer "F.CrtYd")
		)
		(fp_poly
			(pts
				(xy 0.9017 1.4351) (xy 0.9017 -1.4351) (xy -0.9017 -1.4351) (xy -0.9017 1.4351)
			)
			(stroke
				(width 0)
				(type default)
			)
			(fill no)
			(layer "F.Fab")
		)
		(pad "1" smd rect
			(at 0 -0.8382 180)
			(size 1.5494 0.9398)
			(layers "F.Cu" "F.Mask" "F.Paste")
			(net "P1V0_VIN")
		)
		(pad "2" smd rect
			(at 0 0.8382 180)
			(size 1.5494 0.9398)
			(layers "F.Cu" "F.Mask" "F.Paste")
			(net "GND")
		)
	)
	(footprint ""
		(layer "F.Cu")
		(at 129.921 -43.561 180)
		(property "Reference" "C134"
			(at 0 0 180)
			(layer "F.SilkS")
			(hide yes)
			(effects
				(font
					(size 1.27 1.27)
				)
			)
		)
		(property "Value" "SCD1U10V2KX-5GP"
			(at 1.1811 -2.7051 180)
			(unlocked yes)
			(layer "F.Fab")
			(hide yes)
			(effects
				(font
					(size 1.016 1.016)
					(thickness 0.1524)
				)
			)
		)
		(property "Device Type" "C402H22"
			(at 1.1811 -4.2291 180)
			(unlocked yes)
			(layer "F.Fab")
			(hide yes)
			(effects
				(font
					(size 1.016 1.016)
					(thickness 0.1524)
				)
			)
		)
		(duplicate_pad_numbers_are_jumpers no)
		(fp_rect
			(start -0.381 0.7366)
			(end 0.381 -0.7366)
			(stroke
				(width 0)
				(type default)
			)
			(fill no)
			(layer "F.CrtYd")
		)
		(fp_rect
			(start -0.381 0.7366)
			(end 0.381 -0.7366)
			(stroke
				(width 0)
				(type default)
			)
			(fill no)
			(layer "F.Fab")
		)
		(pad "1" smd custom
			(at 0 -0.4572 180)
			(size 0.1143 0.1143)
			(layers "F.Cu" "F.Mask" "F.Paste")
			(net "P3V3_STBY")
			(options
				(clearance outline)
				(anchor circle)
			)
			(primitives
				(gr_poly
					(pts
						(arc
							(start -0.254 -0.1778)
							(mid -0.239121 -0.213721)
							(end -0.2032 -0.2286)
						)
						(arc
							(start 0.2032 -0.2286)
							(mid 0.239121 -0.213721)
							(end 0.254 -0.1778)
						)
						(arc
							(start 0.254 0.1778)
							(mid 0.239121 0.213721)
							(end 0.2032 0.2286)
						)
						(arc
							(start -0.2032 0.2286)
							(mid -0.239121 0.213721)
							(end -0.254 0.1778)
						)
					)
					(width 0)
					(fill yes)
				)
			)
		)
		(pad "2" smd custom
			(at 0 0.4572 180)
			(size 0.1143 0.1143)
			(layers "F.Cu" "F.Mask" "F.Paste")
			(net "GND")
			(options
				(clearance outline)
				(anchor circle)
			)
			(primitives
				(gr_poly
					(pts
						(arc
							(start -0.254 -0.1778)
							(mid -0.239121 -0.213721)
							(end -0.2032 -0.2286)
						)
						(arc
							(start 0.2032 -0.2286)
							(mid 0.239121 -0.213721)
							(end 0.254 -0.1778)
						)
						(arc
							(start 0.254 0.1778)
							(mid 0.239121 0.213721)
							(end 0.2032 0.2286)
						)
						(arc
							(start -0.2032 0.2286)
							(mid -0.239121 0.213721)
							(end -0.254 0.1778)
						)
					)
					(width 0)
					(fill yes)
				)
			)
		)
	)
	(footprint ""
		(layer "F.Cu")
		(at 201.3458 -45.974 180)
		(property "Reference" "PL2"
			(at 0 0 180)
			(layer "F.SilkS")
			(hide yes)
			(effects
				(font
					(size 1.27 1.27)
				)
			)
		)
		(property "Value" "IND-300NH-8-GP"
			(at -4.9403 -2.921 180)
			(unlocked yes)
			(layer "F.Fab")
			(hide yes)
			(effects
				(font
					(size 1.016 1.016)
					(thickness 0.1524)
				)
			)
		)
		(property "Device Type" "L102078-254224H296"
			(at -4.9403 -4.445 180)
			(unlocked yes)
			(layer "F.Fab")
			(hide yes)
			(effects
				(font
					(size 1.016 1.016)
					(thickness 0.1524)
				)
			)
		)
		(duplicate_pad_numbers_are_jumpers no)
		(fp_rect
			(start -4.1529 5.6134)
			(end 4.1529 -5.6134)
			(stroke
				(width 0)
				(type default)
			)
			(fill no)
			(layer "F.CrtYd")
		)
		(fp_rect
			(start -4.1529 5.6134)
			(end 4.1529 -5.6134)
			(stroke
				(width 0)
				(type default)
			)
			(fill no)
			(layer "F.Fab")
		)
		(pad "1" smd rect
			(at 0 -3.893566 180)
			(size 2.4892 3.175)
			(layers "F.Cu" "F.Mask" "F.Paste")
			(net "VR_PVDDR_A_VSW")
		)
		(pad "2" smd rect
			(at 0 3.893566 180)
			(size 2.4892 3.175)
			(layers "F.Cu" "F.Mask" "F.Paste")
			(net "PV_VDDR")
		)
	)
	(footprint ""
		(layer "F.Cu")
		(at 167.894 -23.114 -90)
		(property "Reference" "PR146"
			(at 0 0 270)
			(layer "F.SilkS")
			(hide yes)
			(effects
				(font
					(size 1.27 1.27)
				)
			)
		)
		(property "Value" "0R3J-6-GP"
			(at -0.0254 -2.5146 270)
			(unlocked yes)
			(layer "F.Fab")
			(hide yes)
			(effects
				(font
					(size 1.016 1.016)
					(thickness 0.1524)
				)
			)
		)
		(property "Device Type" "R603H22"
			(at -0.0254 -4.0386 270)
			(unlocked yes)
			(layer "F.Fab")
			(hide yes)
			(effects
				(font
					(size 1.016 1.016)
					(thickness 0.1524)
				)
			)
		)
		(duplicate_pad_numbers_are_jumpers no)
		(fp_line
			(start -0.2032 0)
			(end -0.4191 0)
			(stroke
				(width 0.2032)
				(type default)
			)
			(layer "F.SilkS")
		)
		(fp_line
			(start 0.4318 0)
			(end 0.2032 0)
			(stroke
				(width 0.2032)
				(type default)
			)
			(layer "F.SilkS")
		)
		(fp_rect
			(start -0.635 1.1811)
			(end 0.635 -1.1811)
			(stroke
				(width 0)
				(type default)
			)
			(fill no)
			(layer "F.CrtYd")
		)
		(fp_rect
			(start -0.635 1.1811)
			(end 0.635 -1.1811)
			(stroke
				(width 0)
				(type default)
			)
			(fill no)
			(layer "F.Fab")
		)
		(pad "1" smd custom
			(at 0 -0.6604 270)
			(size 0.19685 0.19685)
			(layers "F.Cu" "F.Mask" "F.Paste")
			(net "P1V8_STBY_LDO_IN2")
			(options
				(clearance outline)
				(anchor circle)
			)
			(primitives
				(gr_poly
					(pts
						(arc
							(start 0.508 -0.2921)
							(mid 0.478242 -0.363942)
							(end 0.4064 -0.3937)
						)
						(arc
							(start -0.4064 -0.3937)
							(mid -0.478242 -0.363942)
							(end -0.508 -0.2921)
						)
						(arc
							(start -0.508 0.2921)
							(mid -0.478242 0.363942)
							(end -0.4064 0.3937)
						)
						(arc
							(start 0.4064 0.3937)
							(mid 0.478242 0.363942)
							(end 0.508 0.2921)
						)
					)
					(width 0)
					(fill yes)
				)
			)
		)
		(pad "2" smd custom
			(at 0 0.6604 270)
			(size 0.19685 0.19685)
			(layers "F.Cu" "F.Mask" "F.Paste")
			(net "P3V3_STBY")
			(options
				(clearance outline)
				(anchor circle)
			)
			(primitives
				(gr_poly
					(pts
						(arc
							(start 0.508 -0.2921)
							(mid 0.478242 -0.363942)
							(end 0.4064 -0.3937)
						)
						(arc
							(start -0.4064 -0.3937)
							(mid -0.478242 -0.363942)
							(end -0.508 -0.2921)
						)
						(arc
							(start -0.508 0.2921)
							(mid -0.478242 0.363942)
							(end -0.4064 0.3937)
						)
						(arc
							(start 0.4064 0.3937)
							(mid 0.478242 0.363942)
							(end 0.508 0.2921)
						)
					)
					(width 0)
					(fill yes)
				)
			)
		)
	)
	(footprint ""
		(layer "F.Cu")
		(at 30.099 -33.02)
		(property "Reference" "C122"
			(at 0 0 0)
			(layer "F.SilkS")
			(hide yes)
			(effects
				(font
					(size 1.27 1.27)
				)
			)
		)
		(property "Value" "SCD1U16V2KX-3GP"
			(at 1.1811 -2.7051 0)
			(unlocked yes)
			(layer "F.Fab")
			(hide yes)
			(effects
				(font
					(size 1.016 1.016)
					(thickness 0.1524)
				)
			)
		)
		(property "Device Type" "C402H22"
			(at 1.1811 -4.2291 0)
			(unlocked yes)
			(layer "F.Fab")
			(hide yes)
			(effects
				(font
					(size 1.016 1.016)
					(thickness 0.1524)
				)
			)
		)
		(duplicate_pad_numbers_are_jumpers no)
		(fp_rect
			(start -0.381 0.7366)
			(end 0.381 -0.7366)
			(stroke
				(width 0)
				(type default)
			)
			(fill no)
			(layer "F.CrtYd")
		)
		(fp_rect
			(start -0.381 0.7366)
			(end 0.381 -0.7366)
			(stroke
				(width 0)
				(type default)
			)
			(fill no)
			(layer "F.Fab")
		)
		(pad "1" smd custom
			(at 0 -0.4572)
			(size 0.1143 0.1143)
			(layers "F.Cu" "F.Mask" "F.Paste")
			(net "GND")
			(options
				(clearance outline)
				(anchor circle)
			)
			(primitives
				(gr_poly
					(pts
						(arc
							(start -0.254 -0.1778)
							(mid -0.239121 -0.213721)
							(end -0.2032 -0.2286)
						)
						(arc
							(start 0.2032 -0.2286)
							(mid 0.239121 -0.213721)
							(end 0.254 -0.1778)
						)
						(arc
							(start 0.254 0.1778)
							(mid 0.239121 0.213721)
							(end 0.2032 0.2286)
						)
						(arc
							(start -0.2032 0.2286)
							(mid -0.239121 0.213721)
							(end -0.254 0.1778)
						)
					)
					(width 0)
					(fill yes)
				)
			)
		)
		(pad "2" smd custom
			(at 0 0.4572)
			(size 0.1143 0.1143)
			(layers "F.Cu" "F.Mask" "F.Paste")
			(net "XDP_CPU_RESET#")
			(options
				(clearance outline)
				(anchor circle)
			)
			(primitives
				(gr_poly
					(pts
						(arc
							(start -0.254 -0.1778)
							(mid -0.239121 -0.213721)
							(end -0.2032 -0.2286)
						)
						(arc
							(start 0.2032 -0.2286)
							(mid 0.239121 -0.213721)
							(end 0.254 -0.1778)
						)
						(arc
							(start 0.254 0.1778)
							(mid 0.239121 0.213721)
							(end 0.2032 0.2286)
						)
						(arc
							(start -0.2032 0.2286)
							(mid -0.239121 0.213721)
							(end -0.254 0.1778)
						)
					)
					(width 0)
					(fill yes)
				)
			)
		)
	)
	(footprint ""
		(layer "F.Cu")
		(at 15.8496 -59.1312 90)
		(property "Reference" "R20"
			(at 0 0 90)
			(layer "F.SilkS")
			(hide yes)
			(effects
				(font
					(size 1.27 1.27)
				)
			)
		)
		(property "Value" "150R2J-L1-GP-U"
			(at 1.7907 -1.1176 90)
			(unlocked yes)
			(layer "F.Fab")
			(hide yes)
			(effects
				(font
					(size 1.016 1.016)
					(thickness 0.1524)
				)
			)
		)
		(property "Device Type" "R402H16"
			(at 1.7907 -2.6416 90)
			(unlocked yes)
			(layer "F.Fab")
			(hide yes)
			(effects
				(font
					(size 1.016 1.016)
					(thickness 0.1524)
				)
			)
		)
		(duplicate_pad_numbers_are_jumpers no)
		(fp_rect
			(start -0.381 0.8382)
			(end 0.381 -0.8382)
			(stroke
				(width 0)
				(type default)
			)
			(fill no)
			(layer "F.CrtYd")
		)
		(fp_rect
			(start -0.381 0.8382)
			(end 0.381 -0.8382)
			(stroke
				(width 0)
				(type default)
			)
			(fill no)
			(layer "F.Fab")
		)
		(pad "1" smd custom
			(at 0 -0.4318 90)
			(size 0.127 0.127)
			(layers "F.Cu" "F.Mask" "F.Paste")
			(net "SVID_CPU_CLK")
			(options
				(clearance outline)
				(anchor circle)
			)
			(primitives
				(gr_poly
					(pts
						(arc
							(start -0.2032 -0.2794)
							(mid -0.239121 -0.264521)
							(end -0.254 -0.2286)
						)
						(arc
							(start -0.254 0.2286)
							(mid -0.239121 0.264521)
							(end -0.2032 0.2794)
						)
						(arc
							(start 0.2032 0.2794)
							(mid 0.239121 0.264521)
							(end 0.254 0.2286)
						)
						(arc
							(start 0.254 -0.2286)
							(mid 0.239121 -0.264521)
							(end 0.2032 -0.2794)
						)
					)
					(width 0)
					(fill yes)
				)
			)
		)
		(pad "2" smd custom
			(at 0 0.4318 90)
			(size 0.127 0.127)
			(layers "F.Cu" "F.Mask" "F.Paste")
			(net "VR_95831_SCLK")
			(options
				(clearance outline)
				(anchor circle)
			)
			(primitives
				(gr_poly
					(pts
						(arc
							(start -0.2032 -0.2794)
							(mid -0.239121 -0.264521)
							(end -0.254 -0.2286)
						)
						(arc
							(start -0.254 0.2286)
							(mid -0.239121 0.264521)
							(end -0.2032 0.2794)
						)
						(arc
							(start 0.2032 0.2794)
							(mid 0.239121 0.264521)
							(end 0.254 0.2286)
						)
						(arc
							(start 0.254 -0.2286)
							(mid 0.239121 -0.264521)
							(end 0.2032 -0.2794)
						)
					)
					(width 0)
					(fill yes)
				)
			)
		)
	)
	(footprint ""
		(layer "F.Cu")
		(at 77.978 -12.827 -90)
		(property "Reference" "R423"
			(at 0 0 270)
			(layer "F.SilkS")
			(hide yes)
			(effects
				(font
					(size 1.27 1.27)
				)
			)
		)
		(property "Value" "0R2J-2-GP"
			(at 1.7907 -1.1176 270)
			(unlocked yes)
			(layer "F.Fab")
			(hide yes)
			(effects
				(font
					(size 1.016 1.016)
					(thickness 0.1524)
				)
			)
		)
		(property "Device Type" "R402H16"
			(at 1.7907 -2.6416 270)
			(unlocked yes)
			(layer "F.Fab")
			(hide yes)
			(effects
				(font
					(size 1.016 1.016)
					(thickness 0.1524)
				)
			)
		)
		(duplicate_pad_numbers_are_jumpers no)
		(fp_rect
			(start -0.381 0.8382)
			(end 0.381 -0.8382)
			(stroke
				(width 0)
				(type default)
			)
			(fill no)
			(layer "F.CrtYd")
		)
		(fp_rect
			(start -0.381 0.8382)
			(end 0.381 -0.8382)
			(stroke
				(width 0)
				(type default)
			)
			(fill no)
			(layer "F.Fab")
		)
		(pad "1" smd custom
			(at 0 -0.4318 270)
			(size 0.127 0.127)
			(layers "F.Cu" "F.Mask" "F.Paste")
			(net "BMC_I2C_ALERT#")
			(options
				(clearance outline)
				(anchor circle)
			)
			(primitives
				(gr_poly
					(pts
						(arc
							(start -0.2032 -0.2794)
							(mid -0.239121 -0.264521)
							(end -0.254 -0.2286)
						)
						(arc
							(start -0.254 0.2286)
							(mid -0.239121 0.264521)
							(end -0.2032 0.2794)
						)
						(arc
							(start 0.2032 0.2794)
							(mid 0.239121 0.264521)
							(end 0.254 0.2286)
						)
						(arc
							(start 0.254 -0.2286)
							(mid 0.239121 -0.264521)
							(end 0.2032 -0.2794)
						)
					)
					(width 0)
					(fill yes)
				)
			)
		)
		(pad "2" smd custom
			(at 0 0.4318 270)
			(size 0.127 0.127)
			(layers "F.Cu" "F.Mask" "F.Paste")
			(net "PCIE_GF_I2C_ALERT#")
			(options
				(clearance outline)
				(anchor circle)
			)
			(primitives
				(gr_poly
					(pts
						(arc
							(start -0.2032 -0.2794)
							(mid -0.239121 -0.264521)
							(end -0.254 -0.2286)
						)
						(arc
							(start -0.254 0.2286)
							(mid -0.239121 0.264521)
							(end -0.2032 0.2794)
						)
						(arc
							(start 0.2032 0.2794)
							(mid 0.239121 0.264521)
							(end 0.254 0.2286)
						)
						(arc
							(start 0.254 -0.2286)
							(mid 0.239121 -0.264521)
							(end 0.2032 -0.2794)
						)
					)
					(width 0)
					(fill yes)
				)
			)
		)
	)
	(footprint ""
		(layer "F.Cu")
		(at 67.564 -57.658)
		(property "Reference" "R476"
			(at 0 0 0)
			(layer "F.SilkS")
			(hide yes)
			(effects
				(font
					(size 1.27 1.27)
				)
			)
		)
		(property "Value" "0R2J-2-GP"
			(at 1.7907 -1.1176 0)
			(unlocked yes)
			(layer "F.Fab")
			(hide yes)
			(effects
				(font
					(size 1.016 1.016)
					(thickness 0.1524)
				)
			)
		)
		(property "Device Type" "R402H16"
			(at 1.7907 -2.6416 0)
			(unlocked yes)
			(layer "F.Fab")
			(hide yes)
			(effects
				(font
					(size 1.016 1.016)
					(thickness 0.1524)
				)
			)
		)
		(duplicate_pad_numbers_are_jumpers no)
		(fp_rect
			(start -0.381 0.8382)
			(end 0.381 -0.8382)
			(stroke
				(width 0)
				(type default)
			)
			(fill no)
			(layer "F.CrtYd")
		)
		(fp_rect
			(start -0.381 0.8382)
			(end 0.381 -0.8382)
			(stroke
				(width 0)
				(type default)
			)
			(fill no)
			(layer "F.Fab")
		)
		(pad "1" smd custom
			(at 0 -0.4318)
			(size 0.127 0.127)
			(layers "F.Cu" "F.Mask" "F.Paste")
			(net "FPGA_SMB_HOST_DATA")
			(options
				(clearance outline)
				(anchor circle)
			)
			(primitives
				(gr_poly
					(pts
						(arc
							(start -0.2032 -0.2794)
							(mid -0.239121 -0.264521)
							(end -0.254 -0.2286)
						)
						(arc
							(start -0.254 0.2286)
							(mid -0.239121 0.264521)
							(end -0.2032 0.2794)
						)
						(arc
							(start 0.2032 0.2794)
							(mid 0.239121 0.264521)
							(end 0.254 0.2286)
						)
						(arc
							(start 0.254 -0.2286)
							(mid 0.239121 -0.264521)
							(end 0.2032 -0.2794)
						)
					)
					(width 0)
					(fill yes)
				)
			)
		)
		(pad "2" smd custom
			(at 0 0.4318)
			(size 0.127 0.127)
			(layers "F.Cu" "F.Mask" "F.Paste")
			(net "FPGA_SMB_HOST_R_DATA")
			(options
				(clearance outline)
				(anchor circle)
			)
			(primitives
				(gr_poly
					(pts
						(arc
							(start -0.2032 -0.2794)
							(mid -0.239121 -0.264521)
							(end -0.254 -0.2286)
						)
						(arc
							(start -0.254 0.2286)
							(mid -0.239121 0.264521)
							(end -0.2032 0.2794)
						)
						(arc
							(start 0.2032 0.2794)
							(mid 0.239121 0.264521)
							(end 0.254 0.2286)
						)
						(arc
							(start 0.254 -0.2286)
							(mid 0.239121 -0.264521)
							(end 0.2032 -0.2794)
						)
					)
					(width 0)
					(fill yes)
				)
			)
		)
	)
	(footprint ""
		(layer "F.Cu")
		(at 56.007 -37.592 -90)
		(property "Reference" "R98"
			(at 0 0 270)
			(layer "F.SilkS")
			(hide yes)
			(effects
				(font
					(size 1.27 1.27)
				)
			)
		)
		(property "Value" "2K2R2F-GP"
			(at 0.064008 -3.993896 270)
			(unlocked yes)
			(layer "F.Fab")
			(hide yes)
			(effects
				(font
					(size 1.016 1.016)
					(thickness 0.1524)
				)
			)
		)
		(property "Device Type" "R402H16"
			(at 0.064008 -5.517896 270)
			(unlocked yes)
			(layer "F.Fab")
			(hide yes)
			(effects
				(font
					(size 1.016 1.016)
					(thickness 0.1524)
				)
			)
		)
		(duplicate_pad_numbers_are_jumpers no)
		(fp_rect
			(start -0.381 0.8382)
			(end 0.381 -0.8382)
			(stroke
				(width 0)
				(type default)
			)
			(fill no)
			(layer "F.CrtYd")
		)
		(fp_rect
			(start -0.381 0.8382)
			(end 0.381 -0.8382)
			(stroke
				(width 0)
				(type default)
			)
			(fill no)
			(layer "F.Fab")
		)
		(pad "1" smd custom
			(at 0 -0.4318 270)
			(size 0.127 0.127)
			(layers "F.Cu" "F.Mask" "F.Paste")
			(net "P3V3_CPU")
			(options
				(clearance outline)
				(anchor circle)
			)
			(primitives
				(gr_poly
					(pts
						(arc
							(start -0.2032 -0.2794)
							(mid -0.239121 -0.264521)
							(end -0.254 -0.2286)
						)
						(arc
							(start -0.254 0.2286)
							(mid -0.239121 0.264521)
							(end -0.2032 0.2794)
						)
						(arc
							(start 0.2032 0.2794)
							(mid 0.239121 0.264521)
							(end 0.254 0.2286)
						)
						(arc
							(start 0.254 -0.2286)
							(mid 0.239121 -0.264521)
							(end 0.2032 -0.2794)
						)
					)
					(width 0)
					(fill yes)
				)
			)
		)
		(pad "2" smd custom
			(at 0 0.4318 270)
			(size 0.127 0.127)
			(layers "F.Cu" "F.Mask" "F.Paste")
			(net "SPI_CS0_N_M_1")
			(options
				(clearance outline)
				(anchor circle)
			)
			(primitives
				(gr_poly
					(pts
						(arc
							(start -0.2032 -0.2794)
							(mid -0.239121 -0.264521)
							(end -0.254 -0.2286)
						)
						(arc
							(start -0.254 0.2286)
							(mid -0.239121 0.264521)
							(end -0.2032 0.2794)
						)
						(arc
							(start 0.2032 0.2794)
							(mid 0.239121 0.264521)
							(end 0.254 0.2286)
						)
						(arc
							(start 0.254 -0.2286)
							(mid 0.239121 -0.264521)
							(end 0.2032 -0.2794)
						)
					)
					(width 0)
					(fill yes)
				)
			)
		)
	)
	(footprint ""
		(layer "F.Cu")
		(at 140.589 -52.1208 -90)
		(property "Reference" "R74"
			(at 0 0 270)
			(layer "F.SilkS")
			(hide yes)
			(effects
				(font
					(size 1.27 1.27)
				)
			)
		)
		(property "Value" "4K7R2F-GP"
			(at 1.7907 -1.1176 270)
			(unlocked yes)
			(layer "F.Fab")
			(hide yes)
			(effects
				(font
					(size 1.016 1.016)
					(thickness 0.1524)
				)
			)
		)
		(property "Device Type" "R402H16"
			(at 1.7907 -2.6416 270)
			(unlocked yes)
			(layer "F.Fab")
			(hide yes)
			(effects
				(font
					(size 1.016 1.016)
					(thickness 0.1524)
				)
			)
		)
		(duplicate_pad_numbers_are_jumpers no)
		(fp_rect
			(start -0.381 0.8382)
			(end 0.381 -0.8382)
			(stroke
				(width 0)
				(type default)
			)
			(fill no)
			(layer "F.CrtYd")
		)
		(fp_rect
			(start -0.381 0.8382)
			(end 0.381 -0.8382)
			(stroke
				(width 0)
				(type default)
			)
			(fill no)
			(layer "F.Fab")
		)
		(pad "1" smd custom
			(at 0 -0.4318 270)
			(size 0.127 0.127)
			(layers "F.Cu" "F.Mask" "F.Paste")
			(net "SPI_SW_ADDR0")
			(options
				(clearance outline)
				(anchor circle)
			)
			(primitives
				(gr_poly
					(pts
						(arc
							(start -0.2032 -0.2794)
							(mid -0.239121 -0.264521)
							(end -0.254 -0.2286)
						)
						(arc
							(start -0.254 0.2286)
							(mid -0.239121 0.264521)
							(end -0.2032 0.2794)
						)
						(arc
							(start 0.2032 0.2794)
							(mid 0.239121 0.264521)
							(end 0.254 0.2286)
						)
						(arc
							(start 0.254 -0.2286)
							(mid 0.239121 -0.264521)
							(end 0.2032 -0.2794)
						)
					)
					(width 0)
					(fill yes)
				)
			)
		)
		(pad "2" smd custom
			(at 0 0.4318 270)
			(size 0.127 0.127)
			(layers "F.Cu" "F.Mask" "F.Paste")
			(net "GND")
			(options
				(clearance outline)
				(anchor circle)
			)
			(primitives
				(gr_poly
					(pts
						(arc
							(start -0.2032 -0.2794)
							(mid -0.239121 -0.264521)
							(end -0.254 -0.2286)
						)
						(arc
							(start -0.254 0.2286)
							(mid -0.239121 0.264521)
							(end -0.2032 0.2794)
						)
						(arc
							(start 0.2032 0.2794)
							(mid 0.239121 0.264521)
							(end 0.254 0.2286)
						)
						(arc
							(start 0.254 -0.2286)
							(mid 0.239121 -0.264521)
							(end 0.2032 -0.2794)
						)
					)
					(width 0)
					(fill yes)
				)
			)
		)
	)
	(footprint ""
		(layer "F.Cu")
		(at 60.3758 -13.8176 -90)
		(property "Reference" "R481"
			(at 0 0 270)
			(layer "F.SilkS")
			(hide yes)
			(effects
				(font
					(size 1.27 1.27)
				)
			)
		)
		(property "Value" "0R2J-2-GP"
			(at 1.7907 -1.1176 270)
			(unlocked yes)
			(layer "F.Fab")
			(hide yes)
			(effects
				(font
					(size 1.016 1.016)
					(thickness 0.1524)
				)
			)
		)
		(property "Device Type" "R402H16"
			(at 1.7907 -2.6416 270)
			(unlocked yes)
			(layer "F.Fab")
			(hide yes)
			(effects
				(font
					(size 1.016 1.016)
					(thickness 0.1524)
				)
			)
		)
		(duplicate_pad_numbers_are_jumpers no)
		(fp_rect
			(start -0.381 0.8382)
			(end 0.381 -0.8382)
			(stroke
				(width 0)
				(type default)
			)
			(fill no)
			(layer "F.CrtYd")
		)
		(fp_rect
			(start -0.381 0.8382)
			(end 0.381 -0.8382)
			(stroke
				(width 0)
				(type default)
			)
			(fill no)
			(layer "F.Fab")
		)
		(pad "1" smd custom
			(at 0 -0.4318 270)
			(size 0.127 0.127)
			(layers "F.Cu" "F.Mask" "F.Paste")
			(net "CPU_RSMRST#")
			(options
				(clearance outline)
				(anchor circle)
			)
			(primitives
				(gr_poly
					(pts
						(arc
							(start -0.2032 -0.2794)
							(mid -0.239121 -0.264521)
							(end -0.254 -0.2286)
						)
						(arc
							(start -0.254 0.2286)
							(mid -0.239121 0.264521)
							(end -0.2032 0.2794)
						)
						(arc
							(start 0.2032 0.2794)
							(mid 0.239121 0.264521)
							(end 0.254 0.2286)
						)
						(arc
							(start 0.254 -0.2286)
							(mid 0.239121 -0.264521)
							(end 0.2032 -0.2794)
						)
					)
					(width 0)
					(fill yes)
				)
			)
		)
		(pad "2" smd custom
			(at 0 0.4318 270)
			(size 0.127 0.127)
			(layers "F.Cu" "F.Mask" "F.Paste")
			(net "GF_GBE_SMB_SW_EN")
			(options
				(clearance outline)
				(anchor circle)
			)
			(primitives
				(gr_poly
					(pts
						(arc
							(start -0.2032 -0.2794)
							(mid -0.239121 -0.264521)
							(end -0.254 -0.2286)
						)
						(arc
							(start -0.254 0.2286)
							(mid -0.239121 0.264521)
							(end -0.2032 0.2794)
						)
						(arc
							(start 0.2032 0.2794)
							(mid 0.239121 0.264521)
							(end 0.254 0.2286)
						)
						(arc
							(start 0.254 -0.2286)
							(mid 0.239121 -0.264521)
							(end 0.2032 -0.2794)
						)
					)
					(width 0)
					(fill yes)
				)
			)
		)
	)
	(footprint ""
		(layer "F.Cu")
		(at 71.882 -18.288 -90)
		(property "Reference" "R442"
			(at 0 0 270)
			(layer "F.SilkS")
			(hide yes)
			(effects
				(font
					(size 1.27 1.27)
				)
			)
		)
		(property "Value" "0R2J-2-GP"
			(at 1.7907 -1.1176 270)
			(unlocked yes)
			(layer "F.Fab")
			(hide yes)
			(effects
				(font
					(size 1.016 1.016)
					(thickness 0.1524)
				)
			)
		)
		(property "Device Type" "R402H16"
			(at 1.7907 -2.6416 270)
			(unlocked yes)
			(layer "F.Fab")
			(hide yes)
			(effects
				(font
					(size 1.016 1.016)
					(thickness 0.1524)
				)
			)
		)
		(duplicate_pad_numbers_are_jumpers no)
		(fp_rect
			(start -0.381 0.8382)
			(end 0.381 -0.8382)
			(stroke
				(width 0)
				(type default)
			)
			(fill no)
			(layer "F.CrtYd")
		)
		(fp_rect
			(start -0.381 0.8382)
			(end 0.381 -0.8382)
			(stroke
				(width 0)
				(type default)
			)
			(fill no)
			(layer "F.Fab")
		)
		(pad "1" smd custom
			(at 0 -0.4318 270)
			(size 0.127 0.127)
			(layers "F.Cu" "F.Mask" "F.Paste")
			(net "CPU_TXD")
			(options
				(clearance outline)
				(anchor circle)
			)
			(primitives
				(gr_poly
					(pts
						(arc
							(start -0.2032 -0.2794)
							(mid -0.239121 -0.264521)
							(end -0.254 -0.2286)
						)
						(arc
							(start -0.254 0.2286)
							(mid -0.239121 0.264521)
							(end -0.2032 0.2794)
						)
						(arc
							(start 0.2032 0.2794)
							(mid 0.239121 0.264521)
							(end 0.254 0.2286)
						)
						(arc
							(start 0.254 -0.2286)
							(mid 0.239121 -0.264521)
							(end 0.2032 -0.2794)
						)
					)
					(width 0)
					(fill yes)
				)
			)
		)
		(pad "2" smd custom
			(at 0 0.4318 270)
			(size 0.127 0.127)
			(layers "F.Cu" "F.Mask" "F.Paste")
			(net "GF_CPU_TXD")
			(options
				(clearance outline)
				(anchor circle)
			)
			(primitives
				(gr_poly
					(pts
						(arc
							(start -0.2032 -0.2794)
							(mid -0.239121 -0.264521)
							(end -0.254 -0.2286)
						)
						(arc
							(start -0.254 0.2286)
							(mid -0.239121 0.264521)
							(end -0.2032 0.2794)
						)
						(arc
							(start 0.2032 0.2794)
							(mid 0.239121 0.264521)
							(end 0.254 0.2286)
						)
						(arc
							(start 0.254 -0.2286)
							(mid 0.239121 -0.264521)
							(end 0.2032 -0.2794)
						)
					)
					(width 0)
					(fill yes)
				)
			)
		)
	)
	(footprint ""
		(layer "F.Cu")
		(at 57.404 -54.356)
		(property "Reference" "PR157"
			(at 0 0 0)
			(layer "F.SilkS")
			(hide yes)
			(effects
				(font
					(size 1.27 1.27)
				)
			)
		)
		(property "Value" "0R2J-2-GP"
			(at 1.7907 -1.1176 0)
			(unlocked yes)
			(layer "F.Fab")
			(hide yes)
			(effects
				(font
					(size 1.016 1.016)
					(thickness 0.1524)
				)
			)
		)
		(property "Device Type" "R402H16"
			(at 1.7907 -2.6416 0)
			(unlocked yes)
			(layer "F.Fab")
			(hide yes)
			(effects
				(font
					(size 1.016 1.016)
					(thickness 0.1524)
				)
			)
		)
		(duplicate_pad_numbers_are_jumpers no)
		(fp_rect
			(start -0.381 0.8382)
			(end 0.381 -0.8382)
			(stroke
				(width 0)
				(type default)
			)
			(fill no)
			(layer "F.CrtYd")
		)
		(fp_rect
			(start -0.381 0.8382)
			(end 0.381 -0.8382)
			(stroke
				(width 0)
				(type default)
			)
			(fill no)
			(layer "F.Fab")
		)
		(pad "1" smd custom
			(at 0 -0.4318)
			(size 0.127 0.127)
			(layers "F.Cu" "F.Mask" "F.Paste")
			(net "VR_FB_R_P1V0_STBY")
			(options
				(clearance outline)
				(anchor circle)
			)
			(primitives
				(gr_poly
					(pts
						(arc
							(start -0.2032 -0.2794)
							(mid -0.239121 -0.264521)
							(end -0.254 -0.2286)
						)
						(arc
							(start -0.254 0.2286)
							(mid -0.239121 0.264521)
							(end -0.2032 0.2794)
						)
						(arc
							(start 0.2032 0.2794)
							(mid 0.239121 0.264521)
							(end 0.254 0.2286)
						)
						(arc
							(start 0.254 -0.2286)
							(mid 0.239121 -0.264521)
							(end 0.2032 -0.2794)
						)
					)
					(width 0)
					(fill yes)
				)
			)
		)
		(pad "2" smd custom
			(at 0 0.4318)
			(size 0.127 0.127)
			(layers "F.Cu" "F.Mask" "F.Paste")
			(net "P1V0_STBY_VOUT")
			(options
				(clearance outline)
				(anchor circle)
			)
			(primitives
				(gr_poly
					(pts
						(arc
							(start -0.2032 -0.2794)
							(mid -0.239121 -0.264521)
							(end -0.254 -0.2286)
						)
						(arc
							(start -0.254 0.2286)
							(mid -0.239121 0.264521)
							(end -0.2032 0.2794)
						)
						(arc
							(start 0.2032 0.2794)
							(mid 0.239121 0.264521)
							(end 0.254 0.2286)
						)
						(arc
							(start 0.254 -0.2286)
							(mid 0.239121 -0.264521)
							(end 0.2032 -0.2794)
						)
					)
					(width 0)
					(fill yes)
				)
			)
		)
	)
	(footprint ""
		(layer "F.Cu")
		(at 70.2818 -46.8376 180)
		(property "Reference" "R62"
			(at 0 0 180)
			(layer "F.SilkS")
			(hide yes)
			(effects
				(font
					(size 1.27 1.27)
				)
			)
		)
		(property "Value" "0R2J-2-GP"
			(at 0.064008 -3.993896 180)
			(unlocked yes)
			(layer "F.Fab")
			(hide yes)
			(effects
				(font
					(size 1.016 1.016)
					(thickness 0.1524)
				)
			)
		)
		(property "Device Type" "R402H16"
			(at 0.064008 -5.517896 180)
			(unlocked yes)
			(layer "F.Fab")
			(hide yes)
			(effects
				(font
					(size 1.016 1.016)
					(thickness 0.1524)
				)
			)
		)
		(duplicate_pad_numbers_are_jumpers no)
		(fp_rect
			(start -0.381 0.8382)
			(end 0.381 -0.8382)
			(stroke
				(width 0)
				(type default)
			)
			(fill no)
			(layer "F.CrtYd")
		)
		(fp_rect
			(start -0.381 0.8382)
			(end 0.381 -0.8382)
			(stroke
				(width 0)
				(type default)
			)
			(fill no)
			(layer "F.Fab")
		)
		(pad "1" smd custom
			(at 0 -0.4318 180)
			(size 0.127 0.127)
			(layers "F.Cu" "F.Mask" "F.Paste")
			(net "SMB_PECI_LV_R_DATA")
			(options
				(clearance outline)
				(anchor circle)
			)
			(primitives
				(gr_poly
					(pts
						(arc
							(start -0.2032 -0.2794)
							(mid -0.239121 -0.264521)
							(end -0.254 -0.2286)
						)
						(arc
							(start -0.254 0.2286)
							(mid -0.239121 0.264521)
							(end -0.2032 0.2794)
						)
						(arc
							(start 0.2032 0.2794)
							(mid 0.239121 0.264521)
							(end 0.254 0.2286)
						)
						(arc
							(start 0.254 -0.2286)
							(mid 0.239121 -0.264521)
							(end 0.2032 -0.2794)
						)
					)
					(width 0)
					(fill yes)
				)
			)
		)
		(pad "2" smd custom
			(at 0 0.4318 180)
			(size 0.127 0.127)
			(layers "F.Cu" "F.Mask" "F.Paste")
			(net "SMB_PECI_LV_DATA")
			(options
				(clearance outline)
				(anchor circle)
			)
			(primitives
				(gr_poly
					(pts
						(arc
							(start -0.2032 -0.2794)
							(mid -0.239121 -0.264521)
							(end -0.254 -0.2286)
						)
						(arc
							(start -0.254 0.2286)
							(mid -0.239121 0.264521)
							(end -0.2032 0.2794)
						)
						(arc
							(start 0.2032 0.2794)
							(mid 0.239121 0.264521)
							(end 0.254 0.2286)
						)
						(arc
							(start 0.254 -0.2286)
							(mid 0.239121 -0.264521)
							(end 0.2032 -0.2794)
						)
					)
					(width 0)
					(fill yes)
				)
			)
		)
	)
	(footprint ""
		(layer "F.Cu")
		(at 204.7748 -26.162 90)
		(property "Reference" "TP18"
			(at 0 0 90)
			(layer "F.SilkS")
			(hide yes)
			(effects
				(font
					(size 1.27 1.27)
				)
			)
		)
		(property "Value" "TPAD32-GP"
			(at 0 -3.166364 90)
			(unlocked yes)
			(layer "F.Fab")
			(hide yes)
			(effects
				(font
					(size 1.016 1.016)
					(thickness 0.1524)
				)
			)
		)
		(property "Device Type" "TPAD32"
			(at 0 -4.690618 90)
			(unlocked yes)
			(layer "F.Fab")
			(hide yes)
			(effects
				(font
					(size 1.016 1.016)
					(thickness 0.1524)
				)
			)
		)
		(duplicate_pad_numbers_are_jumpers no)
		(fp_poly
			(pts
				(arc
					(start 0 0.7112)
					(mid 0 -0.7112)
					(end 0 0.7112)
				)
			)
			(stroke
				(width 0)
				(type default)
			)
			(fill no)
			(layer "F.CrtYd")
		)
		(fp_poly
			(pts
				(arc
					(start 0 0.7112)
					(mid 0 -0.7112)
					(end 0 0.7112)
				)
			)
			(stroke
				(width 0)
				(type default)
			)
			(fill no)
			(layer "F.Fab")
		)
		(pad "1" smd circle
			(at 0 0 90)
			(size 0.8128 0.8128)
			(layers "F.Cu" "F.Mask" "F.Paste")
			(net "JTAG_PLD_TCK")
		)
	)
	(footprint ""
		(layer "F.Cu")
		(at 169.926 -43.561 -90)
		(property "Reference" "PC211"
			(at 0 0 270)
			(layer "F.SilkS")
			(hide yes)
			(effects
				(font
					(size 1.27 1.27)
				)
			)
		)
		(property "Value" "SCD01U16V2KX-3GP"
			(at 1.8923 -1.2065 270)
			(unlocked yes)
			(layer "F.Fab")
			(hide yes)
			(effects
				(font
					(size 1.016 1.016)
					(thickness 0.1524)
				)
			)
		)
		(property "Device Type" "C402H22"
			(at 1.8923 -2.7305 270)
			(unlocked yes)
			(layer "F.Fab")
			(hide yes)
			(effects
				(font
					(size 1.016 1.016)
					(thickness 0.1524)
				)
			)
		)
		(duplicate_pad_numbers_are_jumpers no)
		(fp_rect
			(start -0.381 0.7366)
			(end 0.381 -0.7366)
			(stroke
				(width 0)
				(type default)
			)
			(fill no)
			(layer "F.CrtYd")
		)
		(fp_rect
			(start -0.381 0.7366)
			(end 0.381 -0.7366)
			(stroke
				(width 0)
				(type default)
			)
			(fill no)
			(layer "F.Fab")
		)
		(pad "1" smd custom
			(at 0 -0.4572 270)
			(size 0.1143 0.1143)
			(layers "F.Cu" "F.Mask" "F.Paste")
			(net "P2V5_STBY_BYPASS")
			(options
				(clearance outline)
				(anchor circle)
			)
			(primitives
				(gr_poly
					(pts
						(arc
							(start -0.254 -0.1778)
							(mid -0.239121 -0.213721)
							(end -0.2032 -0.2286)
						)
						(arc
							(start 0.2032 -0.2286)
							(mid 0.239121 -0.213721)
							(end 0.254 -0.1778)
						)
						(arc
							(start 0.254 0.1778)
							(mid 0.239121 0.213721)
							(end 0.2032 0.2286)
						)
						(arc
							(start -0.2032 0.2286)
							(mid -0.239121 0.213721)
							(end -0.254 0.1778)
						)
					)
					(width 0)
					(fill yes)
				)
			)
		)
		(pad "2" smd custom
			(at 0 0.4572 270)
			(size 0.1143 0.1143)
			(layers "F.Cu" "F.Mask" "F.Paste")
			(net "GND")
			(options
				(clearance outline)
				(anchor circle)
			)
			(primitives
				(gr_poly
					(pts
						(arc
							(start -0.254 -0.1778)
							(mid -0.239121 -0.213721)
							(end -0.2032 -0.2286)
						)
						(arc
							(start 0.2032 -0.2286)
							(mid 0.239121 -0.213721)
							(end 0.254 -0.1778)
						)
						(arc
							(start 0.254 0.1778)
							(mid 0.239121 0.213721)
							(end 0.2032 0.2286)
						)
						(arc
							(start -0.2032 0.2286)
							(mid -0.239121 0.213721)
							(end -0.254 0.1778)
						)
					)
					(width 0)
					(fill yes)
				)
			)
		)
	)
	(footprint ""
		(layer "F.Cu")
		(at 18.6944 -67.134486 180)
		(property "Reference" "PC16"
			(at 0 0 180)
			(layer "F.SilkS")
			(hide yes)
			(effects
				(font
					(size 1.27 1.27)
				)
			)
		)
		(property "Value" "SCD022U16V2KX-3GP"
			(at 1.8923 -1.2065 180)
			(unlocked yes)
			(layer "F.Fab")
			(hide yes)
			(effects
				(font
					(size 1.016 1.016)
					(thickness 0.1524)
				)
			)
		)
		(property "Device Type" "C402H22"
			(at 1.8923 -2.7305 180)
			(unlocked yes)
			(layer "F.Fab")
			(hide yes)
			(effects
				(font
					(size 1.016 1.016)
					(thickness 0.1524)
				)
			)
		)
		(duplicate_pad_numbers_are_jumpers no)
		(fp_rect
			(start -0.381 0.7366)
			(end 0.381 -0.7366)
			(stroke
				(width 0)
				(type default)
			)
			(fill no)
			(layer "F.CrtYd")
		)
		(fp_rect
			(start -0.381 0.7366)
			(end 0.381 -0.7366)
			(stroke
				(width 0)
				(type default)
			)
			(fill no)
			(layer "F.Fab")
		)
		(pad "1" smd custom
			(at 0 -0.4572 180)
			(size 0.1143 0.1143)
			(layers "F.Cu" "F.Mask" "F.Paste")
			(net "VR_PVNN_ISUMN")
			(options
				(clearance outline)
				(anchor circle)
			)
			(primitives
				(gr_poly
					(pts
						(arc
							(start -0.254 -0.1778)
							(mid -0.239121 -0.213721)
							(end -0.2032 -0.2286)
						)
						(arc
							(start 0.2032 -0.2286)
							(mid 0.239121 -0.213721)
							(end 0.254 -0.1778)
						)
						(arc
							(start 0.254 0.1778)
							(mid 0.239121 0.213721)
							(end 0.2032 0.2286)
						)
						(arc
							(start -0.2032 0.2286)
							(mid -0.239121 0.213721)
							(end -0.254 0.1778)
						)
					)
					(width 0)
					(fill yes)
				)
			)
		)
		(pad "2" smd custom
			(at 0 0.4572 180)
			(size 0.1143 0.1143)
			(layers "F.Cu" "F.Mask" "F.Paste")
			(net "VR_PVNN_ISUMP")
			(options
				(clearance outline)
				(anchor circle)
			)
			(primitives
				(gr_poly
					(pts
						(arc
							(start -0.254 -0.1778)
							(mid -0.239121 -0.213721)
							(end -0.2032 -0.2286)
						)
						(arc
							(start 0.2032 -0.2286)
							(mid 0.239121 -0.213721)
							(end 0.254 -0.1778)
						)
						(arc
							(start 0.254 0.1778)
							(mid 0.239121 0.213721)
							(end 0.2032 0.2286)
						)
						(arc
							(start -0.2032 0.2286)
							(mid -0.239121 0.213721)
							(end -0.254 0.1778)
						)
					)
					(width 0)
					(fill yes)
				)
			)
		)
	)
	(footprint ""
		(layer "F.Cu")
		(at 20.0914 -23.4442 180)
		(property "Reference" "PR79"
			(at 0 0 180)
			(layer "F.SilkS")
			(hide yes)
			(effects
				(font
					(size 1.27 1.27)
				)
			)
		)
		(property "Value" "0R5J-5-GP"
			(at 0 -4.9022 180)
			(unlocked yes)
			(layer "F.Fab")
			(hide yes)
			(effects
				(font
					(size 1.016 1.016)
					(thickness 0.1524)
				)
			)
		)
		(property "Device Type" "R805H24"
			(at 0 -6.8072 180)
			(unlocked yes)
			(layer "F.Fab")
			(hide yes)
			(effects
				(font
					(size 1.016 1.016)
					(thickness 0.1524)
				)
			)
		)
		(duplicate_pad_numbers_are_jumpers no)
		(fp_line
			(start 0.6096 0)
			(end 0.2794 0)
			(stroke
				(width 0.3048)
				(type default)
			)
			(layer "F.SilkS")
		)
		(fp_line
			(start -0.2794 0)
			(end -0.6096 0)
			(stroke
				(width 0.3048)
				(type default)
			)
			(layer "F.SilkS")
		)
		(fp_poly
			(pts
				(xy -0.9017 1.4351) (xy 0.9017 1.4351) (xy 0.9017 -1.4351) (xy -0.9017 -1.4351)
			)
			(stroke
				(width 0)
				(type default)
			)
			(fill no)
			(layer "F.CrtYd")
		)
		(fp_poly
			(pts
				(xy 0.9017 1.4351) (xy 0.9017 -1.4351) (xy -0.9017 -1.4351) (xy -0.9017 1.4351)
			)
			(stroke
				(width 0)
				(type default)
			)
			(fill no)
			(layer "F.Fab")
		)
		(pad "1" smd rect
			(at 0 -0.8382 180)
			(size 1.5494 0.9398)
			(layers "F.Cu" "F.Mask" "F.Paste")
			(net "P1V0_VBST_RC")
		)
		(pad "2" smd rect
			(at 0 0.8382 180)
			(size 1.5494 0.9398)
			(layers "F.Cu" "F.Mask" "F.Paste")
			(net "P1V0_LX")
		)
	)
	(footprint ""
		(layer "F.Cu")
		(at 8.509 -56.515 90)
		(property "Reference" "C47"
			(at 0 0 90)
			(layer "F.SilkS")
			(hide yes)
			(effects
				(font
					(size 1.27 1.27)
				)
			)
		)
		(property "Value" "SCD1U16V2KX-3GP"
			(at 1.1811 -2.7051 90)
			(unlocked yes)
			(layer "F.Fab")
			(hide yes)
			(effects
				(font
					(size 1.016 1.016)
					(thickness 0.1524)
				)
			)
		)
		(property "Device Type" "C402H22"
			(at 1.1811 -4.2291 90)
			(unlocked yes)
			(layer "F.Fab")
			(hide yes)
			(effects
				(font
					(size 1.016 1.016)
					(thickness 0.1524)
				)
			)
		)
		(duplicate_pad_numbers_are_jumpers no)
		(fp_rect
			(start -0.381 0.7366)
			(end 0.381 -0.7366)
			(stroke
				(width 0)
				(type default)
			)
			(fill no)
			(layer "F.CrtYd")
		)
		(fp_rect
			(start -0.381 0.7366)
			(end 0.381 -0.7366)
			(stroke
				(width 0)
				(type default)
			)
			(fill no)
			(layer "F.Fab")
		)
		(pad "1" smd custom
			(at 0 -0.4572 90)
			(size 0.1143 0.1143)
			(layers "F.Cu" "F.Mask" "F.Paste")
			(net "P2E_CPU_NGFF_TX_DN13")
			(options
				(clearance outline)
				(anchor circle)
			)
			(primitives
				(gr_poly
					(pts
						(arc
							(start -0.254 -0.1778)
							(mid -0.239121 -0.213721)
							(end -0.2032 -0.2286)
						)
						(arc
							(start 0.2032 -0.2286)
							(mid 0.239121 -0.213721)
							(end 0.254 -0.1778)
						)
						(arc
							(start 0.254 0.1778)
							(mid 0.239121 0.213721)
							(end 0.2032 0.2286)
						)
						(arc
							(start -0.2032 0.2286)
							(mid -0.239121 0.213721)
							(end -0.254 0.1778)
						)
					)
					(width 0)
					(fill yes)
				)
			)
		)
		(pad "2" smd custom
			(at 0 0.4572 90)
			(size 0.1143 0.1143)
			(layers "F.Cu" "F.Mask" "F.Paste")
			(net "P2E_CPU_NGFF_C_TX_DN13")
			(options
				(clearance outline)
				(anchor circle)
			)
			(primitives
				(gr_poly
					(pts
						(arc
							(start -0.254 -0.1778)
							(mid -0.239121 -0.213721)
							(end -0.2032 -0.2286)
						)
						(arc
							(start 0.2032 -0.2286)
							(mid 0.239121 -0.213721)
							(end 0.254 -0.1778)
						)
						(arc
							(start 0.254 0.1778)
							(mid 0.239121 0.213721)
							(end 0.2032 0.2286)
						)
						(arc
							(start -0.2032 0.2286)
							(mid -0.239121 0.213721)
							(end -0.254 0.1778)
						)
					)
					(width 0)
					(fill yes)
				)
			)
		)
	)
	(footprint ""
		(layer "F.Cu")
		(at 156.718 -22.098)
		(property "Reference" "TP21"
			(at 0 0 0)
			(layer "F.SilkS")
			(hide yes)
			(effects
				(font
					(size 1.27 1.27)
				)
			)
		)
		(property "Value" "TPAD28-1-GP-U"
			(at 0.0508 -1.9304 0)
			(unlocked yes)
			(layer "F.Fab")
			(hide yes)
			(effects
				(font
					(size 1.016 1.016)
					(thickness 0.1524)
				)
			)
		)
		(property "Device Type" "TPAD28-1-U"
			(at 0.0508 -3.4544 0)
			(unlocked yes)
			(layer "F.Fab")
			(hide yes)
			(effects
				(font
					(size 1.016 1.016)
					(thickness 0.1524)
				)
			)
		)
		(duplicate_pad_numbers_are_jumpers no)
		(fp_poly
			(pts
				(arc
					(start 0.3556 0)
					(mid -0.3556 0)
					(end 0.3556 0)
				)
			)
			(stroke
				(width 0)
				(type default)
			)
			(fill no)
			(layer "F.CrtYd")
		)
		(fp_poly
			(pts
				(arc
					(start 0.9525 0)
					(mid -0.9525 0)
					(end 0.9525 0)
				)
			)
			(stroke
				(width 0)
				(type default)
			)
			(fill no)
			(layer "F.Fab")
		)
		(pad "1" smd circle
			(at 0 0)
			(size 0.7112 0.7112)
			(layers "F.Cu" "F.Mask" "F.Paste")
			(net "TP_FPGA_P111")
		)
	)
	(footprint ""
		(layer "F.Cu")
		(at 184.15 -53.848 180)
		(property "Reference" "R203"
			(at 0 0 180)
			(layer "F.SilkS")
			(hide yes)
			(effects
				(font
					(size 1.27 1.27)
				)
			)
		)
		(property "Value" "100R2F-L1-GP-U"
			(at 0.064008 -3.993896 180)
			(unlocked yes)
			(layer "F.Fab")
			(hide yes)
			(effects
				(font
					(size 1.016 1.016)
					(thickness 0.1524)
				)
			)
		)
		(property "Device Type" "R402H14"
			(at 0.064008 -5.517896 180)
			(unlocked yes)
			(layer "F.Fab")
			(hide yes)
			(effects
				(font
					(size 1.016 1.016)
					(thickness 0.1524)
				)
			)
		)
		(duplicate_pad_numbers_are_jumpers no)
		(fp_rect
			(start -0.381 0.8382)
			(end 0.381 -0.8382)
			(stroke
				(width 0)
				(type default)
			)
			(fill no)
			(layer "F.CrtYd")
		)
		(fp_rect
			(start -0.381 0.8382)
			(end 0.381 -0.8382)
			(stroke
				(width 0)
				(type default)
			)
			(fill no)
			(layer "F.Fab")
		)
		(pad "1" smd custom
			(at 0 -0.4318 180)
			(size 0.127 0.127)
			(layers "F.Cu" "F.Mask" "F.Paste")
			(net "PV_VDDR_VREF_A_FB")
			(options
				(clearance outline)
				(anchor circle)
			)
			(primitives
				(gr_poly
					(pts
						(arc
							(start -0.2032 -0.2794)
							(mid -0.239121 -0.264521)
							(end -0.254 -0.2286)
						)
						(arc
							(start -0.254 0.2286)
							(mid -0.239121 0.264521)
							(end -0.2032 0.2794)
						)
						(arc
							(start 0.2032 0.2794)
							(mid 0.239121 0.264521)
							(end 0.254 0.2286)
						)
						(arc
							(start 0.254 -0.2286)
							(mid 0.239121 -0.264521)
							(end 0.2032 -0.2794)
						)
					)
					(width 0)
					(fill yes)
				)
			)
		)
		(pad "2" smd custom
			(at 0 0.4318 180)
			(size 0.127 0.127)
			(layers "F.Cu" "F.Mask" "F.Paste")
			(net "GND")
			(options
				(clearance outline)
				(anchor circle)
			)
			(primitives
				(gr_poly
					(pts
						(arc
							(start -0.2032 -0.2794)
							(mid -0.239121 -0.264521)
							(end -0.254 -0.2286)
						)
						(arc
							(start -0.254 0.2286)
							(mid -0.239121 0.264521)
							(end -0.2032 0.2794)
						)
						(arc
							(start 0.2032 0.2794)
							(mid 0.239121 0.264521)
							(end 0.254 0.2286)
						)
						(arc
							(start 0.254 -0.2286)
							(mid 0.239121 -0.264521)
							(end 0.2032 -0.2794)
						)
					)
					(width 0)
					(fill yes)
				)
			)
		)
	)
	(footprint ""
		(layer "F.Cu")
		(at 50.038 -41.021 90)
		(property "Reference" "Q4"
			(at 0 0 90)
			(layer "F.SilkS")
			(hide yes)
			(effects
				(font
					(size 1.27 1.27)
				)
			)
		)
		(property "Value" "AO4406AL-GP"
			(at -3.707384 -1.5367 90)
			(unlocked yes)
			(layer "F.Fab")
			(hide yes)
			(effects
				(font
					(size 1.016 1.016)
					(thickness 0.1524)
				)
			)
		)
		(property "Device Type" "SOIC8H69"
			(at -3.707384 -3.0607 90)
			(unlocked yes)
			(layer "F.Fab")
			(hide yes)
			(effects
				(font
					(size 1.016 1.016)
					(thickness 0.1524)
				)
			)
		)
		(duplicate_pad_numbers_are_jumpers no)
		(fp_line
			(start 2.1463 -1.4351)
			(end -2.6797 -1.4351)
			(stroke
				(width 0.1524)
				(type default)
			)
			(layer "F.SilkS")
		)
		(fp_line
			(start -2.6797 -1.4351)
			(end -2.6797 1.4351)
			(stroke
				(width 0.1524)
				(type default)
			)
			(layer "F.SilkS")
		)
		(fp_line
			(start -2.6797 -0.508)
			(end -2.6797 0.508)
			(stroke
				(width 0.1524)
				(type default)
			)
			(layer "F.SilkS")
		)
		(fp_line
			(start -2.1717 0)
			(end -2.6797 -0.508)
			(stroke
				(width 0.1524)
				(type default)
			)
			(layer "F.SilkS")
		)
		(fp_line
			(start -2.6797 0.508)
			(end -2.1717 0)
			(stroke
				(width 0.1524)
				(type default)
			)
			(layer "F.SilkS")
		)
		(fp_line
			(start -2.502154 1.4224)
			(end -2.502154 3.1115)
			(stroke
				(width 0.508)
				(type default)
			)
			(layer "F.SilkS")
		)
		(fp_line
			(start 2.1463 1.4351)
			(end 2.1463 -1.4351)
			(stroke
				(width 0.1524)
				(type default)
			)
			(layer "F.SilkS")
		)
		(fp_line
			(start -2.6797 1.4351)
			(end 2.1463 1.4351)
			(stroke
				(width 0.1524)
				(type default)
			)
			(layer "F.SilkS")
		)
		(fp_poly
			(pts
				(xy -2.2225 -1.4351) (xy -2.2225 1.4351) (xy 2.1463 1.4351) (xy 2.1463 -1.4351)
			)
			(stroke
				(width 0)
				(type default)
			)
			(fill yes)
			(layer "F.SilkS")
		)
		(fp_rect
			(start -2.7559 3.3655)
			(end 2.7559 -3.3655)
			(stroke
				(width 0)
				(type default)
			)
			(fill no)
			(layer "F.CrtYd")
		)
		(fp_rect
			(start -2.7559 3.3655)
			(end 2.7559 -3.3655)
			(stroke
				(width 0)
				(type default)
			)
			(fill no)
			(layer "F.Fab")
		)
		(pad "1" smd rect
			(at -1.905 2.4765 90)
			(size 0.635 1.524)
			(layers "F.Cu" "F.Mask" "F.Paste")
			(net "P3V3")
		)
		(pad "2" smd rect
			(at -0.635 2.4765 90)
			(size 0.635 1.524)
			(layers "F.Cu" "F.Mask" "F.Paste")
			(net "P3V3")
		)
		(pad "3" smd rect
			(at 0.635 2.4765 90)
			(size 0.635 1.524)
			(layers "F.Cu" "F.Mask" "F.Paste")
			(net "P3V3")
		)
		(pad "4" smd rect
			(at 1.905 2.4765 90)
			(size 0.635 1.524)
			(layers "F.Cu" "F.Mask" "F.Paste")
			(net "SW_P3V3_EN_LV_D")
		)
		(pad "5" smd rect
			(at 1.905 -2.4765 90)
			(size 0.635 1.524)
			(layers "F.Cu" "F.Mask" "F.Paste")
			(net "P3V3_STBY")
		)
		(pad "6" smd rect
			(at 0.635 -2.4765 90)
			(size 0.635 1.524)
			(layers "F.Cu" "F.Mask" "F.Paste")
			(net "P3V3_STBY")
		)
		(pad "7" smd rect
			(at -0.635 -2.4765 90)
			(size 0.635 1.524)
			(layers "F.Cu" "F.Mask" "F.Paste")
			(net "P3V3_STBY")
		)
		(pad "8" smd rect
			(at -1.905 -2.4765 90)
			(size 0.635 1.524)
			(layers "F.Cu" "F.Mask" "F.Paste")
			(net "P3V3_STBY")
		)
	)
	(footprint ""
		(layer "F.Cu")
		(at 72.263 -42.926)
		(property "Reference" "R55"
			(at 0 0 0)
			(layer "F.SilkS")
			(hide yes)
			(effects
				(font
					(size 1.27 1.27)
				)
			)
		)
		(property "Value" "0R2J-2-GP"
			(at 1.7907 -1.1176 0)
			(unlocked yes)
			(layer "F.Fab")
			(hide yes)
			(effects
				(font
					(size 1.016 1.016)
					(thickness 0.1524)
				)
			)
		)
		(property "Device Type" "R402H16"
			(at 1.7907 -2.6416 0)
			(unlocked yes)
			(layer "F.Fab")
			(hide yes)
			(effects
				(font
					(size 1.016 1.016)
					(thickness 0.1524)
				)
			)
		)
		(duplicate_pad_numbers_are_jumpers no)
		(fp_rect
			(start -0.381 0.8382)
			(end 0.381 -0.8382)
			(stroke
				(width 0)
				(type default)
			)
			(fill no)
			(layer "F.CrtYd")
		)
		(fp_rect
			(start -0.381 0.8382)
			(end 0.381 -0.8382)
			(stroke
				(width 0)
				(type default)
			)
			(fill no)
			(layer "F.Fab")
		)
		(pad "1" smd custom
			(at 0 -0.4318)
			(size 0.127 0.127)
			(layers "F.Cu" "F.Mask" "F.Paste")
			(net "SMBUS_SW_R_EN")
			(options
				(clearance outline)
				(anchor circle)
			)
			(primitives
				(gr_poly
					(pts
						(arc
							(start -0.2032 -0.2794)
							(mid -0.239121 -0.264521)
							(end -0.254 -0.2286)
						)
						(arc
							(start -0.254 0.2286)
							(mid -0.239121 0.264521)
							(end -0.2032 0.2794)
						)
						(arc
							(start 0.2032 0.2794)
							(mid 0.239121 0.264521)
							(end 0.254 0.2286)
						)
						(arc
							(start 0.254 -0.2286)
							(mid 0.239121 -0.264521)
							(end 0.2032 -0.2794)
						)
					)
					(width 0)
					(fill yes)
				)
			)
		)
		(pad "2" smd custom
			(at 0 0.4318)
			(size 0.127 0.127)
			(layers "F.Cu" "F.Mask" "F.Paste")
			(net "SMBUS_SW_EN")
			(options
				(clearance outline)
				(anchor circle)
			)
			(primitives
				(gr_poly
					(pts
						(arc
							(start -0.2032 -0.2794)
							(mid -0.239121 -0.264521)
							(end -0.254 -0.2286)
						)
						(arc
							(start -0.254 0.2286)
							(mid -0.239121 0.264521)
							(end -0.2032 0.2794)
						)
						(arc
							(start 0.2032 0.2794)
							(mid 0.239121 0.264521)
							(end 0.254 0.2286)
						)
						(arc
							(start 0.254 -0.2286)
							(mid 0.239121 -0.264521)
							(end 0.2032 -0.2794)
						)
					)
					(width 0)
					(fill yes)
				)
			)
		)
	)
	(footprint ""
		(layer "F.Cu")
		(at 128.27 -39.37 -90)
		(property "Reference" "C13"
			(at 0 0 270)
			(layer "F.SilkS")
			(hide yes)
			(effects
				(font
					(size 1.27 1.27)
				)
			)
		)
		(property "Value" "SCD1U10V2KX-5GP"
			(at 1.1811 -2.7051 270)
			(unlocked yes)
			(layer "F.Fab")
			(hide yes)
			(effects
				(font
					(size 1.016 1.016)
					(thickness 0.1524)
				)
			)
		)
		(property "Device Type" "C402H22"
			(at 1.1811 -4.2291 270)
			(unlocked yes)
			(layer "F.Fab")
			(hide yes)
			(effects
				(font
					(size 1.016 1.016)
					(thickness 0.1524)
				)
			)
		)
		(duplicate_pad_numbers_are_jumpers no)
		(fp_rect
			(start -0.381 0.7366)
			(end 0.381 -0.7366)
			(stroke
				(width 0)
				(type default)
			)
			(fill no)
			(layer "F.CrtYd")
		)
		(fp_rect
			(start -0.381 0.7366)
			(end 0.381 -0.7366)
			(stroke
				(width 0)
				(type default)
			)
			(fill no)
			(layer "F.Fab")
		)
		(pad "1" smd custom
			(at 0 -0.4572 270)
			(size 0.1143 0.1143)
			(layers "F.Cu" "F.Mask" "F.Paste")
			(net "P1V2_FPGA_D")
			(options
				(clearance outline)
				(anchor circle)
			)
			(primitives
				(gr_poly
					(pts
						(arc
							(start -0.254 -0.1778)
							(mid -0.239121 -0.213721)
							(end -0.2032 -0.2286)
						)
						(arc
							(start 0.2032 -0.2286)
							(mid 0.239121 -0.213721)
							(end 0.254 -0.1778)
						)
						(arc
							(start 0.254 0.1778)
							(mid 0.239121 0.213721)
							(end 0.2032 0.2286)
						)
						(arc
							(start -0.2032 0.2286)
							(mid -0.239121 0.213721)
							(end -0.254 0.1778)
						)
					)
					(width 0)
					(fill yes)
				)
			)
		)
		(pad "2" smd custom
			(at 0 0.4572 270)
			(size 0.1143 0.1143)
			(layers "F.Cu" "F.Mask" "F.Paste")
			(net "GND")
			(options
				(clearance outline)
				(anchor circle)
			)
			(primitives
				(gr_poly
					(pts
						(arc
							(start -0.254 -0.1778)
							(mid -0.239121 -0.213721)
							(end -0.2032 -0.2286)
						)
						(arc
							(start 0.2032 -0.2286)
							(mid 0.239121 -0.213721)
							(end 0.254 -0.1778)
						)
						(arc
							(start 0.254 0.1778)
							(mid 0.239121 0.213721)
							(end 0.2032 0.2286)
						)
						(arc
							(start -0.2032 0.2286)
							(mid -0.239121 0.213721)
							(end -0.254 0.1778)
						)
					)
					(width 0)
					(fill yes)
				)
			)
		)
	)
	(footprint ""
		(layer "F.Cu")
		(at 96.393 -68.58 180)
		(property "Reference" "TP2"
			(at 0 0 180)
			(layer "F.SilkS")
			(hide yes)
			(effects
				(font
					(size 1.27 1.27)
				)
			)
		)
		(property "Value" "TPAD28-1-GP-U"
			(at 0.0508 -1.9304 180)
			(unlocked yes)
			(layer "F.Fab")
			(hide yes)
			(effects
				(font
					(size 1.016 1.016)
					(thickness 0.1524)
				)
			)
		)
		(property "Device Type" "TPAD28-1-U"
			(at 0.0508 -3.4544 180)
			(unlocked yes)
			(layer "F.Fab")
			(hide yes)
			(effects
				(font
					(size 1.016 1.016)
					(thickness 0.1524)
				)
			)
		)
		(duplicate_pad_numbers_are_jumpers no)
		(fp_poly
			(pts
				(arc
					(start -0.3556 0)
					(mid 0.3556 0)
					(end -0.3556 0)
				)
			)
			(stroke
				(width 0)
				(type default)
			)
			(fill no)
			(layer "F.CrtYd")
		)
		(fp_poly
			(pts
				(arc
					(start -0.9525 0)
					(mid 0.9525 0)
					(end -0.9525 0)
				)
			)
			(stroke
				(width 0)
				(type default)
			)
			(fill no)
			(layer "F.Fab")
		)
		(pad "1" smd circle
			(at 0 0 180)
			(size 0.7112 0.7112)
			(layers "F.Cu" "F.Mask" "F.Paste")
			(net "TP_VDDB")
		)
	)
	(footprint ""
		(layer "F.Cu")
		(at 182.372 -36.068 180)
		(property "Reference" "PR135"
			(at 0 0 180)
			(layer "F.SilkS")
			(hide yes)
			(effects
				(font
					(size 1.27 1.27)
				)
			)
		)
		(property "Value" "5K11R2F-L1-GP"
			(at 1.7907 -1.1176 180)
			(unlocked yes)
			(layer "F.Fab")
			(hide yes)
			(effects
				(font
					(size 1.016 1.016)
					(thickness 0.1524)
				)
			)
		)
		(property "Device Type" "R402H16"
			(at 1.7907 -2.6416 180)
			(unlocked yes)
			(layer "F.Fab")
			(hide yes)
			(effects
				(font
					(size 1.016 1.016)
					(thickness 0.1524)
				)
			)
		)
		(duplicate_pad_numbers_are_jumpers no)
		(fp_rect
			(start -0.381 0.8382)
			(end 0.381 -0.8382)
			(stroke
				(width 0)
				(type default)
			)
			(fill no)
			(layer "F.CrtYd")
		)
		(fp_rect
			(start -0.381 0.8382)
			(end 0.381 -0.8382)
			(stroke
				(width 0)
				(type default)
			)
			(fill no)
			(layer "F.Fab")
		)
		(pad "1" smd custom
			(at 0 -0.4318 180)
			(size 0.127 0.127)
			(layers "F.Cu" "F.Mask" "F.Paste")
			(net "P3V3_STBY")
			(options
				(clearance outline)
				(anchor circle)
			)
			(primitives
				(gr_poly
					(pts
						(arc
							(start -0.2032 -0.2794)
							(mid -0.239121 -0.264521)
							(end -0.254 -0.2286)
						)
						(arc
							(start -0.254 0.2286)
							(mid -0.239121 0.264521)
							(end -0.2032 0.2794)
						)
						(arc
							(start 0.2032 0.2794)
							(mid 0.239121 0.264521)
							(end 0.254 0.2286)
						)
						(arc
							(start 0.254 -0.2286)
							(mid 0.239121 -0.264521)
							(end 0.2032 -0.2794)
						)
					)
					(width 0)
					(fill yes)
				)
			)
		)
		(pad "2" smd custom
			(at 0 0.4318 180)
			(size 0.127 0.127)
			(layers "F.Cu" "F.Mask" "F.Paste")
			(net "VR_PWREN_PVDDR_A")
			(options
				(clearance outline)
				(anchor circle)
			)
			(primitives
				(gr_poly
					(pts
						(arc
							(start -0.2032 -0.2794)
							(mid -0.239121 -0.264521)
							(end -0.254 -0.2286)
						)
						(arc
							(start -0.254 0.2286)
							(mid -0.239121 0.264521)
							(end -0.2032 0.2794)
						)
						(arc
							(start 0.2032 0.2794)
							(mid 0.239121 0.264521)
							(end 0.254 0.2286)
						)
						(arc
							(start 0.254 -0.2286)
							(mid 0.239121 -0.264521)
							(end 0.2032 -0.2794)
						)
					)
					(width 0)
					(fill yes)
				)
			)
		)
	)
	(footprint ""
		(layer "F.Cu")
		(at 67.6402 -42.2402 90)
		(property "Reference" "R39"
			(at 0 0 90)
			(layer "F.SilkS")
			(hide yes)
			(effects
				(font
					(size 1.27 1.27)
				)
			)
		)
		(property "Value" "0R2J-2-GP"
			(at 0.064008 -3.993896 90)
			(unlocked yes)
			(layer "F.Fab")
			(hide yes)
			(effects
				(font
					(size 1.016 1.016)
					(thickness 0.1524)
				)
			)
		)
		(property "Device Type" "R402H16"
			(at 0.064008 -5.517896 90)
			(unlocked yes)
			(layer "F.Fab")
			(hide yes)
			(effects
				(font
					(size 1.016 1.016)
					(thickness 0.1524)
				)
			)
		)
		(duplicate_pad_numbers_are_jumpers no)
		(fp_rect
			(start -0.381 0.8382)
			(end 0.381 -0.8382)
			(stroke
				(width 0)
				(type default)
			)
			(fill no)
			(layer "F.CrtYd")
		)
		(fp_rect
			(start -0.381 0.8382)
			(end 0.381 -0.8382)
			(stroke
				(width 0)
				(type default)
			)
			(fill no)
			(layer "F.Fab")
		)
		(pad "1" smd custom
			(at 0 -0.4318 90)
			(size 0.127 0.127)
			(layers "F.Cu" "F.Mask" "F.Paste")
			(net "SMBUS_HOST_R_CLK")
			(options
				(clearance outline)
				(anchor circle)
			)
			(primitives
				(gr_poly
					(pts
						(arc
							(start -0.2032 -0.2794)
							(mid -0.239121 -0.264521)
							(end -0.254 -0.2286)
						)
						(arc
							(start -0.254 0.2286)
							(mid -0.239121 0.264521)
							(end -0.2032 0.2794)
						)
						(arc
							(start 0.2032 0.2794)
							(mid 0.239121 0.264521)
							(end 0.254 0.2286)
						)
						(arc
							(start 0.254 -0.2286)
							(mid 0.239121 -0.264521)
							(end 0.2032 -0.2794)
						)
					)
					(width 0)
					(fill yes)
				)
			)
		)
		(pad "2" smd custom
			(at 0 0.4318 90)
			(size 0.127 0.127)
			(layers "F.Cu" "F.Mask" "F.Paste")
			(net "SMBUS_HOST_CLK")
			(options
				(clearance outline)
				(anchor circle)
			)
			(primitives
				(gr_poly
					(pts
						(arc
							(start -0.2032 -0.2794)
							(mid -0.239121 -0.264521)
							(end -0.254 -0.2286)
						)
						(arc
							(start -0.254 0.2286)
							(mid -0.239121 0.264521)
							(end -0.2032 0.2794)
						)
						(arc
							(start 0.2032 0.2794)
							(mid 0.239121 0.264521)
							(end 0.254 0.2286)
						)
						(arc
							(start 0.254 -0.2286)
							(mid 0.239121 -0.264521)
							(end 0.2032 -0.2794)
						)
					)
					(width 0)
					(fill yes)
				)
			)
		)
	)
	(footprint ""
		(layer "F.Cu")
		(at 9.525 -40.132 90)
		(property "Reference" "PC181"
			(at 0 0 90)
			(layer "F.SilkS")
			(hide yes)
			(effects
				(font
					(size 1.27 1.27)
				)
			)
		)
		(property "Value" "SCD1U25V2KX-2-GP"
			(at 1.8923 -1.2065 90)
			(unlocked yes)
			(layer "F.Fab")
			(hide yes)
			(effects
				(font
					(size 1.016 1.016)
					(thickness 0.1524)
				)
			)
		)
		(property "Device Type" "C402H22"
			(at 1.8923 -2.7305 90)
			(unlocked yes)
			(layer "F.Fab")
			(hide yes)
			(effects
				(font
					(size 1.016 1.016)
					(thickness 0.1524)
				)
			)
		)
		(duplicate_pad_numbers_are_jumpers no)
		(fp_rect
			(start -0.381 0.7366)
			(end 0.381 -0.7366)
			(stroke
				(width 0)
				(type default)
			)
			(fill no)
			(layer "F.CrtYd")
		)
		(fp_rect
			(start -0.381 0.7366)
			(end 0.381 -0.7366)
			(stroke
				(width 0)
				(type default)
			)
			(fill no)
			(layer "F.Fab")
		)
		(pad "1" smd custom
			(at 0 -0.4572 90)
			(size 0.1143 0.1143)
			(layers "F.Cu" "F.Mask" "F.Paste")
			(net "P3V3_STBY_VIN")
			(options
				(clearance outline)
				(anchor circle)
			)
			(primitives
				(gr_poly
					(pts
						(arc
							(start -0.254 -0.1778)
							(mid -0.239121 -0.213721)
							(end -0.2032 -0.2286)
						)
						(arc
							(start 0.2032 -0.2286)
							(mid 0.239121 -0.213721)
							(end 0.254 -0.1778)
						)
						(arc
							(start 0.254 0.1778)
							(mid 0.239121 0.213721)
							(end 0.2032 0.2286)
						)
						(arc
							(start -0.2032 0.2286)
							(mid -0.239121 0.213721)
							(end -0.254 0.1778)
						)
					)
					(width 0)
					(fill yes)
				)
			)
		)
		(pad "2" smd custom
			(at 0 0.4572 90)
			(size 0.1143 0.1143)
			(layers "F.Cu" "F.Mask" "F.Paste")
			(net "GND")
			(options
				(clearance outline)
				(anchor circle)
			)
			(primitives
				(gr_poly
					(pts
						(arc
							(start -0.254 -0.1778)
							(mid -0.239121 -0.213721)
							(end -0.2032 -0.2286)
						)
						(arc
							(start 0.2032 -0.2286)
							(mid 0.239121 -0.213721)
							(end 0.254 -0.1778)
						)
						(arc
							(start 0.254 0.1778)
							(mid 0.239121 0.213721)
							(end 0.2032 0.2286)
						)
						(arc
							(start -0.2032 0.2286)
							(mid -0.239121 0.213721)
							(end -0.254 0.1778)
						)
					)
					(width 0)
					(fill yes)
				)
			)
		)
	)
	(footprint ""
		(layer "F.Cu")
		(at 174.879 -57.15)
		(property "Reference" "R176"
			(at 0 0 0)
			(layer "F.SilkS")
			(hide yes)
			(effects
				(font
					(size 1.27 1.27)
				)
			)
		)
		(property "Value" "4K7R2F-GP"
			(at 0.064008 -3.993896 0)
			(unlocked yes)
			(layer "F.Fab")
			(hide yes)
			(effects
				(font
					(size 1.016 1.016)
					(thickness 0.1524)
				)
			)
		)
		(property "Device Type" "R402H16"
			(at 0.064008 -5.517896 0)
			(unlocked yes)
			(layer "F.Fab")
			(hide yes)
			(effects
				(font
					(size 1.016 1.016)
					(thickness 0.1524)
				)
			)
		)
		(duplicate_pad_numbers_are_jumpers no)
		(fp_rect
			(start -0.381 0.8382)
			(end 0.381 -0.8382)
			(stroke
				(width 0)
				(type default)
			)
			(fill no)
			(layer "F.CrtYd")
		)
		(fp_rect
			(start -0.381 0.8382)
			(end 0.381 -0.8382)
			(stroke
				(width 0)
				(type default)
			)
			(fill no)
			(layer "F.Fab")
		)
		(pad "1" smd custom
			(at 0 -0.4318)
			(size 0.127 0.127)
			(layers "F.Cu" "F.Mask" "F.Paste")
			(net "P3V3_STBY")
			(options
				(clearance outline)
				(anchor circle)
			)
			(primitives
				(gr_poly
					(pts
						(arc
							(start -0.2032 -0.2794)
							(mid -0.239121 -0.264521)
							(end -0.254 -0.2286)
						)
						(arc
							(start -0.254 0.2286)
							(mid -0.239121 0.264521)
							(end -0.2032 0.2794)
						)
						(arc
							(start 0.2032 0.2794)
							(mid 0.239121 0.264521)
							(end 0.254 0.2286)
						)
						(arc
							(start 0.254 -0.2286)
							(mid 0.239121 -0.264521)
							(end 0.2032 -0.2794)
						)
					)
					(width 0)
					(fill yes)
				)
			)
		)
		(pad "2" smd custom
			(at 0 0.4318)
			(size 0.127 0.127)
			(layers "F.Cu" "F.Mask" "F.Paste")
			(net "EEPROM_A1")
			(options
				(clearance outline)
				(anchor circle)
			)
			(primitives
				(gr_poly
					(pts
						(arc
							(start -0.2032 -0.2794)
							(mid -0.239121 -0.264521)
							(end -0.254 -0.2286)
						)
						(arc
							(start -0.254 0.2286)
							(mid -0.239121 0.264521)
							(end -0.2032 0.2794)
						)
						(arc
							(start 0.2032 0.2794)
							(mid 0.239121 0.264521)
							(end 0.254 0.2286)
						)
						(arc
							(start 0.254 -0.2286)
							(mid 0.239121 -0.264521)
							(end 0.2032 -0.2794)
						)
					)
					(width 0)
					(fill yes)
				)
			)
		)
	)
	(footprint ""
		(layer "F.Cu")
		(at 97.155 -14.097)
		(property "Reference" "R194"
			(at 0 0 0)
			(layer "F.SilkS")
			(hide yes)
			(effects
				(font
					(size 1.27 1.27)
				)
			)
		)
		(property "Value" "0R2J-2-GP"
			(at 0.064008 -3.993896 0)
			(unlocked yes)
			(layer "F.Fab")
			(hide yes)
			(effects
				(font
					(size 1.016 1.016)
					(thickness 0.1524)
				)
			)
		)
		(property "Device Type" "R402H16"
			(at 0.064008 -5.517896 0)
			(unlocked yes)
			(layer "F.Fab")
			(hide yes)
			(effects
				(font
					(size 1.016 1.016)
					(thickness 0.1524)
				)
			)
		)
		(duplicate_pad_numbers_are_jumpers no)
		(fp_rect
			(start -0.381 0.8382)
			(end 0.381 -0.8382)
			(stroke
				(width 0)
				(type default)
			)
			(fill no)
			(layer "F.CrtYd")
		)
		(fp_rect
			(start -0.381 0.8382)
			(end 0.381 -0.8382)
			(stroke
				(width 0)
				(type default)
			)
			(fill no)
			(layer "F.Fab")
		)
		(pad "1" smd custom
			(at 0 -0.4318)
			(size 0.127 0.127)
			(layers "F.Cu" "F.Mask" "F.Paste")
			(net "GND")
			(options
				(clearance outline)
				(anchor circle)
			)
			(primitives
				(gr_poly
					(pts
						(arc
							(start -0.2032 -0.2794)
							(mid -0.239121 -0.264521)
							(end -0.254 -0.2286)
						)
						(arc
							(start -0.254 0.2286)
							(mid -0.239121 0.264521)
							(end -0.2032 0.2794)
						)
						(arc
							(start 0.2032 0.2794)
							(mid 0.239121 0.264521)
							(end 0.254 0.2286)
						)
						(arc
							(start 0.254 -0.2286)
							(mid 0.239121 -0.264521)
							(end 0.2032 -0.2794)
						)
					)
					(width 0)
					(fill yes)
				)
			)
		)
		(pad "2" smd custom
			(at 0 0.4318)
			(size 0.127 0.127)
			(layers "F.Cu" "F.Mask" "F.Paste")
			(net "BOARD_PRSNT#")
			(options
				(clearance outline)
				(anchor circle)
			)
			(primitives
				(gr_poly
					(pts
						(arc
							(start -0.2032 -0.2794)
							(mid -0.239121 -0.264521)
							(end -0.254 -0.2286)
						)
						(arc
							(start -0.254 0.2286)
							(mid -0.239121 0.264521)
							(end -0.2032 0.2794)
						)
						(arc
							(start 0.2032 0.2794)
							(mid 0.239121 0.264521)
							(end 0.254 0.2286)
						)
						(arc
							(start 0.254 -0.2286)
							(mid 0.239121 -0.264521)
							(end 0.2032 -0.2794)
						)
					)
					(width 0)
					(fill yes)
				)
			)
		)
	)
	(footprint ""
		(layer "F.Cu")
		(at 153.035 -12.446 -90)
		(property "Reference" "R386"
			(at 0 0 270)
			(layer "F.SilkS")
			(hide yes)
			(effects
				(font
					(size 1.27 1.27)
				)
			)
		)
		(property "Value" "100R2F-L1-GP-U"
			(at 0.064008 -3.993896 270)
			(unlocked yes)
			(layer "F.Fab")
			(hide yes)
			(effects
				(font
					(size 1.016 1.016)
					(thickness 0.1524)
				)
			)
		)
		(property "Device Type" "R402H14"
			(at 0.064008 -5.517896 270)
			(unlocked yes)
			(layer "F.Fab")
			(hide yes)
			(effects
				(font
					(size 1.016 1.016)
					(thickness 0.1524)
				)
			)
		)
		(duplicate_pad_numbers_are_jumpers no)
		(fp_rect
			(start -0.381 0.8382)
			(end 0.381 -0.8382)
			(stroke
				(width 0)
				(type default)
			)
			(fill no)
			(layer "F.CrtYd")
		)
		(fp_rect
			(start -0.381 0.8382)
			(end 0.381 -0.8382)
			(stroke
				(width 0)
				(type default)
			)
			(fill no)
			(layer "F.Fab")
		)
		(pad "1" smd custom
			(at 0 -0.4318 270)
			(size 0.127 0.127)
			(layers "F.Cu" "F.Mask" "F.Paste")
			(net "DDR3_M_B_VREF_CA")
			(options
				(clearance outline)
				(anchor circle)
			)
			(primitives
				(gr_poly
					(pts
						(arc
							(start -0.2032 -0.2794)
							(mid -0.239121 -0.264521)
							(end -0.254 -0.2286)
						)
						(arc
							(start -0.254 0.2286)
							(mid -0.239121 0.264521)
							(end -0.2032 0.2794)
						)
						(arc
							(start 0.2032 0.2794)
							(mid 0.239121 0.264521)
							(end 0.254 0.2286)
						)
						(arc
							(start 0.254 -0.2286)
							(mid 0.239121 -0.264521)
							(end 0.2032 -0.2794)
						)
					)
					(width 0)
					(fill yes)
				)
			)
		)
		(pad "2" smd custom
			(at 0 0.4318 270)
			(size 0.127 0.127)
			(layers "F.Cu" "F.Mask" "F.Paste")
			(net "GND")
			(options
				(clearance outline)
				(anchor circle)
			)
			(primitives
				(gr_poly
					(pts
						(arc
							(start -0.2032 -0.2794)
							(mid -0.239121 -0.264521)
							(end -0.254 -0.2286)
						)
						(arc
							(start -0.254 0.2286)
							(mid -0.239121 0.264521)
							(end -0.2032 0.2794)
						)
						(arc
							(start 0.2032 0.2794)
							(mid 0.239121 0.264521)
							(end 0.254 0.2286)
						)
						(arc
							(start 0.254 -0.2286)
							(mid 0.239121 -0.264521)
							(end 0.2032 -0.2794)
						)
					)
					(width 0)
					(fill yes)
				)
			)
		)
	)
	(footprint ""
		(layer "F.Cu")
		(at 26.416 -49.276 -90)
		(property "Reference" "PC68"
			(at 0 0 270)
			(layer "F.SilkS")
			(hide yes)
			(effects
				(font
					(size 1.27 1.27)
				)
			)
		)
		(property "Value" "SCD33U6D3V2KX-1-GP"
			(at 1.8923 -1.2065 270)
			(unlocked yes)
			(layer "F.Fab")
			(hide yes)
			(effects
				(font
					(size 1.016 1.016)
					(thickness 0.1524)
				)
			)
		)
		(property "Device Type" "C402H22"
			(at 1.8923 -2.7305 270)
			(unlocked yes)
			(layer "F.Fab")
			(hide yes)
			(effects
				(font
					(size 1.016 1.016)
					(thickness 0.1524)
				)
			)
		)
		(duplicate_pad_numbers_are_jumpers no)
		(fp_rect
			(start -0.381 0.7366)
			(end 0.381 -0.7366)
			(stroke
				(width 0)
				(type default)
			)
			(fill no)
			(layer "F.CrtYd")
		)
		(fp_rect
			(start -0.381 0.7366)
			(end 0.381 -0.7366)
			(stroke
				(width 0)
				(type default)
			)
			(fill no)
			(layer "F.Fab")
		)
		(pad "1" smd custom
			(at 0 -0.4572 270)
			(size 0.1143 0.1143)
			(layers "F.Cu" "F.Mask" "F.Paste")
			(net "VR_PVCCP_ISUMP")
			(options
				(clearance outline)
				(anchor circle)
			)
			(primitives
				(gr_poly
					(pts
						(arc
							(start -0.254 -0.1778)
							(mid -0.239121 -0.213721)
							(end -0.2032 -0.2286)
						)
						(arc
							(start 0.2032 -0.2286)
							(mid 0.239121 -0.213721)
							(end 0.254 -0.1778)
						)
						(arc
							(start 0.254 0.1778)
							(mid 0.239121 0.213721)
							(end 0.2032 0.2286)
						)
						(arc
							(start -0.2032 0.2286)
							(mid -0.239121 0.213721)
							(end -0.254 0.1778)
						)
					)
					(width 0)
					(fill yes)
				)
			)
		)
		(pad "2" smd custom
			(at 0 0.4572 270)
			(size 0.1143 0.1143)
			(layers "F.Cu" "F.Mask" "F.Paste")
			(net "VR_PVCCP_ISUMN")
			(options
				(clearance outline)
				(anchor circle)
			)
			(primitives
				(gr_poly
					(pts
						(arc
							(start -0.254 -0.1778)
							(mid -0.239121 -0.213721)
							(end -0.2032 -0.2286)
						)
						(arc
							(start 0.2032 -0.2286)
							(mid 0.239121 -0.213721)
							(end 0.254 -0.1778)
						)
						(arc
							(start 0.254 0.1778)
							(mid 0.239121 0.213721)
							(end 0.2032 0.2286)
						)
						(arc
							(start -0.2032 0.2286)
							(mid -0.239121 0.213721)
							(end -0.254 0.1778)
						)
					)
					(width 0)
					(fill yes)
				)
			)
		)
	)
	(footprint ""
		(layer "F.Cu")
		(at 203.4794 -56.4642 90)
		(property "Reference" "PC162"
			(at 0 0 90)
			(layer "F.SilkS")
			(hide yes)
			(effects
				(font
					(size 1.27 1.27)
				)
			)
		)
		(property "Value" "SC22U6D3V5MX-2GP"
			(at 0 -4.9022 90)
			(unlocked yes)
			(layer "F.Fab")
			(hide yes)
			(effects
				(font
					(size 1.016 1.016)
					(thickness 0.1524)
				)
			)
		)
		(property "Device Type" "C805H58"
			(at 0 -6.8072 90)
			(unlocked yes)
			(layer "F.Fab")
			(hide yes)
			(effects
				(font
					(size 1.016 1.016)
					(thickness 0.1524)
				)
			)
		)
		(duplicate_pad_numbers_are_jumpers no)
		(fp_line
			(start 0.6096 0)
			(end -0.6096 0)
			(stroke
				(width 0.3048)
				(type default)
			)
			(layer "F.SilkS")
		)
		(fp_poly
			(pts
				(xy -0.9017 1.4351) (xy 0.9017 1.4351) (xy 0.9017 -1.4351) (xy -0.9017 -1.4351)
			)
			(stroke
				(width 0)
				(type default)
			)
			(fill no)
			(layer "F.CrtYd")
		)
		(fp_poly
			(pts
				(xy 0.9017 1.4351) (xy 0.9017 -1.4351) (xy -0.9017 -1.4351) (xy -0.9017 1.4351)
			)
			(stroke
				(width 0)
				(type default)
			)
			(fill no)
			(layer "F.Fab")
		)
		(pad "1" smd rect
			(at 0 -0.8382 90)
			(size 1.5494 0.9398)
			(layers "F.Cu" "F.Mask" "F.Paste")
			(net "PV_VDDR")
		)
		(pad "2" smd rect
			(at 0 0.8382 90)
			(size 1.5494 0.9398)
			(layers "F.Cu" "F.Mask" "F.Paste")
			(net "GND")
		)
	)
	(footprint ""
		(layer "F.Cu")
		(at 15.875 -68.453 90)
		(property "Reference" "R315"
			(at 0 0 90)
			(layer "F.SilkS")
			(hide yes)
			(effects
				(font
					(size 1.27 1.27)
				)
			)
		)
		(property "Value" "4K7R2F-GP"
			(at 1.7907 -1.1176 90)
			(unlocked yes)
			(layer "F.Fab")
			(hide yes)
			(effects
				(font
					(size 1.016 1.016)
					(thickness 0.1524)
				)
			)
		)
		(property "Device Type" "R402H16"
			(at 1.7907 -2.6416 90)
			(unlocked yes)
			(layer "F.Fab")
			(hide yes)
			(effects
				(font
					(size 1.016 1.016)
					(thickness 0.1524)
				)
			)
		)
		(duplicate_pad_numbers_are_jumpers no)
		(fp_rect
			(start -0.381 0.8382)
			(end 0.381 -0.8382)
			(stroke
				(width 0)
				(type default)
			)
			(fill no)
			(layer "F.CrtYd")
		)
		(fp_rect
			(start -0.381 0.8382)
			(end 0.381 -0.8382)
			(stroke
				(width 0)
				(type default)
			)
			(fill no)
			(layer "F.Fab")
		)
		(pad "1" smd custom
			(at 0 -0.4318 90)
			(size 0.127 0.127)
			(layers "F.Cu" "F.Mask" "F.Paste")
			(net "P3V3")
			(options
				(clearance outline)
				(anchor circle)
			)
			(primitives
				(gr_poly
					(pts
						(arc
							(start -0.2032 -0.2794)
							(mid -0.239121 -0.264521)
							(end -0.254 -0.2286)
						)
						(arc
							(start -0.254 0.2286)
							(mid -0.239121 0.264521)
							(end -0.2032 0.2794)
						)
						(arc
							(start 0.2032 0.2794)
							(mid 0.239121 0.264521)
							(end 0.254 0.2286)
						)
						(arc
							(start 0.254 -0.2286)
							(mid 0.239121 -0.264521)
							(end 0.2032 -0.2794)
						)
					)
					(width 0)
					(fill yes)
				)
			)
		)
		(pad "2" smd custom
			(at 0 0.4318 90)
			(size 0.127 0.127)
			(layers "F.Cu" "F.Mask" "F.Paste")
			(net "LED_NGFF_DAS")
			(options
				(clearance outline)
				(anchor circle)
			)
			(primitives
				(gr_poly
					(pts
						(arc
							(start -0.2032 -0.2794)
							(mid -0.239121 -0.264521)
							(end -0.254 -0.2286)
						)
						(arc
							(start -0.254 0.2286)
							(mid -0.239121 0.264521)
							(end -0.2032 0.2794)
						)
						(arc
							(start 0.2032 0.2794)
							(mid 0.239121 0.264521)
							(end 0.254 0.2286)
						)
						(arc
							(start 0.254 -0.2286)
							(mid 0.239121 -0.264521)
							(end 0.2032 -0.2794)
						)
					)
					(width 0)
					(fill yes)
				)
			)
		)
	)
	(footprint ""
		(layer "F.Cu")
		(at 148.2598 -49.4665 -90)
		(property "Reference" "U50"
			(at 0 0 270)
			(layer "F.SilkS")
			(hide yes)
			(effects
				(font
					(size 1.27 1.27)
				)
			)
		)
		(property "Value" "74CBTLV3257RG-1GP"
			(at 0 -8.5852 270)
			(unlocked yes)
			(layer "F.Fab")
			(hide yes)
			(effects
				(font
					(size 1.016 1.016)
					(thickness 0.1524)
				)
			)
		)
		(property "Device Type" "QFN16-G3H40"
			(at 0 -10.1092 270)
			(unlocked yes)
			(layer "F.Fab")
			(hide yes)
			(effects
				(font
					(size 1.016 1.016)
					(thickness 0.1524)
				)
			)
		)
		(duplicate_pad_numbers_are_jumpers no)
		(fp_line
			(start -2.4638 2.2098)
			(end -1.6002 2.2098)
			(stroke
				(width 0.1524)
				(type default)
			)
			(layer "F.SilkS")
		)
		(fp_line
			(start -1.6002 2.2098)
			(end -1.6002 2.0701)
			(stroke
				(width 0.1524)
				(type default)
			)
			(layer "F.SilkS")
		)
		(fp_line
			(start -2.3241 2.0701)
			(end -2.3241 1.0922)
			(stroke
				(width 0.1524)
				(type default)
			)
			(layer "F.SilkS")
		)
		(fp_line
			(start -1.6002 2.0701)
			(end -2.3241 2.0701)
			(stroke
				(width 0.1524)
				(type default)
			)
			(layer "F.SilkS")
		)
		(fp_line
			(start -2.1844 1.9304)
			(end -2.1844 1.0922)
			(stroke
				(width 0.1524)
				(type default)
			)
			(layer "F.SilkS")
		)
		(fp_line
			(start -1.6002 1.9304)
			(end -1.6002 2.0701)
			(stroke
				(width 0.1524)
				(type default)
			)
			(layer "F.SilkS")
		)
		(fp_line
			(start -1.6002 1.9304)
			(end -2.1844 1.9304)
			(stroke
				(width 0.1524)
				(type default)
			)
			(layer "F.SilkS")
		)
		(fp_line
			(start -2.4638 1.0922)
			(end -2.4638 2.2098)
			(stroke
				(width 0.1524)
				(type default)
			)
			(layer "F.SilkS")
		)
		(fp_line
			(start -2.3241 1.0922)
			(end -2.4638 1.0922)
			(stroke
				(width 0.1524)
				(type default)
			)
			(layer "F.SilkS")
		)
		(fp_line
			(start -2.3241 1.0922)
			(end -2.1844 1.0922)
			(stroke
				(width 0.1524)
				(type default)
			)
			(layer "F.SilkS")
		)
		(fp_poly
			(pts
				(xy -1.6002 2.2352) (xy -1.6002 1.9304) (xy -2.1844 1.9304) (xy -2.1844 1.0922) (xy -2.4892 1.0922)
				(xy -2.4892 -1.0922) (xy -2.1844 -1.0922) (xy -2.1844 -1.9304) (xy -1.6002 -1.9304) (xy -1.6002 -2.2352)
				(xy 1.6002 -2.2352) (xy 1.6002 -1.9304) (xy 2.1844 -1.9304) (xy 2.1844 -1.0922) (xy 2.4892 -1.0922)
				(xy 2.4892 1.0922) (xy 2.1844 1.0922) (xy 2.1844 1.9304) (xy 1.6002 1.9304) (xy 1.6002 2.2352)
			)
			(stroke
				(width 0)
				(type default)
			)
			(fill no)
			(layer "F.CrtYd")
		)
		(fp_poly
			(pts
				(xy -1.6002 2.2352) (xy -1.6002 1.9304) (xy -2.1844 1.9304) (xy -2.1844 1.0922) (xy -2.4892 1.0922)
				(xy -2.4892 -1.0922) (xy -2.1844 -1.0922) (xy -2.1844 -1.9304) (xy -1.6002 -1.9304) (xy -1.6002 -2.2352)
				(xy 1.6002 -2.2352) (xy 1.6002 -1.9304) (xy 2.1844 -1.9304) (xy 2.1844 -1.0922) (xy 2.4892 -1.0922)
				(xy 2.4892 1.0922) (xy 2.1844 1.0922) (xy 2.1844 1.9304) (xy 1.6002 1.9304) (xy 1.6002 2.2352)
			)
			(stroke
				(width 0)
				(type default)
			)
			(fill no)
			(layer "F.Fab")
		)
		(pad "1" smd rect
			(at -1.9558 0.75057 270)
			(size 0.7112 0.3048)
			(layers "F.Cu" "F.Mask" "F.Paste")
			(net "BUS_SW_SEL")
		)
		(pad "2" smd rect
			(at -1.24968 1.7018 270)
			(size 0.3048 0.7112)
			(layers "F.Cu" "F.Mask" "F.Paste")
			(net "SPI_SW_CSO#")
		)
		(pad "3" smd rect
			(at -0.75057 1.7018 270)
			(size 0.3048 0.7112)
			(layers "F.Cu" "F.Mask" "F.Paste")
			(net "FPGA_CSO#")
		)
		(pad "4" smd rect
			(at -0.25019 1.7018 270)
			(size 0.3048 0.7112)
			(layers "F.Cu" "F.Mask" "F.Paste")
			(net "C_CSO#")
		)
		(pad "5" smd rect
			(at 0.25019 1.7018 270)
			(size 0.3048 0.7112)
			(layers "F.Cu" "F.Mask" "F.Paste")
			(net "SPI_SW_DCLK")
		)
		(pad "6" smd rect
			(at 0.75057 1.7018 270)
			(size 0.3048 0.7112)
			(layers "F.Cu" "F.Mask" "F.Paste")
			(net "FPGA_DCLK")
		)
		(pad "7" smd rect
			(at 1.24968 1.7018 270)
			(size 0.3048 0.7112)
			(layers "F.Cu" "F.Mask" "F.Paste")
			(net "C_DCLK")
		)
		(pad "8" smd rect
			(at 1.9558 0.75057 270)
			(size 0.7112 0.3048)
			(layers "F.Cu" "F.Mask" "F.Paste")
			(net "GND")
		)
		(pad "9" smd rect
			(at 1.9558 -0.75057 270)
			(size 0.7112 0.3048)
			(layers "F.Cu" "F.Mask" "F.Paste")
			(net "C_ASDO")
		)
		(pad "10" smd rect
			(at 1.24968 -1.7018 270)
			(size 0.3048 0.7112)
			(layers "F.Cu" "F.Mask" "F.Paste")
			(net "FPGA_ASDO")
		)
		(pad "11" smd rect
			(at 0.75057 -1.7018 270)
			(size 0.3048 0.7112)
			(layers "F.Cu" "F.Mask" "F.Paste")
			(net "SPI_SW_ASDO")
		)
		(pad "12" smd rect
			(at 0.25019 -1.7018 270)
			(size 0.3048 0.7112)
			(layers "F.Cu" "F.Mask" "F.Paste")
			(net "C_DATA0")
		)
		(pad "13" smd rect
			(at -0.25019 -1.7018 270)
			(size 0.3048 0.7112)
			(layers "F.Cu" "F.Mask" "F.Paste")
			(net "FPGA_DATA0")
		)
		(pad "14" smd rect
			(at -0.75057 -1.7018 270)
			(size 0.3048 0.7112)
			(layers "F.Cu" "F.Mask" "F.Paste")
			(net "SPI_SW_DATA0")
		)
		(pad "15" smd rect
			(at -1.24968 -1.7018 270)
			(size 0.3048 0.7112)
			(layers "F.Cu" "F.Mask" "F.Paste")
			(net "BUS_SW_OE#")
		)
		(pad "16" smd rect
			(at -1.9558 -0.75057 270)
			(size 0.7112 0.3048)
			(layers "F.Cu" "F.Mask" "F.Paste")
			(net "P3V3_STBY")
		)
		(pad "17" smd rect
			(at 0 0 270)
			(size 2.1844 1.6764)
			(layers "F.Cu" "F.Mask" "F.Paste")
			(net "GND")
		)
	)
	(footprint ""
		(layer "F.Cu")
		(at 12.573 -55.245 -90)
		(property "Reference" "PC48"
			(at 0 0 270)
			(layer "F.SilkS")
			(hide yes)
			(effects
				(font
					(size 1.27 1.27)
				)
			)
		)
		(property "Value" "SCD22U10V2KX-1GP"
			(at 1.8923 -1.2065 270)
			(unlocked yes)
			(layer "F.Fab")
			(hide yes)
			(effects
				(font
					(size 1.016 1.016)
					(thickness 0.1524)
				)
			)
		)
		(property "Device Type" "C402H22"
			(at 1.8923 -2.7305 270)
			(unlocked yes)
			(layer "F.Fab")
			(hide yes)
			(effects
				(font
					(size 1.016 1.016)
					(thickness 0.1524)
				)
			)
		)
		(duplicate_pad_numbers_are_jumpers no)
		(fp_rect
			(start -0.381 0.7366)
			(end 0.381 -0.7366)
			(stroke
				(width 0)
				(type default)
			)
			(fill no)
			(layer "F.CrtYd")
		)
		(fp_rect
			(start -0.381 0.7366)
			(end 0.381 -0.7366)
			(stroke
				(width 0)
				(type default)
			)
			(fill no)
			(layer "F.Fab")
		)
		(pad "1" smd custom
			(at 0 -0.4572 270)
			(size 0.1143 0.1143)
			(layers "F.Cu" "F.Mask" "F.Paste")
			(net "VR_PVCCP_IMON")
			(options
				(clearance outline)
				(anchor circle)
			)
			(primitives
				(gr_poly
					(pts
						(arc
							(start -0.254 -0.1778)
							(mid -0.239121 -0.213721)
							(end -0.2032 -0.2286)
						)
						(arc
							(start 0.2032 -0.2286)
							(mid 0.239121 -0.213721)
							(end 0.254 -0.1778)
						)
						(arc
							(start 0.254 0.1778)
							(mid 0.239121 0.213721)
							(end 0.2032 0.2286)
						)
						(arc
							(start -0.2032 0.2286)
							(mid -0.239121 0.213721)
							(end -0.254 0.1778)
						)
					)
					(width 0)
					(fill yes)
				)
			)
		)
		(pad "2" smd custom
			(at 0 0.4572 270)
			(size 0.1143 0.1143)
			(layers "F.Cu" "F.Mask" "F.Paste")
			(net "GND")
			(options
				(clearance outline)
				(anchor circle)
			)
			(primitives
				(gr_poly
					(pts
						(arc
							(start -0.254 -0.1778)
							(mid -0.239121 -0.213721)
							(end -0.2032 -0.2286)
						)
						(arc
							(start 0.2032 -0.2286)
							(mid 0.239121 -0.213721)
							(end 0.254 -0.1778)
						)
						(arc
							(start 0.254 0.1778)
							(mid 0.239121 0.213721)
							(end 0.2032 0.2286)
						)
						(arc
							(start -0.2032 0.2286)
							(mid -0.239121 0.213721)
							(end -0.254 0.1778)
						)
					)
					(width 0)
					(fill yes)
				)
			)
		)
	)
	(footprint ""
		(layer "F.Cu")
		(at 69.9262 -43.6626)
		(property "Reference" "R71"
			(at 0 0 0)
			(layer "F.SilkS")
			(hide yes)
			(effects
				(font
					(size 1.27 1.27)
				)
			)
		)
		(property "Value" "4K7R2F-GP"
			(at 0.064008 -3.993896 0)
			(unlocked yes)
			(layer "F.Fab")
			(hide yes)
			(effects
				(font
					(size 1.016 1.016)
					(thickness 0.1524)
				)
			)
		)
		(property "Device Type" "R402H16"
			(at 0.064008 -5.517896 0)
			(unlocked yes)
			(layer "F.Fab")
			(hide yes)
			(effects
				(font
					(size 1.016 1.016)
					(thickness 0.1524)
				)
			)
		)
		(duplicate_pad_numbers_are_jumpers no)
		(fp_rect
			(start -0.381 0.8382)
			(end 0.381 -0.8382)
			(stroke
				(width 0)
				(type default)
			)
			(fill no)
			(layer "F.CrtYd")
		)
		(fp_rect
			(start -0.381 0.8382)
			(end 0.381 -0.8382)
			(stroke
				(width 0)
				(type default)
			)
			(fill no)
			(layer "F.Fab")
		)
		(pad "1" smd custom
			(at 0 -0.4318)
			(size 0.127 0.127)
			(layers "F.Cu" "F.Mask" "F.Paste")
			(net "P3V3")
			(options
				(clearance outline)
				(anchor circle)
			)
			(primitives
				(gr_poly
					(pts
						(arc
							(start -0.2032 -0.2794)
							(mid -0.239121 -0.264521)
							(end -0.254 -0.2286)
						)
						(arc
							(start -0.254 0.2286)
							(mid -0.239121 0.264521)
							(end -0.2032 0.2794)
						)
						(arc
							(start 0.2032 0.2794)
							(mid 0.239121 0.264521)
							(end 0.254 0.2286)
						)
						(arc
							(start 0.254 -0.2286)
							(mid 0.239121 -0.264521)
							(end 0.2032 -0.2794)
						)
					)
					(width 0)
					(fill yes)
				)
			)
		)
		(pad "2" smd custom
			(at 0 0.4318)
			(size 0.127 0.127)
			(layers "F.Cu" "F.Mask" "F.Paste")
			(net "SMBUS_PECI_DATA")
			(options
				(clearance outline)
				(anchor circle)
			)
			(primitives
				(gr_poly
					(pts
						(arc
							(start -0.2032 -0.2794)
							(mid -0.239121 -0.264521)
							(end -0.254 -0.2286)
						)
						(arc
							(start -0.254 0.2286)
							(mid -0.239121 0.264521)
							(end -0.2032 0.2794)
						)
						(arc
							(start 0.2032 0.2794)
							(mid 0.239121 0.264521)
							(end 0.254 0.2286)
						)
						(arc
							(start 0.254 -0.2286)
							(mid 0.239121 -0.264521)
							(end 0.2032 -0.2794)
						)
					)
					(width 0)
					(fill yes)
				)
			)
		)
	)
	(footprint ""
		(layer "F.Cu")
		(at 162.5092 -48.5648)
		(property "Reference" "R207"
			(at 0 0 0)
			(layer "F.SilkS")
			(hide yes)
			(effects
				(font
					(size 1.27 1.27)
				)
			)
		)
		(property "Value" "0R2J-2-GP"
			(at 1.7907 -1.1176 0)
			(unlocked yes)
			(layer "F.Fab")
			(hide yes)
			(effects
				(font
					(size 1.016 1.016)
					(thickness 0.1524)
				)
			)
		)
		(property "Device Type" "R402H16"
			(at 1.7907 -2.6416 0)
			(unlocked yes)
			(layer "F.Fab")
			(hide yes)
			(effects
				(font
					(size 1.016 1.016)
					(thickness 0.1524)
				)
			)
		)
		(duplicate_pad_numbers_are_jumpers no)
		(fp_rect
			(start -0.381 0.8382)
			(end 0.381 -0.8382)
			(stroke
				(width 0)
				(type default)
			)
			(fill no)
			(layer "F.CrtYd")
		)
		(fp_rect
			(start -0.381 0.8382)
			(end 0.381 -0.8382)
			(stroke
				(width 0)
				(type default)
			)
			(fill no)
			(layer "F.Fab")
		)
		(pad "1" smd custom
			(at 0 -0.4318)
			(size 0.127 0.127)
			(layers "F.Cu" "F.Mask" "F.Paste")
			(net "XDP_SOC_CPU_TMS")
			(options
				(clearance outline)
				(anchor circle)
			)
			(primitives
				(gr_poly
					(pts
						(arc
							(start -0.2032 -0.2794)
							(mid -0.239121 -0.264521)
							(end -0.254 -0.2286)
						)
						(arc
							(start -0.254 0.2286)
							(mid -0.239121 0.264521)
							(end -0.2032 0.2794)
						)
						(arc
							(start 0.2032 0.2794)
							(mid 0.239121 0.264521)
							(end 0.254 0.2286)
						)
						(arc
							(start 0.254 -0.2286)
							(mid 0.239121 -0.264521)
							(end 0.2032 -0.2794)
						)
					)
					(width 0)
					(fill yes)
				)
			)
		)
		(pad "2" smd custom
			(at 0 0.4318)
			(size 0.127 0.127)
			(layers "F.Cu" "F.Mask" "F.Paste")
			(net "XDP_SOC_CPU_TMS_S")
			(options
				(clearance outline)
				(anchor circle)
			)
			(primitives
				(gr_poly
					(pts
						(arc
							(start -0.2032 -0.2794)
							(mid -0.239121 -0.264521)
							(end -0.254 -0.2286)
						)
						(arc
							(start -0.254 0.2286)
							(mid -0.239121 0.264521)
							(end -0.2032 0.2794)
						)
						(arc
							(start 0.2032 0.2794)
							(mid 0.239121 0.264521)
							(end 0.254 0.2286)
						)
						(arc
							(start 0.254 -0.2286)
							(mid 0.239121 -0.264521)
							(end 0.2032 -0.2794)
						)
					)
					(width 0)
					(fill yes)
				)
			)
		)
	)
	(footprint ""
		(layer "F.Cu")
		(at 205.105 -21.463 180)
		(property "Reference" "R224"
			(at 0 0 180)
			(layer "F.SilkS")
			(hide yes)
			(effects
				(font
					(size 1.27 1.27)
				)
			)
		)
		(property "Value" "10KR2F-2-GP"
			(at 1.7907 -1.1176 180)
			(unlocked yes)
			(layer "F.Fab")
			(hide yes)
			(effects
				(font
					(size 1.016 1.016)
					(thickness 0.1524)
				)
			)
		)
		(property "Device Type" "R402H16"
			(at 1.7907 -2.6416 180)
			(unlocked yes)
			(layer "F.Fab")
			(hide yes)
			(effects
				(font
					(size 1.016 1.016)
					(thickness 0.1524)
				)
			)
		)
		(duplicate_pad_numbers_are_jumpers no)
		(fp_rect
			(start -0.381 0.8382)
			(end 0.381 -0.8382)
			(stroke
				(width 0)
				(type default)
			)
			(fill no)
			(layer "F.CrtYd")
		)
		(fp_rect
			(start -0.381 0.8382)
			(end 0.381 -0.8382)
			(stroke
				(width 0)
				(type default)
			)
			(fill no)
			(layer "F.Fab")
		)
		(pad "1" smd custom
			(at 0 -0.4318 180)
			(size 0.127 0.127)
			(layers "F.Cu" "F.Mask" "F.Paste")
			(net "P3V3_STBY")
			(options
				(clearance outline)
				(anchor circle)
			)
			(primitives
				(gr_poly
					(pts
						(arc
							(start -0.2032 -0.2794)
							(mid -0.239121 -0.264521)
							(end -0.254 -0.2286)
						)
						(arc
							(start -0.254 0.2286)
							(mid -0.239121 0.264521)
							(end -0.2032 0.2794)
						)
						(arc
							(start 0.2032 0.2794)
							(mid 0.239121 0.264521)
							(end 0.254 0.2286)
						)
						(arc
							(start 0.254 -0.2286)
							(mid 0.239121 -0.264521)
							(end 0.2032 -0.2794)
						)
					)
					(width 0)
					(fill yes)
				)
			)
		)
		(pad "2" smd custom
			(at 0 0.4318 180)
			(size 0.127 0.127)
			(layers "F.Cu" "F.Mask" "F.Paste")
			(net "JTAG_CPU_PLD_TDO")
			(options
				(clearance outline)
				(anchor circle)
			)
			(primitives
				(gr_poly
					(pts
						(arc
							(start -0.2032 -0.2794)
							(mid -0.239121 -0.264521)
							(end -0.254 -0.2286)
						)
						(arc
							(start -0.254 0.2286)
							(mid -0.239121 0.264521)
							(end -0.2032 0.2794)
						)
						(arc
							(start 0.2032 0.2794)
							(mid 0.239121 0.264521)
							(end 0.254 0.2286)
						)
						(arc
							(start 0.254 -0.2286)
							(mid 0.239121 -0.264521)
							(end 0.2032 -0.2794)
						)
					)
					(width 0)
					(fill yes)
				)
			)
		)
	)
	(footprint ""
		(layer "F.Cu")
		(at 60.198 -21.844 -90)
		(property "Reference" "Q10"
			(at 0 0 270)
			(layer "F.SilkS")
			(hide yes)
			(effects
				(font
					(size 1.27 1.27)
				)
			)
		)
		(property "Value" "2N7002A-7-GP"
			(at 0.127 -8.9662 270)
			(unlocked yes)
			(layer "F.Fab")
			(hide yes)
			(effects
				(font
					(size 1.016 1.016)
					(thickness 0.1524)
				)
			)
		)
		(property "Device Type" "SOT23DGS2D4H48"
			(at 0.127 -10.4902 270)
			(unlocked yes)
			(layer "F.Fab")
			(hide yes)
			(effects
				(font
					(size 1.016 1.016)
					(thickness 0.1524)
				)
			)
		)
		(duplicate_pad_numbers_are_jumpers no)
		(fp_line
			(start -1.7145 0.4445)
			(end 1.7145 0.4445)
			(stroke
				(width 0.1524)
				(type default)
			)
			(layer "F.SilkS")
		)
		(fp_line
			(start 1.7145 0.4445)
			(end 1.7145 -0.4445)
			(stroke
				(width 0.1524)
				(type default)
			)
			(layer "F.SilkS")
		)
		(fp_line
			(start -1.7145 -0.4445)
			(end -1.7145 0.4445)
			(stroke
				(width 0.1524)
				(type default)
			)
			(layer "F.SilkS")
		)
		(fp_line
			(start 1.7145 -0.4445)
			(end -1.7145 -0.4445)
			(stroke
				(width 0.1524)
				(type default)
			)
			(layer "F.SilkS")
		)
		(fp_poly
			(pts
				(xy -1.4224 1.5621) (xy -1.4224 0.9017) (xy -1.7145 0.9017) (xy -1.7145 -0.9017) (xy -0.4699 -0.9017)
				(xy -0.4699 -1.5621) (xy 0.4699 -1.5621) (xy 0.4699 -0.9017) (xy 1.7145 -0.9017) (xy 1.7145 0.9017)
				(xy 1.4224 0.9017) (xy 1.4224 1.5621) (xy 0.4826 1.5621) (xy 0.4826 0.9017) (xy -0.4826 0.9017)
				(xy -0.4826 1.5621)
			)
			(stroke
				(width 0)
				(type default)
			)
			(fill no)
			(layer "F.CrtYd")
		)
		(fp_poly
			(pts
				(xy -1.4224 1.5621) (xy -1.4224 0.9017) (xy -1.7145 0.9017) (xy -1.7145 -0.9017) (xy -0.4699 -0.9017)
				(xy -0.4699 -1.5621) (xy 0.4699 -1.5621) (xy 0.4699 -0.9017) (xy 1.7145 -0.9017) (xy 1.7145 0.9017)
				(xy 1.4224 0.9017) (xy 1.4224 1.5621) (xy 0.4826 1.5621) (xy 0.4826 0.9017) (xy -0.4826 0.9017)
				(xy -0.4826 1.5621)
			)
			(stroke
				(width 0)
				(type default)
			)
			(fill no)
			(layer "F.Fab")
		)
		(pad "D" smd custom
			(at 0 -1.069086 270)
			(size 0.17145 0.17145)
			(layers "F.Cu" "F.Mask" "F.Paste")
			(net "PWRGD_P1V8_PG")
			(options
				(clearance outline)
				(anchor circle)
			)
			(primitives
				(gr_poly
					(pts
						(arc
							(start -0.1397 0.3683)
							(mid -0.283384 0.308784)
							(end -0.3429 0.1651)
						)
						(arc
							(start -0.3429 -0.1651)
							(mid -0.283384 -0.308784)
							(end -0.1397 -0.3683)
						)
						(arc
							(start 0.1397 -0.3683)
							(mid 0.283384 -0.308784)
							(end 0.3429 -0.1651)
						)
						(arc
							(start 0.3429 0.1651)
							(mid 0.283384 0.308784)
							(end 0.1397 0.3683)
						)
					)
					(width 0)
					(fill yes)
				)
			)
		)
		(pad "G" smd custom
			(at -0.94996 1.069086 270)
			(size 0.17145 0.17145)
			(layers "F.Cu" "F.Mask" "F.Paste")
			(net "P1V8_G")
			(options
				(clearance outline)
				(anchor circle)
			)
			(primitives
				(gr_poly
					(pts
						(arc
							(start -0.1397 0.3683)
							(mid -0.283384 0.308784)
							(end -0.3429 0.1651)
						)
						(arc
							(start -0.3429 -0.1651)
							(mid -0.283384 -0.308784)
							(end -0.1397 -0.3683)
						)
						(arc
							(start 0.1397 -0.3683)
							(mid 0.283384 -0.308784)
							(end 0.3429 -0.1651)
						)
						(arc
							(start 0.3429 0.1651)
							(mid 0.283384 0.308784)
							(end 0.1397 0.3683)
						)
					)
					(width 0)
					(fill yes)
				)
			)
		)
		(pad "S" smd custom
			(at 0.94996 1.069086 270)
			(size 0.17145 0.17145)
			(layers "F.Cu" "F.Mask" "F.Paste")
			(net "GND")
			(options
				(clearance outline)
				(anchor circle)
			)
			(primitives
				(gr_poly
					(pts
						(arc
							(start -0.1397 0.3683)
							(mid -0.283384 0.308784)
							(end -0.3429 0.1651)
						)
						(arc
							(start -0.3429 -0.1651)
							(mid -0.283384 -0.308784)
							(end -0.1397 -0.3683)
						)
						(arc
							(start 0.1397 -0.3683)
							(mid 0.283384 -0.308784)
							(end 0.3429 -0.1651)
						)
						(arc
							(start 0.3429 0.1651)
							(mid 0.283384 0.308784)
							(end 0.1397 0.3683)
						)
					)
					(width 0)
					(fill yes)
				)
			)
		)
	)
	(footprint ""
		(layer "F.Cu")
		(at 6.9088 -32.004 180)
		(property "Reference" "PR202"
			(at 0 0 180)
			(layer "F.SilkS")
			(hide yes)
			(effects
				(font
					(size 1.27 1.27)
				)
			)
		)
		(property "Value" "73K2R2F-GP"
			(at 1.7907 -1.1176 180)
			(unlocked yes)
			(layer "F.Fab")
			(hide yes)
			(effects
				(font
					(size 1.016 1.016)
					(thickness 0.1524)
				)
			)
		)
		(property "Device Type" "R402H16"
			(at 1.7907 -2.6416 180)
			(unlocked yes)
			(layer "F.Fab")
			(hide yes)
			(effects
				(font
					(size 1.016 1.016)
					(thickness 0.1524)
				)
			)
		)
		(duplicate_pad_numbers_are_jumpers no)
		(fp_rect
			(start -0.381 0.8382)
			(end 0.381 -0.8382)
			(stroke
				(width 0)
				(type default)
			)
			(fill no)
			(layer "F.CrtYd")
		)
		(fp_rect
			(start -0.381 0.8382)
			(end 0.381 -0.8382)
			(stroke
				(width 0)
				(type default)
			)
			(fill no)
			(layer "F.Fab")
		)
		(pad "1" smd custom
			(at 0 -0.4318 180)
			(size 0.127 0.127)
			(layers "F.Cu" "F.Mask" "F.Paste")
			(net "AGND_P3V3_STBY")
			(options
				(clearance outline)
				(anchor circle)
			)
			(primitives
				(gr_poly
					(pts
						(arc
							(start -0.2032 -0.2794)
							(mid -0.239121 -0.264521)
							(end -0.254 -0.2286)
						)
						(arc
							(start -0.254 0.2286)
							(mid -0.239121 0.264521)
							(end -0.2032 0.2794)
						)
						(arc
							(start 0.2032 0.2794)
							(mid 0.239121 0.264521)
							(end 0.254 0.2286)
						)
						(arc
							(start 0.254 -0.2286)
							(mid 0.239121 -0.264521)
							(end 0.2032 -0.2794)
						)
					)
					(width 0)
					(fill yes)
				)
			)
		)
		(pad "2" smd custom
			(at 0 0.4318 180)
			(size 0.127 0.127)
			(layers "F.Cu" "F.Mask" "F.Paste")
			(net "P3V3_STBY_TRIP")
			(options
				(clearance outline)
				(anchor circle)
			)
			(primitives
				(gr_poly
					(pts
						(arc
							(start -0.2032 -0.2794)
							(mid -0.239121 -0.264521)
							(end -0.254 -0.2286)
						)
						(arc
							(start -0.254 0.2286)
							(mid -0.239121 0.264521)
							(end -0.2032 0.2794)
						)
						(arc
							(start 0.2032 0.2794)
							(mid 0.239121 0.264521)
							(end 0.254 0.2286)
						)
						(arc
							(start 0.254 -0.2286)
							(mid 0.239121 -0.264521)
							(end 0.2032 -0.2794)
						)
					)
					(width 0)
					(fill yes)
				)
			)
		)
	)
	(footprint ""
		(layer "F.Cu")
		(at 187.198 -50.673)
		(property "Reference" "R209"
			(at 0 0 0)
			(layer "F.SilkS")
			(hide yes)
			(effects
				(font
					(size 1.27 1.27)
				)
			)
		)
		(property "Value" "12K1R2F-L1-GP"
			(at 0.064008 -3.993896 0)
			(unlocked yes)
			(layer "F.Fab")
			(hide yes)
			(effects
				(font
					(size 1.016 1.016)
					(thickness 0.1524)
				)
			)
		)
		(property "Device Type" "R402H16"
			(at 0.064008 -5.517896 0)
			(unlocked yes)
			(layer "F.Fab")
			(hide yes)
			(effects
				(font
					(size 1.016 1.016)
					(thickness 0.1524)
				)
			)
		)
		(duplicate_pad_numbers_are_jumpers no)
		(fp_rect
			(start -0.381 0.8382)
			(end 0.381 -0.8382)
			(stroke
				(width 0)
				(type default)
			)
			(fill no)
			(layer "F.CrtYd")
		)
		(fp_rect
			(start -0.381 0.8382)
			(end 0.381 -0.8382)
			(stroke
				(width 0)
				(type default)
			)
			(fill no)
			(layer "F.Fab")
		)
		(pad "1" smd custom
			(at 0 -0.4318)
			(size 0.127 0.127)
			(layers "F.Cu" "F.Mask" "F.Paste")
			(net "PV_VDDR")
			(options
				(clearance outline)
				(anchor circle)
			)
			(primitives
				(gr_poly
					(pts
						(arc
							(start -0.2032 -0.2794)
							(mid -0.239121 -0.264521)
							(end -0.254 -0.2286)
						)
						(arc
							(start -0.254 0.2286)
							(mid -0.239121 0.264521)
							(end -0.2032 0.2794)
						)
						(arc
							(start 0.2032 0.2794)
							(mid 0.239121 0.264521)
							(end 0.254 0.2286)
						)
						(arc
							(start 0.254 -0.2286)
							(mid 0.239121 -0.264521)
							(end 0.2032 -0.2794)
						)
					)
					(width 0)
					(fill yes)
				)
			)
		)
		(pad "2" smd custom
			(at 0 0.4318)
			(size 0.127 0.127)
			(layers "F.Cu" "F.Mask" "F.Paste")
			(net "PV_VDDR_VREF_RW")
			(options
				(clearance outline)
				(anchor circle)
			)
			(primitives
				(gr_poly
					(pts
						(arc
							(start -0.2032 -0.2794)
							(mid -0.239121 -0.264521)
							(end -0.254 -0.2286)
						)
						(arc
							(start -0.254 0.2286)
							(mid -0.239121 0.264521)
							(end -0.2032 0.2794)
						)
						(arc
							(start 0.2032 0.2794)
							(mid 0.239121 0.264521)
							(end 0.254 0.2286)
						)
						(arc
							(start 0.254 -0.2286)
							(mid 0.239121 -0.264521)
							(end 0.2032 -0.2794)
						)
					)
					(width 0)
					(fill yes)
				)
			)
		)
	)
	(footprint ""
		(layer "F.Cu")
		(at 64.262 -33.02 90)
		(property "Reference" "R239"
			(at 0 0 90)
			(layer "F.SilkS")
			(hide yes)
			(effects
				(font
					(size 1.27 1.27)
				)
			)
		)
		(property "Value" "1KR2F-3-GP"
			(at 0.064008 -3.993896 90)
			(unlocked yes)
			(layer "F.Fab")
			(hide yes)
			(effects
				(font
					(size 1.016 1.016)
					(thickness 0.1524)
				)
			)
		)
		(property "Device Type" "R402H16"
			(at 0.064008 -5.517896 90)
			(unlocked yes)
			(layer "F.Fab")
			(hide yes)
			(effects
				(font
					(size 1.016 1.016)
					(thickness 0.1524)
				)
			)
		)
		(duplicate_pad_numbers_are_jumpers no)
		(fp_rect
			(start -0.381 0.8382)
			(end 0.381 -0.8382)
			(stroke
				(width 0)
				(type default)
			)
			(fill no)
			(layer "F.CrtYd")
		)
		(fp_rect
			(start -0.381 0.8382)
			(end 0.381 -0.8382)
			(stroke
				(width 0)
				(type default)
			)
			(fill no)
			(layer "F.Fab")
		)
		(pad "1" smd custom
			(at 0 -0.4318 90)
			(size 0.127 0.127)
			(layers "F.Cu" "F.Mask" "F.Paste")
			(net "GND")
			(options
				(clearance outline)
				(anchor circle)
			)
			(primitives
				(gr_poly
					(pts
						(arc
							(start -0.2032 -0.2794)
							(mid -0.239121 -0.264521)
							(end -0.254 -0.2286)
						)
						(arc
							(start -0.254 0.2286)
							(mid -0.239121 0.264521)
							(end -0.2032 0.2794)
						)
						(arc
							(start 0.2032 0.2794)
							(mid 0.239121 0.264521)
							(end 0.254 0.2286)
						)
						(arc
							(start 0.254 -0.2286)
							(mid 0.239121 -0.264521)
							(end 0.2032 -0.2794)
						)
					)
					(width 0)
					(fill yes)
				)
			)
		)
		(pad "2" smd custom
			(at 0 0.4318 90)
			(size 0.127 0.127)
			(layers "F.Cu" "F.Mask" "F.Paste")
			(net "P1V8")
			(options
				(clearance outline)
				(anchor circle)
			)
			(primitives
				(gr_poly
					(pts
						(arc
							(start -0.2032 -0.2794)
							(mid -0.239121 -0.264521)
							(end -0.254 -0.2286)
						)
						(arc
							(start -0.254 0.2286)
							(mid -0.239121 0.264521)
							(end -0.2032 0.2794)
						)
						(arc
							(start 0.2032 0.2794)
							(mid 0.239121 0.264521)
							(end 0.254 0.2286)
						)
						(arc
							(start 0.254 -0.2286)
							(mid 0.239121 -0.264521)
							(end 0.2032 -0.2794)
						)
					)
					(width 0)
					(fill yes)
				)
			)
		)
	)
	(footprint ""
		(layer "F.Cu")
		(at 55.245 -39.878 -90)
		(property "Reference" "R88"
			(at 0 0 270)
			(layer "F.SilkS")
			(hide yes)
			(effects
				(font
					(size 1.27 1.27)
				)
			)
		)
		(property "Value" "1KR2F-3-GP"
			(at 0.064008 -3.993896 270)
			(unlocked yes)
			(layer "F.Fab")
			(hide yes)
			(effects
				(font
					(size 1.016 1.016)
					(thickness 0.1524)
				)
			)
		)
		(property "Device Type" "R402H16"
			(at 0.064008 -5.517896 270)
			(unlocked yes)
			(layer "F.Fab")
			(hide yes)
			(effects
				(font
					(size 1.016 1.016)
					(thickness 0.1524)
				)
			)
		)
		(duplicate_pad_numbers_are_jumpers no)
		(fp_rect
			(start -0.381 0.8382)
			(end 0.381 -0.8382)
			(stroke
				(width 0)
				(type default)
			)
			(fill no)
			(layer "F.CrtYd")
		)
		(fp_rect
			(start -0.381 0.8382)
			(end 0.381 -0.8382)
			(stroke
				(width 0)
				(type default)
			)
			(fill no)
			(layer "F.Fab")
		)
		(pad "1" smd custom
			(at 0 -0.4318 270)
			(size 0.127 0.127)
			(layers "F.Cu" "F.Mask" "F.Paste")
			(net "GND")
			(options
				(clearance outline)
				(anchor circle)
			)
			(primitives
				(gr_poly
					(pts
						(arc
							(start -0.2032 -0.2794)
							(mid -0.239121 -0.264521)
							(end -0.254 -0.2286)
						)
						(arc
							(start -0.254 0.2286)
							(mid -0.239121 0.264521)
							(end -0.2032 0.2794)
						)
						(arc
							(start 0.2032 0.2794)
							(mid 0.239121 0.264521)
							(end 0.254 0.2286)
						)
						(arc
							(start 0.254 -0.2286)
							(mid 0.239121 -0.264521)
							(end 0.2032 -0.2794)
						)
					)
					(width 0)
					(fill yes)
				)
			)
		)
		(pad "2" smd custom
			(at 0 0.4318 270)
			(size 0.127 0.127)
			(layers "F.Cu" "F.Mask" "F.Paste")
			(net "P3V3")
			(options
				(clearance outline)
				(anchor circle)
			)
			(primitives
				(gr_poly
					(pts
						(arc
							(start -0.2032 -0.2794)
							(mid -0.239121 -0.264521)
							(end -0.254 -0.2286)
						)
						(arc
							(start -0.254 0.2286)
							(mid -0.239121 0.264521)
							(end -0.2032 0.2794)
						)
						(arc
							(start 0.2032 0.2794)
							(mid 0.239121 0.264521)
							(end 0.254 0.2286)
						)
						(arc
							(start 0.254 -0.2286)
							(mid 0.239121 -0.264521)
							(end 0.2032 -0.2794)
						)
					)
					(width 0)
					(fill yes)
				)
			)
		)
	)
	(footprint ""
		(layer "F.Cu")
		(at 8.509 -65.405 90)
		(property "Reference" "C181"
			(at 0 0 90)
			(layer "F.SilkS")
			(hide yes)
			(effects
				(font
					(size 1.27 1.27)
				)
			)
		)
		(property "Value" "SCD1U16V2KX-3GP"
			(at 1.1811 -2.7051 90)
			(unlocked yes)
			(layer "F.Fab")
			(hide yes)
			(effects
				(font
					(size 1.016 1.016)
					(thickness 0.1524)
				)
			)
		)
		(property "Device Type" "C402H22"
			(at 1.1811 -4.2291 90)
			(unlocked yes)
			(layer "F.Fab")
			(hide yes)
			(effects
				(font
					(size 1.016 1.016)
					(thickness 0.1524)
				)
			)
		)
		(duplicate_pad_numbers_are_jumpers no)
		(fp_rect
			(start -0.381 0.7366)
			(end 0.381 -0.7366)
			(stroke
				(width 0)
				(type default)
			)
			(fill no)
			(layer "F.CrtYd")
		)
		(fp_rect
			(start -0.381 0.7366)
			(end 0.381 -0.7366)
			(stroke
				(width 0)
				(type default)
			)
			(fill no)
			(layer "F.Fab")
		)
		(pad "1" smd custom
			(at 0 -0.4572 90)
			(size 0.1143 0.1143)
			(layers "F.Cu" "F.Mask" "F.Paste")
			(net "P2E_CPU_NGFF_C_RX_DN15")
			(options
				(clearance outline)
				(anchor circle)
			)
			(primitives
				(gr_poly
					(pts
						(arc
							(start -0.254 -0.1778)
							(mid -0.239121 -0.213721)
							(end -0.2032 -0.2286)
						)
						(arc
							(start 0.2032 -0.2286)
							(mid 0.239121 -0.213721)
							(end 0.254 -0.1778)
						)
						(arc
							(start 0.254 0.1778)
							(mid 0.239121 0.213721)
							(end 0.2032 0.2286)
						)
						(arc
							(start -0.2032 0.2286)
							(mid -0.239121 0.213721)
							(end -0.254 0.1778)
						)
					)
					(width 0)
					(fill yes)
				)
			)
		)
		(pad "2" smd custom
			(at 0 0.4572 90)
			(size 0.1143 0.1143)
			(layers "F.Cu" "F.Mask" "F.Paste")
			(net "P2E_CPU_NGFF_RX_DN15")
			(options
				(clearance outline)
				(anchor circle)
			)
			(primitives
				(gr_poly
					(pts
						(arc
							(start -0.254 -0.1778)
							(mid -0.239121 -0.213721)
							(end -0.2032 -0.2286)
						)
						(arc
							(start 0.2032 -0.2286)
							(mid 0.239121 -0.213721)
							(end 0.254 -0.1778)
						)
						(arc
							(start 0.254 0.1778)
							(mid 0.239121 0.213721)
							(end 0.2032 0.2286)
						)
						(arc
							(start -0.2032 0.2286)
							(mid -0.239121 0.213721)
							(end -0.254 0.1778)
						)
					)
					(width 0)
					(fill yes)
				)
			)
		)
	)
	(footprint ""
		(layer "F.Cu")
		(at 131.699 -51.689)
		(property "Reference" "R15"
			(at 0 0 0)
			(layer "F.SilkS")
			(hide yes)
			(effects
				(font
					(size 1.27 1.27)
				)
			)
		)
		(property "Value" "0R2J-2-GP"
			(at 1.7907 -1.1176 0)
			(unlocked yes)
			(layer "F.Fab")
			(hide yes)
			(effects
				(font
					(size 1.016 1.016)
					(thickness 0.1524)
				)
			)
		)
		(property "Device Type" "R402H16"
			(at 1.7907 -2.6416 0)
			(unlocked yes)
			(layer "F.Fab")
			(hide yes)
			(effects
				(font
					(size 1.016 1.016)
					(thickness 0.1524)
				)
			)
		)
		(duplicate_pad_numbers_are_jumpers no)
		(fp_rect
			(start -0.381 0.8382)
			(end 0.381 -0.8382)
			(stroke
				(width 0)
				(type default)
			)
			(fill no)
			(layer "F.CrtYd")
		)
		(fp_rect
			(start -0.381 0.8382)
			(end 0.381 -0.8382)
			(stroke
				(width 0)
				(type default)
			)
			(fill no)
			(layer "F.Fab")
		)
		(pad "1" smd custom
			(at 0 -0.4318)
			(size 0.127 0.127)
			(layers "F.Cu" "F.Mask" "F.Paste")
			(net "MEMORY_HOT_LV_R#")
			(options
				(clearance outline)
				(anchor circle)
			)
			(primitives
				(gr_poly
					(pts
						(arc
							(start -0.2032 -0.2794)
							(mid -0.239121 -0.264521)
							(end -0.254 -0.2286)
						)
						(arc
							(start -0.254 0.2286)
							(mid -0.239121 0.264521)
							(end -0.2032 0.2794)
						)
						(arc
							(start 0.2032 0.2794)
							(mid 0.239121 0.264521)
							(end 0.254 0.2286)
						)
						(arc
							(start 0.254 -0.2286)
							(mid 0.239121 -0.264521)
							(end 0.2032 -0.2794)
						)
					)
					(width 0)
					(fill yes)
				)
			)
		)
		(pad "2" smd custom
			(at 0 0.4318)
			(size 0.127 0.127)
			(layers "F.Cu" "F.Mask" "F.Paste")
			(net "MEMORY_HOT_LV_E2#")
			(options
				(clearance outline)
				(anchor circle)
			)
			(primitives
				(gr_poly
					(pts
						(arc
							(start -0.2032 -0.2794)
							(mid -0.239121 -0.264521)
							(end -0.254 -0.2286)
						)
						(arc
							(start -0.254 0.2286)
							(mid -0.239121 0.264521)
							(end -0.2032 0.2794)
						)
						(arc
							(start 0.2032 0.2794)
							(mid 0.239121 0.264521)
							(end 0.254 0.2286)
						)
						(arc
							(start 0.254 -0.2286)
							(mid 0.239121 -0.264521)
							(end 0.2032 -0.2794)
						)
					)
					(width 0)
					(fill yes)
				)
			)
		)
	)
	(footprint ""
		(layer "F.Cu")
		(at 190.4492 -27.5082)
		(property "Reference" "PC106"
			(at 0 0 0)
			(layer "F.SilkS")
			(hide yes)
			(effects
				(font
					(size 1.27 1.27)
				)
			)
		)
		(property "Value" "SC1U16V3KX-5GP"
			(at -0.0254 -2.0193 0)
			(unlocked yes)
			(layer "F.Fab")
			(hide yes)
			(effects
				(font
					(size 1.016 1.016)
					(thickness 0.1524)
				)
			)
		)
		(property "Device Type" "C603H36"
			(at -0.0254 -3.5433 0)
			(unlocked yes)
			(layer "F.Fab")
			(hide yes)
			(effects
				(font
					(size 1.016 1.016)
					(thickness 0.1524)
				)
			)
		)
		(duplicate_pad_numbers_are_jumpers no)
		(fp_line
			(start -0.4064 0)
			(end 0.4064 0)
			(stroke
				(width 0.2286)
				(type default)
			)
			(layer "F.SilkS")
		)
		(fp_rect
			(start -0.635 1.1811)
			(end 0.635 -1.1811)
			(stroke
				(width 0)
				(type default)
			)
			(fill no)
			(layer "F.CrtYd")
		)
		(fp_rect
			(start -0.635 1.1811)
			(end 0.635 -1.1811)
			(stroke
				(width 0)
				(type default)
			)
			(fill no)
			(layer "F.Fab")
		)
		(pad "1" smd custom
			(at 0 -0.6604)
			(size 0.19685 0.19685)
			(layers "F.Cu" "F.Mask" "F.Paste")
			(net "VR_PVDDR_A_VDD")
			(options
				(clearance outline)
				(anchor circle)
			)
			(primitives
				(gr_poly
					(pts
						(arc
							(start 0.508 -0.2921)
							(mid 0.478242 -0.363942)
							(end 0.4064 -0.3937)
						)
						(arc
							(start -0.4064 -0.3937)
							(mid -0.478242 -0.363942)
							(end -0.508 -0.2921)
						)
						(arc
							(start -0.508 0.2921)
							(mid -0.478242 0.363942)
							(end -0.4064 0.3937)
						)
						(arc
							(start 0.4064 0.3937)
							(mid 0.478242 0.363942)
							(end 0.508 0.2921)
						)
					)
					(width 0)
					(fill yes)
				)
			)
		)
		(pad "2" smd custom
			(at 0 0.6604)
			(size 0.19685 0.19685)
			(layers "F.Cu" "F.Mask" "F.Paste")
			(net "GND")
			(options
				(clearance outline)
				(anchor circle)
			)
			(primitives
				(gr_poly
					(pts
						(arc
							(start 0.508 -0.2921)
							(mid 0.478242 -0.363942)
							(end 0.4064 -0.3937)
						)
						(arc
							(start -0.4064 -0.3937)
							(mid -0.478242 -0.363942)
							(end -0.508 -0.2921)
						)
						(arc
							(start -0.508 0.2921)
							(mid -0.478242 0.363942)
							(end -0.4064 0.3937)
						)
						(arc
							(start 0.4064 0.3937)
							(mid 0.478242 0.363942)
							(end 0.508 0.2921)
						)
					)
					(width 0)
					(fill yes)
				)
			)
		)
	)
	(footprint ""
		(layer "F.Cu")
		(at 137.033 -49.657 180)
		(property "Reference" "SW1"
			(at 0 0 180)
			(layer "F.SilkS")
			(hide yes)
			(effects
				(font
					(size 1.27 1.27)
				)
			)
		)
		(property "Value" "SW-PUSH-2P-6-GP"
			(at -3.7973 -1.2573 180)
			(unlocked yes)
			(layer "F.Fab")
			(hide yes)
			(effects
				(font
					(size 1.016 1.016)
					(thickness 0.1524)
				)
			)
		)
		(property "Device Type" "TL1015AF160QG-2"
			(at -3.7973 -2.7813 180)
			(unlocked yes)
			(layer "F.Fab")
			(hide yes)
			(effects
				(font
					(size 1.016 1.016)
					(thickness 0.1524)
				)
			)
		)
		(duplicate_pad_numbers_are_jumpers no)
		(fp_poly
			(pts
				(xy -2.726944 0.01905) (xy -3.29057 0.582676) (xy -3.29057 -0.544576)
			)
			(stroke
				(width 0)
				(type default)
			)
			(fill yes)
			(layer "F.SilkS")
		)
		(fp_poly
			(pts
				(xy -2.2098 1.905) (xy -2.2098 0.8255) (xy -2.6797 0.8255) (xy -2.6797 -0.8255) (xy -2.2098 -0.8255)
				(xy -2.2098 -1.905) (xy 2.2098 -1.905) (xy 2.2098 -0.8255) (xy 2.6797 -0.8255) (xy 2.6797 0.8255)
				(xy 2.2098 0.8255) (xy 2.2098 1.905)
			)
			(stroke
				(width 0)
				(type default)
			)
			(fill no)
			(layer "F.CrtYd")
		)
		(fp_poly
			(pts
				(xy -2.2098 1.905) (xy -2.2098 0.8255) (xy -2.6797 0.8255) (xy -2.6797 -0.8255) (xy -2.2098 -0.8255)
				(xy -2.2098 -1.905) (xy 2.2098 -1.905) (xy 2.2098 -0.8255) (xy 2.6797 -0.8255) (xy 2.6797 0.8255)
				(xy 2.2098 0.8255) (xy 2.2098 1.905)
			)
			(stroke
				(width 0)
				(type default)
			)
			(fill no)
			(layer "F.Fab")
		)
		(pad "1" smd rect
			(at -2.074926 0 180)
			(size 0.9398 1.397)
			(layers "F.Cu" "F.Mask" "F.Paste")
			(net "C_NCONFIG#")
		)
		(pad "2" smd rect
			(at 2.074926 0 180)
			(size 0.9398 1.397)
			(layers "F.Cu" "F.Mask" "F.Paste")
			(net "GND")
		)
		(zone
			(layer "F.Cu")
			(hatch none 0.5)
			(connect_pads
				(clearance 0)
			)
			(min_thickness 0.25)
			(keepout
				(tracks allowed)
				(vias not_allowed)
				(pads allowed)
				(copperpour not_allowed)
				(footprints allowed)
			)
			(placement
				(enabled no)
				(sheetname "")
			)
			(fill
				(thermal_gap 0.5)
				(thermal_bridge_width 0.5)
				(island_removal_mode 0)
			)
			(polygon
				(pts
					(xy 136.033002 -51.55692) (xy 134.88289 -51.55692) (xy 134.88289 -50.807112) (xy 136.033002 -50.807112)
				)
			)
		)
		(zone
			(layer "F.Cu")
			(hatch none 0.5)
			(connect_pads
				(clearance 0)
			)
			(min_thickness 0.25)
			(keepout
				(tracks not_allowed)
				(vias allowed)
				(pads allowed)
				(copperpour not_allowed)
				(footprints allowed)
			)
			(placement
				(enabled no)
				(sheetname "")
			)
			(fill
				(thermal_gap 0.5)
				(thermal_bridge_width 0.5)
				(island_removal_mode 0)
			)
			(polygon
				(pts
					(xy 136.033002 -50.807112) (xy 136.033002 -51.55692) (xy 134.88289 -51.55692) (xy 134.88289 -50.807112)
				)
			)
		)
		(zone
			(layer "F.Cu")
			(hatch none 0.5)
			(connect_pads
				(clearance 0)
			)
			(min_thickness 0.25)
			(keepout
				(tracks allowed)
				(vias not_allowed)
				(pads allowed)
				(copperpour not_allowed)
				(footprints allowed)
			)
			(placement
				(enabled no)
				(sheetname "")
			)
			(fill
				(thermal_gap 0.5)
				(thermal_bridge_width 0.5)
				(island_removal_mode 0)
			)
			(polygon
				(pts
					(xy 136.033002 -48.506888) (xy 134.88289 -48.506888) (xy 134.88289 -47.75708) (xy 136.033002 -47.75708)
				)
			)
		)
		(zone
			(layer "F.Cu")
			(hatch none 0.5)
			(connect_pads
				(clearance 0)
			)
			(min_thickness 0.25)
			(keepout
				(tracks not_allowed)
				(vias allowed)
				(pads allowed)
				(copperpour not_allowed)
				(footprints allowed)
			)
			(placement
				(enabled no)
				(sheetname "")
			)
			(fill
				(thermal_gap 0.5)
				(thermal_bridge_width 0.5)
				(island_removal_mode 0)
			)
			(polygon
				(pts
					(xy 136.033002 -47.75708) (xy 136.033002 -48.506888) (xy 134.88289 -48.506888) (xy 134.88289 -47.75708)
				)
			)
		)
		(zone
			(layer "F.Cu")
			(hatch none 0.5)
			(connect_pads
				(clearance 0)
			)
			(min_thickness 0.25)
			(keepout
				(tracks allowed)
				(vias not_allowed)
				(pads allowed)
				(copperpour not_allowed)
				(footprints allowed)
			)
			(placement
				(enabled no)
				(sheetname "")
			)
			(fill
				(thermal_gap 0.5)
				(thermal_bridge_width 0.5)
				(island_removal_mode 0)
			)
			(polygon
				(pts
					(xy 139.18311 -51.55692) (xy 138.032998 -51.55692) (xy 138.032998 -50.807112) (xy 139.18311 -50.807112)
				)
			)
		)
		(zone
			(layer "F.Cu")
			(hatch none 0.5)
			(connect_pads
				(clearance 0)
			)
			(min_thickness 0.25)
			(keepout
				(tracks not_allowed)
				(vias allowed)
				(pads allowed)
				(copperpour not_allowed)
				(footprints allowed)
			)
			(placement
				(enabled no)
				(sheetname "")
			)
			(fill
				(thermal_gap 0.5)
				(thermal_bridge_width 0.5)
				(island_removal_mode 0)
			)
			(polygon
				(pts
					(xy 139.18311 -50.807112) (xy 139.18311 -51.55692) (xy 138.032998 -51.55692) (xy 138.032998 -50.807112)
				)
			)
		)
		(zone
			(layer "F.Cu")
			(hatch none 0.5)
			(connect_pads
				(clearance 0)
			)
			(min_thickness 0.25)
			(keepout
				(tracks allowed)
				(vias not_allowed)
				(pads allowed)
				(copperpour not_allowed)
				(footprints allowed)
			)
			(placement
				(enabled no)
				(sheetname "")
			)
			(fill
				(thermal_gap 0.5)
				(thermal_bridge_width 0.5)
				(island_removal_mode 0)
			)
			(polygon
				(pts
					(xy 139.18311 -48.506888) (xy 138.032998 -48.506888) (xy 138.032998 -47.75708) (xy 139.18311 -47.75708)
				)
			)
		)
		(zone
			(layer "F.Cu")
			(hatch none 0.5)
			(connect_pads
				(clearance 0)
			)
			(min_thickness 0.25)
			(keepout
				(tracks not_allowed)
				(vias allowed)
				(pads allowed)
				(copperpour not_allowed)
				(footprints allowed)
			)
			(placement
				(enabled no)
				(sheetname "")
			)
			(fill
				(thermal_gap 0.5)
				(thermal_bridge_width 0.5)
				(island_removal_mode 0)
			)
			(polygon
				(pts
					(xy 139.18311 -47.75708) (xy 139.18311 -48.506888) (xy 138.032998 -48.506888) (xy 138.032998 -47.75708)
				)
			)
		)
	)
	(footprint ""
		(layer "F.Cu")
		(at 46.1264 -44.704 -90)
		(property "Reference" "C29"
			(at 0 0 270)
			(layer "F.SilkS")
			(hide yes)
			(effects
				(font
					(size 1.27 1.27)
				)
			)
		)
		(property "Value" "SCD1U10V2KX-5GP"
			(at 1.8923 -1.2065 270)
			(unlocked yes)
			(layer "F.Fab")
			(hide yes)
			(effects
				(font
					(size 1.016 1.016)
					(thickness 0.1524)
				)
			)
		)
		(property "Device Type" "C402H22"
			(at 1.8923 -2.7305 270)
			(unlocked yes)
			(layer "F.Fab")
			(hide yes)
			(effects
				(font
					(size 1.016 1.016)
					(thickness 0.1524)
				)
			)
		)
		(duplicate_pad_numbers_are_jumpers no)
		(fp_rect
			(start -0.381 0.7366)
			(end 0.381 -0.7366)
			(stroke
				(width 0)
				(type default)
			)
			(fill no)
			(layer "F.CrtYd")
		)
		(fp_rect
			(start -0.381 0.7366)
			(end 0.381 -0.7366)
			(stroke
				(width 0)
				(type default)
			)
			(fill no)
			(layer "F.Fab")
		)
		(pad "1" smd custom
			(at 0 -0.4572 270)
			(size 0.1143 0.1143)
			(layers "F.Cu" "F.Mask" "F.Paste")
			(net "P3V3_STBY")
			(options
				(clearance outline)
				(anchor circle)
			)
			(primitives
				(gr_poly
					(pts
						(arc
							(start -0.254 -0.1778)
							(mid -0.239121 -0.213721)
							(end -0.2032 -0.2286)
						)
						(arc
							(start 0.2032 -0.2286)
							(mid 0.239121 -0.213721)
							(end 0.254 -0.1778)
						)
						(arc
							(start 0.254 0.1778)
							(mid 0.239121 0.213721)
							(end 0.2032 0.2286)
						)
						(arc
							(start -0.2032 0.2286)
							(mid -0.239121 0.213721)
							(end -0.254 0.1778)
						)
					)
					(width 0)
					(fill yes)
				)
			)
		)
		(pad "2" smd custom
			(at 0 0.4572 270)
			(size 0.1143 0.1143)
			(layers "F.Cu" "F.Mask" "F.Paste")
			(net "GND")
			(options
				(clearance outline)
				(anchor circle)
			)
			(primitives
				(gr_poly
					(pts
						(arc
							(start -0.254 -0.1778)
							(mid -0.239121 -0.213721)
							(end -0.2032 -0.2286)
						)
						(arc
							(start 0.2032 -0.2286)
							(mid 0.239121 -0.213721)
							(end 0.254 -0.1778)
						)
						(arc
							(start 0.254 0.1778)
							(mid 0.239121 0.213721)
							(end 0.2032 0.2286)
						)
						(arc
							(start -0.2032 0.2286)
							(mid -0.239121 0.213721)
							(end -0.254 0.1778)
						)
					)
					(width 0)
					(fill yes)
				)
			)
		)
	)
	(footprint ""
		(layer "F.Cu")
		(at 21.209 -28.829 90)
		(property "Reference" "PL5"
			(at 0 0 90)
			(layer "F.SilkS")
			(hide yes)
			(effects
				(font
					(size 1.27 1.27)
				)
			)
		)
		(property "Value" "COIL-D68UH-9-GP"
			(at -4.522978 -6.630924 90)
			(unlocked yes)
			(layer "F.Fab")
			(hide yes)
			(effects
				(font
					(size 1.016 1.016)
					(thickness 0.1524)
				)
			)
		)
		(property "Device Type" "L7066-1830-UH119"
			(at -4.522978 -8.154924 90)
			(unlocked yes)
			(layer "F.Fab")
			(hide yes)
			(effects
				(font
					(size 1.016 1.016)
					(thickness 0.1524)
				)
			)
		)
		(duplicate_pad_numbers_are_jumpers no)
		(fp_rect
			(start -3.556 4.1148)
			(end 3.556 -4.1148)
			(stroke
				(width 0)
				(type default)
			)
			(fill no)
			(layer "F.CrtYd")
		)
		(fp_rect
			(start -3.556 4.1148)
			(end 3.556 -4.1148)
			(stroke
				(width 0)
				(type default)
			)
			(fill no)
			(layer "F.Fab")
		)
		(pad "1" smd rect
			(at 0 -2.652522 90)
			(size 3.5052 2.667)
			(layers "F.Cu" "F.Mask" "F.Paste")
			(net "P1V0_LX")
		)
		(pad "2" smd rect
			(at 0 2.652522 90)
			(size 3.5052 2.667)
			(layers "F.Cu" "F.Mask" "F.Paste")
			(net "P1V0")
		)
	)
	(footprint ""
		(layer "F.Cu")
		(at 140.589 -50.5968 -90)
		(property "Reference" "R91"
			(at 0 0 270)
			(layer "F.SilkS")
			(hide yes)
			(effects
				(font
					(size 1.27 1.27)
				)
			)
		)
		(property "Value" "4K7R2F-GP"
			(at 1.7907 -1.1176 270)
			(unlocked yes)
			(layer "F.Fab")
			(hide yes)
			(effects
				(font
					(size 1.016 1.016)
					(thickness 0.1524)
				)
			)
		)
		(property "Device Type" "R402H16"
			(at 1.7907 -2.6416 270)
			(unlocked yes)
			(layer "F.Fab")
			(hide yes)
			(effects
				(font
					(size 1.016 1.016)
					(thickness 0.1524)
				)
			)
		)
		(duplicate_pad_numbers_are_jumpers no)
		(fp_rect
			(start -0.381 0.8382)
			(end 0.381 -0.8382)
			(stroke
				(width 0)
				(type default)
			)
			(fill no)
			(layer "F.CrtYd")
		)
		(fp_rect
			(start -0.381 0.8382)
			(end 0.381 -0.8382)
			(stroke
				(width 0)
				(type default)
			)
			(fill no)
			(layer "F.Fab")
		)
		(pad "1" smd custom
			(at 0 -0.4318 270)
			(size 0.127 0.127)
			(layers "F.Cu" "F.Mask" "F.Paste")
			(net "SPI_SW_ADDR2")
			(options
				(clearance outline)
				(anchor circle)
			)
			(primitives
				(gr_poly
					(pts
						(arc
							(start -0.2032 -0.2794)
							(mid -0.239121 -0.264521)
							(end -0.254 -0.2286)
						)
						(arc
							(start -0.254 0.2286)
							(mid -0.239121 0.264521)
							(end -0.2032 0.2794)
						)
						(arc
							(start 0.2032 0.2794)
							(mid 0.239121 0.264521)
							(end 0.254 0.2286)
						)
						(arc
							(start 0.254 -0.2286)
							(mid 0.239121 -0.264521)
							(end 0.2032 -0.2794)
						)
					)
					(width 0)
					(fill yes)
				)
			)
		)
		(pad "2" smd custom
			(at 0 0.4318 270)
			(size 0.127 0.127)
			(layers "F.Cu" "F.Mask" "F.Paste")
			(net "GND")
			(options
				(clearance outline)
				(anchor circle)
			)
			(primitives
				(gr_poly
					(pts
						(arc
							(start -0.2032 -0.2794)
							(mid -0.239121 -0.264521)
							(end -0.254 -0.2286)
						)
						(arc
							(start -0.254 0.2286)
							(mid -0.239121 0.264521)
							(end -0.2032 0.2794)
						)
						(arc
							(start 0.2032 0.2794)
							(mid 0.239121 0.264521)
							(end 0.254 0.2286)
						)
						(arc
							(start 0.254 -0.2286)
							(mid 0.239121 -0.264521)
							(end 0.2032 -0.2794)
						)
					)
					(width 0)
					(fill yes)
				)
			)
		)
	)
	(footprint ""
		(layer "F.Cu")
		(at 169.6974 -12.955778 180)
		(property "Reference" "C373"
			(at 0 0 180)
			(layer "F.SilkS")
			(hide yes)
			(effects
				(font
					(size 1.27 1.27)
				)
			)
		)
		(property "Value" "SC47U6D3V5MX-1-GP"
			(at 0 -4.9022 180)
			(unlocked yes)
			(layer "F.Fab")
			(hide yes)
			(effects
				(font
					(size 1.016 1.016)
					(thickness 0.1524)
				)
			)
		)
		(property "Device Type" "C805H54"
			(at 0 -6.8072 180)
			(unlocked yes)
			(layer "F.Fab")
			(hide yes)
			(effects
				(font
					(size 1.016 1.016)
					(thickness 0.1524)
				)
			)
		)
		(duplicate_pad_numbers_are_jumpers no)
		(fp_line
			(start 0.6096 0)
			(end -0.6096 0)
			(stroke
				(width 0.3048)
				(type default)
			)
			(layer "F.SilkS")
		)
		(fp_poly
			(pts
				(xy -0.9017 1.4351) (xy 0.9017 1.4351) (xy 0.9017 -1.4351) (xy -0.9017 -1.4351)
			)
			(stroke
				(width 0)
				(type default)
			)
			(fill no)
			(layer "F.CrtYd")
		)
		(fp_poly
			(pts
				(xy 0.9017 1.4351) (xy 0.9017 -1.4351) (xy -0.9017 -1.4351) (xy -0.9017 1.4351)
			)
			(stroke
				(width 0)
				(type default)
			)
			(fill no)
			(layer "F.Fab")
		)
		(pad "1" smd rect
			(at 0 -0.8382 180)
			(size 1.5494 0.9398)
			(layers "F.Cu" "F.Mask" "F.Paste")
			(net "PV_VDDR")
		)
		(pad "2" smd rect
			(at 0 0.8382 180)
			(size 1.5494 0.9398)
			(layers "F.Cu" "F.Mask" "F.Paste")
			(net "GND")
		)
	)
	(footprint ""
		(layer "F.Cu")
		(at 18.482818 -63.375286 -90)
		(property "Reference" "PR30"
			(at 0 0 270)
			(layer "F.SilkS")
			(hide yes)
			(effects
				(font
					(size 1.27 1.27)
				)
			)
		)
		(property "Value" "5K1R2F-2-GP"
			(at 1.7907 -1.1176 270)
			(unlocked yes)
			(layer "F.Fab")
			(hide yes)
			(effects
				(font
					(size 1.016 1.016)
					(thickness 0.1524)
				)
			)
		)
		(property "Device Type" "R402H16"
			(at 1.7907 -2.6416 270)
			(unlocked yes)
			(layer "F.Fab")
			(hide yes)
			(effects
				(font
					(size 1.016 1.016)
					(thickness 0.1524)
				)
			)
		)
		(duplicate_pad_numbers_are_jumpers no)
		(fp_rect
			(start -0.381 0.8382)
			(end 0.381 -0.8382)
			(stroke
				(width 0)
				(type default)
			)
			(fill no)
			(layer "F.CrtYd")
		)
		(fp_rect
			(start -0.381 0.8382)
			(end 0.381 -0.8382)
			(stroke
				(width 0)
				(type default)
			)
			(fill no)
			(layer "F.Fab")
		)
		(pad "1" smd custom
			(at 0 -0.4318 270)
			(size 0.127 0.127)
			(layers "F.Cu" "F.Mask" "F.Paste")
			(net "VR_PVNN_COMP")
			(options
				(clearance outline)
				(anchor circle)
			)
			(primitives
				(gr_poly
					(pts
						(arc
							(start -0.2032 -0.2794)
							(mid -0.239121 -0.264521)
							(end -0.254 -0.2286)
						)
						(arc
							(start -0.254 0.2286)
							(mid -0.239121 0.264521)
							(end -0.2032 0.2794)
						)
						(arc
							(start 0.2032 0.2794)
							(mid 0.239121 0.264521)
							(end 0.254 0.2286)
						)
						(arc
							(start 0.254 -0.2286)
							(mid 0.239121 -0.264521)
							(end 0.2032 -0.2794)
						)
					)
					(width 0)
					(fill yes)
				)
			)
		)
		(pad "2" smd custom
			(at 0 0.4318 270)
			(size 0.127 0.127)
			(layers "F.Cu" "F.Mask" "F.Paste")
			(net "VR_PVNN_VW")
			(options
				(clearance outline)
				(anchor circle)
			)
			(primitives
				(gr_poly
					(pts
						(arc
							(start -0.2032 -0.2794)
							(mid -0.239121 -0.264521)
							(end -0.254 -0.2286)
						)
						(arc
							(start -0.254 0.2286)
							(mid -0.239121 0.264521)
							(end -0.2032 0.2794)
						)
						(arc
							(start 0.2032 0.2794)
							(mid 0.239121 0.264521)
							(end 0.254 0.2286)
						)
						(arc
							(start 0.254 -0.2286)
							(mid 0.239121 -0.264521)
							(end 0.2032 -0.2794)
						)
					)
					(width 0)
					(fill yes)
				)
			)
		)
	)
	(footprint ""
		(layer "F.Cu")
		(at 12.9286 -63.6016 90)
		(property "Reference" "PR36"
			(at 0 0 90)
			(layer "F.SilkS")
			(hide yes)
			(effects
				(font
					(size 1.27 1.27)
				)
			)
		)
		(property "Value" "1K91R2F-1-GP"
			(at 1.7907 -1.1176 90)
			(unlocked yes)
			(layer "F.Fab")
			(hide yes)
			(effects
				(font
					(size 1.016 1.016)
					(thickness 0.1524)
				)
			)
		)
		(property "Device Type" "R402H16"
			(at 1.7907 -2.6416 90)
			(unlocked yes)
			(layer "F.Fab")
			(hide yes)
			(effects
				(font
					(size 1.016 1.016)
					(thickness 0.1524)
				)
			)
		)
		(duplicate_pad_numbers_are_jumpers no)
		(fp_rect
			(start -0.381 0.8382)
			(end 0.381 -0.8382)
			(stroke
				(width 0)
				(type default)
			)
			(fill no)
			(layer "F.CrtYd")
		)
		(fp_rect
			(start -0.381 0.8382)
			(end 0.381 -0.8382)
			(stroke
				(width 0)
				(type default)
			)
			(fill no)
			(layer "F.Fab")
		)
		(pad "1" smd custom
			(at 0 -0.4318 90)
			(size 0.127 0.127)
			(layers "F.Cu" "F.Mask" "F.Paste")
			(net "P3V3_STBY")
			(options
				(clearance outline)
				(anchor circle)
			)
			(primitives
				(gr_poly
					(pts
						(arc
							(start -0.2032 -0.2794)
							(mid -0.239121 -0.264521)
							(end -0.254 -0.2286)
						)
						(arc
							(start -0.254 0.2286)
							(mid -0.239121 0.264521)
							(end -0.2032 0.2794)
						)
						(arc
							(start 0.2032 0.2794)
							(mid 0.239121 0.264521)
							(end 0.254 0.2286)
						)
						(arc
							(start 0.254 -0.2286)
							(mid 0.239121 -0.264521)
							(end 0.2032 -0.2794)
						)
					)
					(width 0)
					(fill yes)
				)
			)
		)
		(pad "2" smd custom
			(at 0 0.4318 90)
			(size 0.127 0.127)
			(layers "F.Cu" "F.Mask" "F.Paste")
			(net "PWRGD_PVCCP_VNN_PG")
			(options
				(clearance outline)
				(anchor circle)
			)
			(primitives
				(gr_poly
					(pts
						(arc
							(start -0.2032 -0.2794)
							(mid -0.239121 -0.264521)
							(end -0.254 -0.2286)
						)
						(arc
							(start -0.254 0.2286)
							(mid -0.239121 0.264521)
							(end -0.2032 0.2794)
						)
						(arc
							(start 0.2032 0.2794)
							(mid 0.239121 0.264521)
							(end 0.254 0.2286)
						)
						(arc
							(start 0.254 -0.2286)
							(mid 0.239121 -0.264521)
							(end 0.2032 -0.2794)
						)
					)
					(width 0)
					(fill yes)
				)
			)
		)
	)
	(footprint ""
		(layer "F.Cu")
		(at 18.2372 -43.942 180)
		(property "Reference" "PC176"
			(at 0 0 180)
			(layer "F.SilkS")
			(hide yes)
			(effects
				(font
					(size 1.27 1.27)
				)
			)
		)
		(property "Value" "SC2K2P50V3KX-GP"
			(at -0.0254 -2.0193 180)
			(unlocked yes)
			(layer "F.Fab")
			(hide yes)
			(effects
				(font
					(size 1.016 1.016)
					(thickness 0.1524)
				)
			)
		)
		(property "Device Type" "C603"
			(at -0.0254 -3.5433 180)
			(unlocked yes)
			(layer "F.Fab")
			(hide yes)
			(effects
				(font
					(size 1.016 1.016)
					(thickness 0.1524)
				)
			)
		)
		(duplicate_pad_numbers_are_jumpers no)
		(fp_line
			(start -0.4064 0)
			(end 0.4064 0)
			(stroke
				(width 0.2032)
				(type default)
			)
			(layer "F.SilkS")
		)
		(fp_rect
			(start -0.635 1.1811)
			(end 0.635 -1.1811)
			(stroke
				(width 0)
				(type default)
			)
			(fill no)
			(layer "F.CrtYd")
		)
		(fp_rect
			(start -0.635 1.1811)
			(end 0.635 -1.1811)
			(stroke
				(width 0)
				(type default)
			)
			(fill no)
			(layer "F.Fab")
		)
		(pad "1" smd custom
			(at 0 -0.6604 180)
			(size 0.19685 0.19685)
			(layers "F.Cu" "F.Mask" "F.Paste")
			(net "P3V3_STBY_LL")
			(options
				(clearance outline)
				(anchor circle)
			)
			(primitives
				(gr_poly
					(pts
						(arc
							(start 0.508 -0.2921)
							(mid 0.478242 -0.363942)
							(end 0.4064 -0.3937)
						)
						(arc
							(start -0.4064 -0.3937)
							(mid -0.478242 -0.363942)
							(end -0.508 -0.2921)
						)
						(arc
							(start -0.508 0.2921)
							(mid -0.478242 0.363942)
							(end -0.4064 0.3937)
						)
						(arc
							(start 0.4064 0.3937)
							(mid 0.478242 0.363942)
							(end 0.508 0.2921)
						)
					)
					(width 0)
					(fill yes)
				)
			)
		)
		(pad "2" smd custom
			(at 0 0.6604 180)
			(size 0.19685 0.19685)
			(layers "F.Cu" "F.Mask" "F.Paste")
			(net "P3V3_STBY_SNB")
			(options
				(clearance outline)
				(anchor circle)
			)
			(primitives
				(gr_poly
					(pts
						(arc
							(start 0.508 -0.2921)
							(mid 0.478242 -0.363942)
							(end 0.4064 -0.3937)
						)
						(arc
							(start -0.4064 -0.3937)
							(mid -0.478242 -0.363942)
							(end -0.508 -0.2921)
						)
						(arc
							(start -0.508 0.2921)
							(mid -0.478242 0.363942)
							(end -0.4064 0.3937)
						)
						(arc
							(start 0.4064 0.3937)
							(mid 0.478242 0.363942)
							(end 0.508 0.2921)
						)
					)
					(width 0)
					(fill yes)
				)
			)
		)
	)
	(footprint ""
		(layer "F.Cu")
		(at 140.83792 -58.669428 -90)
		(property "Reference" "PR61"
			(at 0 0 270)
			(layer "F.SilkS")
			(hide yes)
			(effects
				(font
					(size 1.27 1.27)
				)
			)
		)
		(property "Value" "10R3F-GP"
			(at -0.0254 -2.5146 270)
			(unlocked yes)
			(layer "F.Fab")
			(hide yes)
			(effects
				(font
					(size 1.016 1.016)
					(thickness 0.1524)
				)
			)
		)
		(property "Device Type" "R603H22"
			(at -0.0254 -4.0386 270)
			(unlocked yes)
			(layer "F.Fab")
			(hide yes)
			(effects
				(font
					(size 1.016 1.016)
					(thickness 0.1524)
				)
			)
		)
		(duplicate_pad_numbers_are_jumpers no)
		(fp_line
			(start -0.2032 0)
			(end -0.4191 0)
			(stroke
				(width 0.2032)
				(type default)
			)
			(layer "F.SilkS")
		)
		(fp_line
			(start 0.4318 0)
			(end 0.2032 0)
			(stroke
				(width 0.2032)
				(type default)
			)
			(layer "F.SilkS")
		)
		(fp_rect
			(start -0.635 1.1811)
			(end 0.635 -1.1811)
			(stroke
				(width 0)
				(type default)
			)
			(fill no)
			(layer "F.CrtYd")
		)
		(fp_rect
			(start -0.635 1.1811)
			(end 0.635 -1.1811)
			(stroke
				(width 0)
				(type default)
			)
			(fill no)
			(layer "F.Fab")
		)
		(pad "1" smd custom
			(at 0 -0.6604 270)
			(size 0.19685 0.19685)
			(layers "F.Cu" "F.Mask" "F.Paste")
			(net "P3V3_STBY")
			(options
				(clearance outline)
				(anchor circle)
			)
			(primitives
				(gr_poly
					(pts
						(arc
							(start 0.508 -0.2921)
							(mid 0.478242 -0.363942)
							(end 0.4064 -0.3937)
						)
						(arc
							(start -0.4064 -0.3937)
							(mid -0.478242 -0.363942)
							(end -0.508 -0.2921)
						)
						(arc
							(start -0.508 0.2921)
							(mid -0.478242 0.363942)
							(end -0.4064 0.3937)
						)
						(arc
							(start 0.4064 0.3937)
							(mid 0.478242 0.363942)
							(end 0.508 0.2921)
						)
					)
					(width 0)
					(fill yes)
				)
			)
		)
		(pad "2" smd custom
			(at 0 0.6604 270)
			(size 0.19685 0.19685)
			(layers "F.Cu" "F.Mask" "F.Paste")
			(net "PV_VTT_DDR_VIN")
			(options
				(clearance outline)
				(anchor circle)
			)
			(primitives
				(gr_poly
					(pts
						(arc
							(start 0.508 -0.2921)
							(mid 0.478242 -0.363942)
							(end 0.4064 -0.3937)
						)
						(arc
							(start -0.4064 -0.3937)
							(mid -0.478242 -0.363942)
							(end -0.508 -0.2921)
						)
						(arc
							(start -0.508 0.2921)
							(mid -0.478242 0.363942)
							(end -0.4064 0.3937)
						)
						(arc
							(start 0.4064 0.3937)
							(mid 0.478242 0.363942)
							(end 0.508 0.2921)
						)
					)
					(width 0)
					(fill yes)
				)
			)
		)
	)
	(footprint ""
		(layer "F.Cu")
		(at 42.418 -42.926)
		(property "Reference" "R65"
			(at 0 0 0)
			(layer "F.SilkS")
			(hide yes)
			(effects
				(font
					(size 1.27 1.27)
				)
			)
		)
		(property "Value" "33R2F-3-GP"
			(at 1.7907 -1.1176 0)
			(unlocked yes)
			(layer "F.Fab")
			(hide yes)
			(effects
				(font
					(size 1.016 1.016)
					(thickness 0.1524)
				)
			)
		)
		(property "Device Type" "R402H16"
			(at 1.7907 -2.6416 0)
			(unlocked yes)
			(layer "F.Fab")
			(hide yes)
			(effects
				(font
					(size 1.016 1.016)
					(thickness 0.1524)
				)
			)
		)
		(duplicate_pad_numbers_are_jumpers no)
		(fp_rect
			(start -0.381 0.8382)
			(end 0.381 -0.8382)
			(stroke
				(width 0)
				(type default)
			)
			(fill no)
			(layer "F.CrtYd")
		)
		(fp_rect
			(start -0.381 0.8382)
			(end 0.381 -0.8382)
			(stroke
				(width 0)
				(type default)
			)
			(fill no)
			(layer "F.Fab")
		)
		(pad "1" smd custom
			(at 0 -0.4318)
			(size 0.127 0.127)
			(layers "F.Cu" "F.Mask" "F.Paste")
			(net "CLK_GEN_DELAY2_PG")
			(options
				(clearance outline)
				(anchor circle)
			)
			(primitives
				(gr_poly
					(pts
						(arc
							(start -0.2032 -0.2794)
							(mid -0.239121 -0.264521)
							(end -0.254 -0.2286)
						)
						(arc
							(start -0.254 0.2286)
							(mid -0.239121 0.264521)
							(end -0.2032 0.2794)
						)
						(arc
							(start 0.2032 0.2794)
							(mid 0.239121 0.264521)
							(end 0.254 0.2286)
						)
						(arc
							(start 0.254 -0.2286)
							(mid 0.239121 -0.264521)
							(end 0.2032 -0.2794)
						)
					)
					(width 0)
					(fill yes)
				)
			)
		)
		(pad "2" smd custom
			(at 0 0.4318)
			(size 0.127 0.127)
			(layers "F.Cu" "F.Mask" "F.Paste")
			(net "CLK_GEN_PG")
			(options
				(clearance outline)
				(anchor circle)
			)
			(primitives
				(gr_poly
					(pts
						(arc
							(start -0.2032 -0.2794)
							(mid -0.239121 -0.264521)
							(end -0.254 -0.2286)
						)
						(arc
							(start -0.254 0.2286)
							(mid -0.239121 0.264521)
							(end -0.2032 0.2794)
						)
						(arc
							(start 0.2032 0.2794)
							(mid 0.239121 0.264521)
							(end 0.254 0.2286)
						)
						(arc
							(start 0.254 -0.2286)
							(mid 0.239121 -0.264521)
							(end 0.2032 -0.2794)
						)
					)
					(width 0)
					(fill yes)
				)
			)
		)
	)
	(footprint ""
		(layer "F.Cu")
		(at 6.096 -32.004 180)
		(property "Reference" "PR203"
			(at 0 0 180)
			(layer "F.SilkS")
			(hide yes)
			(effects
				(font
					(size 1.27 1.27)
				)
			)
		)
		(property "Value" "100KR2F-L1-GP"
			(at 1.7907 -1.1176 180)
			(unlocked yes)
			(layer "F.Fab")
			(hide yes)
			(effects
				(font
					(size 1.016 1.016)
					(thickness 0.1524)
				)
			)
		)
		(property "Device Type" "R402H16"
			(at 1.7907 -2.6416 180)
			(unlocked yes)
			(layer "F.Fab")
			(hide yes)
			(effects
				(font
					(size 1.016 1.016)
					(thickness 0.1524)
				)
			)
		)
		(duplicate_pad_numbers_are_jumpers no)
		(fp_rect
			(start -0.381 0.8382)
			(end 0.381 -0.8382)
			(stroke
				(width 0)
				(type default)
			)
			(fill no)
			(layer "F.CrtYd")
		)
		(fp_rect
			(start -0.381 0.8382)
			(end 0.381 -0.8382)
			(stroke
				(width 0)
				(type default)
			)
			(fill no)
			(layer "F.Fab")
		)
		(pad "1" smd custom
			(at 0 -0.4318 180)
			(size 0.127 0.127)
			(layers "F.Cu" "F.Mask" "F.Paste")
			(net "AGND_P3V3_STBY")
			(options
				(clearance outline)
				(anchor circle)
			)
			(primitives
				(gr_poly
					(pts
						(arc
							(start -0.2032 -0.2794)
							(mid -0.239121 -0.264521)
							(end -0.254 -0.2286)
						)
						(arc
							(start -0.254 0.2286)
							(mid -0.239121 0.264521)
							(end -0.2032 0.2794)
						)
						(arc
							(start 0.2032 0.2794)
							(mid 0.239121 0.264521)
							(end 0.254 0.2286)
						)
						(arc
							(start 0.254 -0.2286)
							(mid 0.239121 -0.264521)
							(end 0.2032 -0.2794)
						)
					)
					(width 0)
					(fill yes)
				)
			)
		)
		(pad "2" smd custom
			(at 0 0.4318 180)
			(size 0.127 0.127)
			(layers "F.Cu" "F.Mask" "F.Paste")
			(net "P3V3_STBY_MODE")
			(options
				(clearance outline)
				(anchor circle)
			)
			(primitives
				(gr_poly
					(pts
						(arc
							(start -0.2032 -0.2794)
							(mid -0.239121 -0.264521)
							(end -0.254 -0.2286)
						)
						(arc
							(start -0.254 0.2286)
							(mid -0.239121 0.264521)
							(end -0.2032 0.2794)
						)
						(arc
							(start 0.2032 0.2794)
							(mid 0.239121 0.264521)
							(end 0.254 0.2286)
						)
						(arc
							(start 0.254 -0.2286)
							(mid 0.239121 -0.264521)
							(end 0.2032 -0.2794)
						)
					)
					(width 0)
					(fill yes)
				)
			)
		)
	)
	(footprint ""
		(layer "F.Cu")
		(at 52.767992 -28.796234 -90)
		(property "Reference" "SKT1"
			(at 0 0 270)
			(layer "F.SilkS")
			(hide yes)
			(effects
				(font
					(size 1.27 1.27)
				)
			)
		)
		(property "Value" "SKT-G6179T010-001-GP"
			(at -7.4676 -8.382 270)
			(unlocked yes)
			(layer "F.Fab")
			(hide yes)
			(effects
				(font
					(size 1.016 1.016)
					(thickness 0.1524)
				)
			)
		)
		(property "Device Type" "G6179HT0321-001"
			(at -7.4676 -9.906 270)
			(unlocked yes)
			(layer "F.Fab")
			(hide yes)
			(effects
				(font
					(size 1.016 1.016)
					(thickness 0.1524)
				)
			)
		)
		(duplicate_pad_numbers_are_jumpers no)
		(fp_line
			(start -5.2832 5.6007)
			(end -5.2832 2.2479)
			(stroke
				(width 0.1524)
				(type default)
			)
			(layer "F.SilkS")
		)
		(fp_line
			(start 4.8768 5.6007)
			(end -5.2832 5.6007)
			(stroke
				(width 0.1524)
				(type default)
			)
			(layer "F.SilkS")
		)
		(fp_line
			(start -8.9662 2.2479)
			(end -8.9662 -2.2479)
			(stroke
				(width 0.1524)
				(type default)
			)
			(layer "F.SilkS")
		)
		(fp_line
			(start -5.2832 2.2479)
			(end -8.9662 2.2479)
			(stroke
				(width 0.1524)
				(type default)
			)
			(layer "F.SilkS")
		)
		(fp_line
			(start -8.9662 -2.2479)
			(end -5.2832 -2.2479)
			(stroke
				(width 0.1524)
				(type default)
			)
			(layer "F.SilkS")
		)
		(fp_line
			(start -5.2832 -2.2479)
			(end -5.2832 -5.6007)
			(stroke
				(width 0.1524)
				(type default)
			)
			(layer "F.SilkS")
		)
		(fp_line
			(start -5.2832 -5.6007)
			(end 4.8768 -5.6007)
			(stroke
				(width 0.1524)
				(type default)
			)
			(layer "F.SilkS")
		)
		(fp_line
			(start 4.8768 -5.6007)
			(end 4.8768 5.6007)
			(stroke
				(width 0.1524)
				(type default)
			)
			(layer "F.SilkS")
		)
		(fp_poly
			(pts
				(xy 1.397 -6.1849) (xy 2.413 -6.1849) (xy 1.905 -5.6769)
			)
			(stroke
				(width 0)
				(type default)
			)
			(fill yes)
			(layer "F.SilkS")
		)
		(fp_poly
			(pts
				(xy -2.2225 2.20853) (xy 2.2225 2.20853) (xy 2.2225 -2.20853) (xy -2.2225 -2.20853)
			)
			(stroke
				(width 0)
				(type default)
			)
			(fill yes)
			(layer "F.SilkS")
		)
		(fp_poly
			(pts
				(xy -5.2832 5.6007) (xy -5.2832 2.2479) (xy -8.9662 2.2479) (xy -8.9662 -2.2479) (xy -5.2832 -2.2479)
				(xy -5.2832 -5.6007) (xy 4.8768 -5.6007) (xy 4.8768 5.6007)
			)
			(stroke
				(width 0)
				(type default)
			)
			(fill no)
			(layer "F.CrtYd")
		)
		(fp_poly
			(pts
				(xy -5.2832 5.6007) (xy -5.2832 2.2479) (xy -8.9662 2.2479) (xy -8.9662 -2.2479) (xy -5.2832 -2.2479)
				(xy -5.2832 -5.6007) (xy 4.8768 -5.6007) (xy 4.8768 5.6007)
			)
			(stroke
				(width 0)
				(type default)
			)
			(fill no)
			(layer "F.Fab")
		)
		(pad "1" smd rect
			(at 1.905 -3.33883 270)
			(size 0.635 1.8542)
			(layers "F.Cu" "F.Mask" "F.Paste")
			(net "SPI_CS0_N_M_1")
		)
		(pad "2" smd rect
			(at 0.635 -3.33883 270)
			(size 0.635 1.8542)
			(layers "F.Cu" "F.Mask" "F.Paste")
			(net "SPI_MISO_R_1")
		)
		(pad "3" smd rect
			(at -0.635 -3.33883 270)
			(size 0.635 1.8542)
			(layers "F.Cu" "F.Mask" "F.Paste")
			(net "SPI_WP_R_N_1")
		)
		(pad "4" smd rect
			(at -1.905 -3.33883 270)
			(size 0.635 1.8542)
			(layers "F.Cu" "F.Mask" "F.Paste")
			(net "GND")
		)
		(pad "5" smd rect
			(at -1.905 3.33883 270)
			(size 0.635 1.8542)
			(layers "F.Cu" "F.Mask" "F.Paste")
			(net "SPI_MOSI_R_1")
		)
		(pad "6" smd rect
			(at -0.635 3.33883 270)
			(size 0.635 1.8542)
			(layers "F.Cu" "F.Mask" "F.Paste")
			(net "SPI_SCLK_R_1")
		)
		(pad "7" smd rect
			(at 0.635 3.33883 270)
			(size 0.635 1.8542)
			(layers "F.Cu" "F.Mask" "F.Paste")
			(net "SPI_HOLD#")
		)
		(pad "8" smd rect
			(at 1.905 3.33883 270)
			(size 0.635 1.8542)
			(layers "F.Cu" "F.Mask" "F.Paste")
			(net "P3V3_CPU")
		)
	)
	(footprint ""
		(layer "F.Cu")
		(at 180.594 -16.51 180)
		(property "Reference" "PR169"
			(at 0 0 180)
			(layer "F.SilkS")
			(hide yes)
			(effects
				(font
					(size 1.27 1.27)
				)
			)
		)
		(property "Value" "20KR2F-L-GP"
			(at 0.064008 -3.993896 180)
			(unlocked yes)
			(layer "F.Fab")
			(hide yes)
			(effects
				(font
					(size 1.016 1.016)
					(thickness 0.1524)
				)
			)
		)
		(property "Device Type" "R402H16"
			(at 0.064008 -5.517896 180)
			(unlocked yes)
			(layer "F.Fab")
			(hide yes)
			(effects
				(font
					(size 1.016 1.016)
					(thickness 0.1524)
				)
			)
		)
		(duplicate_pad_numbers_are_jumpers no)
		(fp_rect
			(start -0.381 0.8382)
			(end 0.381 -0.8382)
			(stroke
				(width 0)
				(type default)
			)
			(fill no)
			(layer "F.CrtYd")
		)
		(fp_rect
			(start -0.381 0.8382)
			(end 0.381 -0.8382)
			(stroke
				(width 0)
				(type default)
			)
			(fill no)
			(layer "F.Fab")
		)
		(pad "1" smd custom
			(at 0 -0.4318 180)
			(size 0.127 0.127)
			(layers "F.Cu" "F.Mask" "F.Paste")
			(net "PV_VDDR")
			(options
				(clearance outline)
				(anchor circle)
			)
			(primitives
				(gr_poly
					(pts
						(arc
							(start -0.2032 -0.2794)
							(mid -0.239121 -0.264521)
							(end -0.254 -0.2286)
						)
						(arc
							(start -0.254 0.2286)
							(mid -0.239121 0.264521)
							(end -0.2032 0.2794)
						)
						(arc
							(start 0.2032 0.2794)
							(mid 0.239121 0.264521)
							(end 0.254 0.2286)
						)
						(arc
							(start 0.254 -0.2286)
							(mid 0.239121 -0.264521)
							(end 0.2032 -0.2794)
						)
					)
					(width 0)
					(fill yes)
				)
			)
		)
		(pad "2" smd custom
			(at 0 0.4318 180)
			(size 0.127 0.127)
			(layers "F.Cu" "F.Mask" "F.Paste")
			(net "PV_VTT_DDR_B_REFIN")
			(options
				(clearance outline)
				(anchor circle)
			)
			(primitives
				(gr_poly
					(pts
						(arc
							(start -0.2032 -0.2794)
							(mid -0.239121 -0.264521)
							(end -0.254 -0.2286)
						)
						(arc
							(start -0.254 0.2286)
							(mid -0.239121 0.264521)
							(end -0.2032 0.2794)
						)
						(arc
							(start 0.2032 0.2794)
							(mid 0.239121 0.264521)
							(end 0.254 0.2286)
						)
						(arc
							(start 0.254 -0.2286)
							(mid 0.239121 -0.264521)
							(end 0.2032 -0.2794)
						)
					)
					(width 0)
					(fill yes)
				)
			)
		)
	)
	(footprint ""
		(layer "F.Cu")
		(at 53.5432 -49.276)
		(property "Reference" "PR159"
			(at 0 0 0)
			(layer "F.SilkS")
			(hide yes)
			(effects
				(font
					(size 1.27 1.27)
				)
			)
		)
		(property "Value" "10R2F-L-GP"
			(at 1.7907 -1.1176 0)
			(unlocked yes)
			(layer "F.Fab")
			(hide yes)
			(effects
				(font
					(size 1.016 1.016)
					(thickness 0.1524)
				)
			)
		)
		(property "Device Type" "R402H14"
			(at 1.7907 -2.6416 0)
			(unlocked yes)
			(layer "F.Fab")
			(hide yes)
			(effects
				(font
					(size 1.016 1.016)
					(thickness 0.1524)
				)
			)
		)
		(duplicate_pad_numbers_are_jumpers no)
		(fp_rect
			(start -0.381 0.8382)
			(end 0.381 -0.8382)
			(stroke
				(width 0)
				(type default)
			)
			(fill no)
			(layer "F.CrtYd")
		)
		(fp_rect
			(start -0.381 0.8382)
			(end 0.381 -0.8382)
			(stroke
				(width 0)
				(type default)
			)
			(fill no)
			(layer "F.Fab")
		)
		(pad "1" smd custom
			(at 0 -0.4318)
			(size 0.127 0.127)
			(layers "F.Cu" "F.Mask" "F.Paste")
			(net "VR_AVIN_P1V0_STBY")
			(options
				(clearance outline)
				(anchor circle)
			)
			(primitives
				(gr_poly
					(pts
						(arc
							(start -0.2032 -0.2794)
							(mid -0.239121 -0.264521)
							(end -0.254 -0.2286)
						)
						(arc
							(start -0.254 0.2286)
							(mid -0.239121 0.264521)
							(end -0.2032 0.2794)
						)
						(arc
							(start 0.2032 0.2794)
							(mid 0.239121 0.264521)
							(end 0.254 0.2286)
						)
						(arc
							(start 0.254 -0.2286)
							(mid 0.239121 -0.264521)
							(end 0.2032 -0.2794)
						)
					)
					(width 0)
					(fill yes)
				)
			)
		)
		(pad "2" smd custom
			(at 0 0.4318)
			(size 0.127 0.127)
			(layers "F.Cu" "F.Mask" "F.Paste")
			(net "VR_PVIN_P1V0_STBY")
			(options
				(clearance outline)
				(anchor circle)
			)
			(primitives
				(gr_poly
					(pts
						(arc
							(start -0.2032 -0.2794)
							(mid -0.239121 -0.264521)
							(end -0.254 -0.2286)
						)
						(arc
							(start -0.254 0.2286)
							(mid -0.239121 0.264521)
							(end -0.2032 0.2794)
						)
						(arc
							(start 0.2032 0.2794)
							(mid 0.239121 0.264521)
							(end 0.254 0.2286)
						)
						(arc
							(start 0.254 -0.2286)
							(mid 0.239121 -0.264521)
							(end 0.2032 -0.2794)
						)
					)
					(width 0)
					(fill yes)
				)
			)
		)
	)
	(footprint ""
		(layer "F.Cu")
		(at 70.7644 -45.3136 -90)
		(property "Reference" "R67"
			(at 0 0 270)
			(layer "F.SilkS")
			(hide yes)
			(effects
				(font
					(size 1.27 1.27)
				)
			)
		)
		(property "Value" "4K7R2F-GP"
			(at 0.064008 -3.993896 270)
			(unlocked yes)
			(layer "F.Fab")
			(hide yes)
			(effects
				(font
					(size 1.016 1.016)
					(thickness 0.1524)
				)
			)
		)
		(property "Device Type" "R402H16"
			(at 0.064008 -5.517896 270)
			(unlocked yes)
			(layer "F.Fab")
			(hide yes)
			(effects
				(font
					(size 1.016 1.016)
					(thickness 0.1524)
				)
			)
		)
		(duplicate_pad_numbers_are_jumpers no)
		(fp_rect
			(start -0.381 0.8382)
			(end 0.381 -0.8382)
			(stroke
				(width 0)
				(type default)
			)
			(fill no)
			(layer "F.CrtYd")
		)
		(fp_rect
			(start -0.381 0.8382)
			(end 0.381 -0.8382)
			(stroke
				(width 0)
				(type default)
			)
			(fill no)
			(layer "F.Fab")
		)
		(pad "1" smd custom
			(at 0 -0.4318 270)
			(size 0.127 0.127)
			(layers "F.Cu" "F.Mask" "F.Paste")
			(net "P3V3")
			(options
				(clearance outline)
				(anchor circle)
			)
			(primitives
				(gr_poly
					(pts
						(arc
							(start -0.2032 -0.2794)
							(mid -0.239121 -0.264521)
							(end -0.254 -0.2286)
						)
						(arc
							(start -0.254 0.2286)
							(mid -0.239121 0.264521)
							(end -0.2032 0.2794)
						)
						(arc
							(start 0.2032 0.2794)
							(mid 0.239121 0.264521)
							(end 0.254 0.2286)
						)
						(arc
							(start 0.254 -0.2286)
							(mid 0.239121 -0.264521)
							(end 0.2032 -0.2794)
						)
					)
					(width 0)
					(fill yes)
				)
			)
		)
		(pad "2" smd custom
			(at 0 0.4318 270)
			(size 0.127 0.127)
			(layers "F.Cu" "F.Mask" "F.Paste")
			(net "SMBUS_PECI_CLK")
			(options
				(clearance outline)
				(anchor circle)
			)
			(primitives
				(gr_poly
					(pts
						(arc
							(start -0.2032 -0.2794)
							(mid -0.239121 -0.264521)
							(end -0.254 -0.2286)
						)
						(arc
							(start -0.254 0.2286)
							(mid -0.239121 0.264521)
							(end -0.2032 0.2794)
						)
						(arc
							(start 0.2032 0.2794)
							(mid 0.239121 0.264521)
							(end 0.254 0.2286)
						)
						(arc
							(start 0.254 -0.2286)
							(mid 0.239121 -0.264521)
							(end 0.2032 -0.2794)
						)
					)
					(width 0)
					(fill yes)
				)
			)
		)
	)
	(footprint ""
		(layer "F.Cu")
		(at 56.896 -51.308 -90)
		(property "Reference" "PU11"
			(at 0 0 270)
			(layer "F.SilkS")
			(hide yes)
			(effects
				(font
					(size 1.27 1.27)
				)
			)
		)
		(property "Value" "EP53F8QI-T-GP"
			(at 2.827274 -2.223262 270)
			(unlocked yes)
			(layer "F.Fab")
			(hide yes)
			(effects
				(font
					(size 1.016 1.016)
					(thickness 0.1524)
				)
			)
		)
		(property "Device Type" "QFN16G3H46"
			(at 2.827274 -3.747262 270)
			(unlocked yes)
			(layer "F.Fab")
			(hide yes)
			(effects
				(font
					(size 1.016 1.016)
					(thickness 0.1524)
				)
			)
		)
		(duplicate_pad_numbers_are_jumpers no)
		(fp_poly
			(pts
				(xy 1.565656 -2.195576) (xy 1.252728 -1.882648) (xy 0.9398 -2.195576)
			)
			(stroke
				(width 0)
				(type default)
			)
			(fill yes)
			(layer "F.SilkS")
		)
		(fp_rect
			(start -1.8796 1.8796)
			(end 1.8796 -1.8796)
			(stroke
				(width 0)
				(type default)
			)
			(fill no)
			(layer "F.CrtYd")
		)
		(fp_rect
			(start -1.8796 1.8796)
			(end 1.8796 -1.8796)
			(stroke
				(width 0)
				(type default)
			)
			(fill no)
			(layer "F.Fab")
		)
		(pad "1" smd rect
			(at 1.249934 -1.32207 270)
			(size 0.3048 0.8636)
			(layers "F.Cu" "F.Mask" "F.Paste")
			(net "Net_645")
		)
		(pad "2" smd rect
			(at 0.750062 -1.32207 270)
			(size 0.3048 0.8636)
			(layers "F.Cu" "F.Mask" "F.Paste")
			(net "GND")
		)
		(pad "3" smd rect
			(at 0.249936 -1.32207 270)
			(size 0.3048 0.8636)
			(layers "F.Cu" "F.Mask" "F.Paste")
			(net "GND")
		)
		(pad "4" smd rect
			(at -0.249936 -1.32207 270)
			(size 0.3048 0.8636)
			(layers "F.Cu" "F.Mask" "F.Paste")
			(net "VR_AVIN_P1V0_STBY")
		)
		(pad "5" smd rect
			(at -0.750062 -1.32207 270)
			(size 0.3048 0.8636)
			(layers "F.Cu" "F.Mask" "F.Paste")
			(net "VR_FB_P1V0_STBY")
		)
		(pad "6" smd rect
			(at -1.249934 -1.32207 270)
			(size 0.3048 0.8636)
			(layers "F.Cu" "F.Mask" "F.Paste")
			(net "Net_648")
		)
		(pad "7" smd rect
			(at -1.32207 -0.249936 270)
			(size 0.8636 0.3048)
			(layers "F.Cu" "F.Mask" "F.Paste")
			(net "P1V0_STBY_VOUT")
		)
		(pad "8" smd rect
			(at -1.32207 0.249936 270)
			(size 0.8636 0.3048)
			(layers "F.Cu" "F.Mask" "F.Paste")
			(net "P1V0_STBY_VOUT")
		)
		(pad "9" smd rect
			(at -1.249934 1.32207 270)
			(size 0.3048 0.8636)
			(layers "F.Cu" "F.Mask" "F.Paste")
			(net "AGND_P1V0_STBY")
		)
		(pad "10" smd rect
			(at -0.750062 1.32207 270)
			(size 0.3048 0.8636)
			(layers "F.Cu" "F.Mask" "F.Paste")
			(net "VR_AVIN_P1V0_STBY")
		)
		(pad "11" smd rect
			(at -0.249936 1.32207 270)
			(size 0.3048 0.8636)
			(layers "F.Cu" "F.Mask" "F.Paste")
			(net "P1V0_STBY_PG")
		)
		(pad "12" smd rect
			(at 0.249936 1.32207 270)
			(size 0.3048 0.8636)
			(layers "F.Cu" "F.Mask" "F.Paste")
			(net "VR_EN_P1V0_STBY")
		)
		(pad "13" smd rect
			(at 0.750062 1.32207 270)
			(size 0.3048 0.8636)
			(layers "F.Cu" "F.Mask" "F.Paste")
			(net "VR_PVIN_P1V0_STBY")
		)
		(pad "14" smd rect
			(at 1.249934 1.32207 270)
			(size 0.3048 0.8636)
			(layers "F.Cu" "F.Mask" "F.Paste")
			(net "VR_PVIN_P1V0_STBY")
		)
		(pad "15" smd rect
			(at 1.32207 0.249936 270)
			(size 0.8636 0.3048)
			(layers "F.Cu" "F.Mask" "F.Paste")
			(net "Net_646")
		)
		(pad "16" smd rect
			(at 1.32207 -0.249936 270)
			(size 0.8636 0.3048)
			(layers "F.Cu" "F.Mask" "F.Paste")
			(net "Net_647")
		)
	)
	(footprint ""
		(layer "F.Cu")
		(at 145.923 -18.796)
		(property "Reference" "TP11"
			(at 0 0 0)
			(layer "F.SilkS")
			(hide yes)
			(effects
				(font
					(size 1.27 1.27)
				)
			)
		)
		(property "Value" "TPAD28-1-GP-U"
			(at 0.0508 -1.9304 0)
			(unlocked yes)
			(layer "F.Fab")
			(hide yes)
			(effects
				(font
					(size 1.016 1.016)
					(thickness 0.1524)
				)
			)
		)
		(property "Device Type" "TPAD28-1-U"
			(at 0.0508 -3.4544 0)
			(unlocked yes)
			(layer "F.Fab")
			(hide yes)
			(effects
				(font
					(size 1.016 1.016)
					(thickness 0.1524)
				)
			)
		)
		(duplicate_pad_numbers_are_jumpers no)
		(fp_poly
			(pts
				(arc
					(start 0.3556 0)
					(mid -0.3556 0)
					(end 0.3556 0)
				)
			)
			(stroke
				(width 0)
				(type default)
			)
			(fill no)
			(layer "F.CrtYd")
		)
		(fp_poly
			(pts
				(arc
					(start 0.9525 0)
					(mid -0.9525 0)
					(end 0.9525 0)
				)
			)
			(stroke
				(width 0)
				(type default)
			)
			(fill no)
			(layer "F.Fab")
		)
		(pad "1" smd circle
			(at 0 0)
			(size 0.7112 0.7112)
			(layers "F.Cu" "F.Mask" "F.Paste")
			(net "TP_FPGA_P100")
		)
	)
	(footprint ""
		(layer "F.Cu")
		(at 198.12 -7.112 90)
		(property "Reference" "R387"
			(at 0 0 90)
			(layer "F.SilkS")
			(hide yes)
			(effects
				(font
					(size 1.27 1.27)
				)
			)
		)
		(property "Value" "4K7R2F-GP"
			(at 0.064008 -3.993896 90)
			(unlocked yes)
			(layer "F.Fab")
			(hide yes)
			(effects
				(font
					(size 1.016 1.016)
					(thickness 0.1524)
				)
			)
		)
		(property "Device Type" "R402H16"
			(at 0.064008 -5.517896 90)
			(unlocked yes)
			(layer "F.Fab")
			(hide yes)
			(effects
				(font
					(size 1.016 1.016)
					(thickness 0.1524)
				)
			)
		)
		(duplicate_pad_numbers_are_jumpers no)
		(fp_rect
			(start -0.381 0.8382)
			(end 0.381 -0.8382)
			(stroke
				(width 0)
				(type default)
			)
			(fill no)
			(layer "F.CrtYd")
		)
		(fp_rect
			(start -0.381 0.8382)
			(end 0.381 -0.8382)
			(stroke
				(width 0)
				(type default)
			)
			(fill no)
			(layer "F.Fab")
		)
		(pad "1" smd custom
			(at 0 -0.4318 90)
			(size 0.127 0.127)
			(layers "F.Cu" "F.Mask" "F.Paste")
			(net "CHB_1_SA0")
			(options
				(clearance outline)
				(anchor circle)
			)
			(primitives
				(gr_poly
					(pts
						(arc
							(start -0.2032 -0.2794)
							(mid -0.239121 -0.264521)
							(end -0.254 -0.2286)
						)
						(arc
							(start -0.254 0.2286)
							(mid -0.239121 0.264521)
							(end -0.2032 0.2794)
						)
						(arc
							(start 0.2032 0.2794)
							(mid 0.239121 0.264521)
							(end 0.254 0.2286)
						)
						(arc
							(start 0.254 -0.2286)
							(mid 0.239121 -0.264521)
							(end 0.2032 -0.2794)
						)
					)
					(width 0)
					(fill yes)
				)
			)
		)
		(pad "2" smd custom
			(at 0 0.4318 90)
			(size 0.127 0.127)
			(layers "F.Cu" "F.Mask" "F.Paste")
			(net "GND")
			(options
				(clearance outline)
				(anchor circle)
			)
			(primitives
				(gr_poly
					(pts
						(arc
							(start -0.2032 -0.2794)
							(mid -0.239121 -0.264521)
							(end -0.254 -0.2286)
						)
						(arc
							(start -0.254 0.2286)
							(mid -0.239121 0.264521)
							(end -0.2032 0.2794)
						)
						(arc
							(start 0.2032 0.2794)
							(mid 0.239121 0.264521)
							(end 0.254 0.2286)
						)
						(arc
							(start 0.254 -0.2286)
							(mid 0.239121 -0.264521)
							(end 0.2032 -0.2794)
						)
					)
					(width 0)
					(fill yes)
				)
			)
		)
	)
	(footprint ""
		(layer "F.Cu")
		(at 175.641 -57.15 180)
		(property "Reference" "R181"
			(at 0 0 180)
			(layer "F.SilkS")
			(hide yes)
			(effects
				(font
					(size 1.27 1.27)
				)
			)
		)
		(property "Value" "4K7R2F-GP"
			(at 0.064008 -3.993896 180)
			(unlocked yes)
			(layer "F.Fab")
			(hide yes)
			(effects
				(font
					(size 1.016 1.016)
					(thickness 0.1524)
				)
			)
		)
		(property "Device Type" "R402H16"
			(at 0.064008 -5.517896 180)
			(unlocked yes)
			(layer "F.Fab")
			(hide yes)
			(effects
				(font
					(size 1.016 1.016)
					(thickness 0.1524)
				)
			)
		)
		(duplicate_pad_numbers_are_jumpers no)
		(fp_rect
			(start -0.381 0.8382)
			(end 0.381 -0.8382)
			(stroke
				(width 0)
				(type default)
			)
			(fill no)
			(layer "F.CrtYd")
		)
		(fp_rect
			(start -0.381 0.8382)
			(end 0.381 -0.8382)
			(stroke
				(width 0)
				(type default)
			)
			(fill no)
			(layer "F.Fab")
		)
		(pad "1" smd custom
			(at 0 -0.4318 180)
			(size 0.127 0.127)
			(layers "F.Cu" "F.Mask" "F.Paste")
			(net "EEPROM_A1")
			(options
				(clearance outline)
				(anchor circle)
			)
			(primitives
				(gr_poly
					(pts
						(arc
							(start -0.2032 -0.2794)
							(mid -0.239121 -0.264521)
							(end -0.254 -0.2286)
						)
						(arc
							(start -0.254 0.2286)
							(mid -0.239121 0.264521)
							(end -0.2032 0.2794)
						)
						(arc
							(start 0.2032 0.2794)
							(mid 0.239121 0.264521)
							(end 0.254 0.2286)
						)
						(arc
							(start 0.254 -0.2286)
							(mid 0.239121 -0.264521)
							(end 0.2032 -0.2794)
						)
					)
					(width 0)
					(fill yes)
				)
			)
		)
		(pad "2" smd custom
			(at 0 0.4318 180)
			(size 0.127 0.127)
			(layers "F.Cu" "F.Mask" "F.Paste")
			(net "GND")
			(options
				(clearance outline)
				(anchor circle)
			)
			(primitives
				(gr_poly
					(pts
						(arc
							(start -0.2032 -0.2794)
							(mid -0.239121 -0.264521)
							(end -0.254 -0.2286)
						)
						(arc
							(start -0.254 0.2286)
							(mid -0.239121 0.264521)
							(end -0.2032 0.2794)
						)
						(arc
							(start 0.2032 0.2794)
							(mid 0.239121 0.264521)
							(end 0.254 0.2286)
						)
						(arc
							(start 0.254 -0.2286)
							(mid 0.239121 -0.264521)
							(end 0.2032 -0.2794)
						)
					)
					(width 0)
					(fill yes)
				)
			)
		)
	)
	(footprint ""
		(layer "F.Cu")
		(at 167.894 -31.877 -90)
		(property "Reference" "PC88"
			(at 0 0 270)
			(layer "F.SilkS")
			(hide yes)
			(effects
				(font
					(size 1.27 1.27)
				)
			)
		)
		(property "Value" "SC10U6D3V5KX-4GP"
			(at -0.0762 -6.1214 270)
			(unlocked yes)
			(layer "F.Fab")
			(hide yes)
			(effects
				(font
					(size 1.016 1.016)
					(thickness 0.1524)
				)
			)
		)
		(property "Device Type" "C805H58"
			(at -0.0762 -8.1534 270)
			(unlocked yes)
			(layer "F.Fab")
			(hide yes)
			(effects
				(font
					(size 1.016 1.016)
					(thickness 0.1524)
				)
			)
		)
		(duplicate_pad_numbers_are_jumpers no)
		(fp_line
			(start 0.6096 0)
			(end -0.6096 0)
			(stroke
				(width 0.3048)
				(type default)
			)
			(layer "F.SilkS")
		)
		(fp_poly
			(pts
				(xy -0.9017 1.4351) (xy 0.9017 1.4351) (xy 0.9017 -1.4351) (xy -0.9017 -1.4351)
			)
			(stroke
				(width 0)
				(type default)
			)
			(fill no)
			(layer "F.CrtYd")
		)
		(fp_poly
			(pts
				(xy 0.9017 1.4351) (xy 0.9017 -1.4351) (xy -0.9017 -1.4351) (xy -0.9017 1.4351)
			)
			(stroke
				(width 0)
				(type default)
			)
			(fill no)
			(layer "F.Fab")
		)
		(pad "1" smd rect
			(at 0 -0.8382 270)
			(size 1.5494 0.9398)
			(layers "F.Cu" "F.Mask" "F.Paste")
			(net "P1V8_STBY_LDO_IN1")
		)
		(pad "2" smd rect
			(at 0 0.8382 270)
			(size 1.5494 0.9398)
			(layers "F.Cu" "F.Mask" "F.Paste")
			(net "GND")
		)
	)
	(footprint ""
		(layer "F.Cu")
		(at 68.58 -21.082 180)
		(property "Reference" "R411"
			(at 0 0 180)
			(layer "F.SilkS")
			(hide yes)
			(effects
				(font
					(size 1.27 1.27)
				)
			)
		)
		(property "Value" "0R2J-2-GP"
			(at 1.7907 -1.1176 180)
			(unlocked yes)
			(layer "F.Fab")
			(hide yes)
			(effects
				(font
					(size 1.016 1.016)
					(thickness 0.1524)
				)
			)
		)
		(property "Device Type" "R402H16"
			(at 1.7907 -2.6416 180)
			(unlocked yes)
			(layer "F.Fab")
			(hide yes)
			(effects
				(font
					(size 1.016 1.016)
					(thickness 0.1524)
				)
			)
		)
		(duplicate_pad_numbers_are_jumpers no)
		(fp_rect
			(start -0.381 0.8382)
			(end 0.381 -0.8382)
			(stroke
				(width 0)
				(type default)
			)
			(fill no)
			(layer "F.CrtYd")
		)
		(fp_rect
			(start -0.381 0.8382)
			(end 0.381 -0.8382)
			(stroke
				(width 0)
				(type default)
			)
			(fill no)
			(layer "F.Fab")
		)
		(pad "1" smd custom
			(at 0 -0.4318 180)
			(size 0.127 0.127)
			(layers "F.Cu" "F.Mask" "F.Paste")
			(net "MSATA_PRESENT#")
			(options
				(clearance outline)
				(anchor circle)
			)
			(primitives
				(gr_poly
					(pts
						(arc
							(start -0.2032 -0.2794)
							(mid -0.239121 -0.264521)
							(end -0.254 -0.2286)
						)
						(arc
							(start -0.254 0.2286)
							(mid -0.239121 0.264521)
							(end -0.2032 0.2794)
						)
						(arc
							(start 0.2032 0.2794)
							(mid 0.239121 0.264521)
							(end 0.254 0.2286)
						)
						(arc
							(start 0.254 -0.2286)
							(mid 0.239121 -0.264521)
							(end 0.2032 -0.2794)
						)
					)
					(width 0)
					(fill yes)
				)
			)
		)
		(pad "2" smd custom
			(at 0 0.4318 180)
			(size 0.127 0.127)
			(layers "F.Cu" "F.Mask" "F.Paste")
			(net "MSATA_PRESENT_R#")
			(options
				(clearance outline)
				(anchor circle)
			)
			(primitives
				(gr_poly
					(pts
						(arc
							(start -0.2032 -0.2794)
							(mid -0.239121 -0.264521)
							(end -0.254 -0.2286)
						)
						(arc
							(start -0.254 0.2286)
							(mid -0.239121 0.264521)
							(end -0.2032 0.2794)
						)
						(arc
							(start 0.2032 0.2794)
							(mid 0.239121 0.264521)
							(end 0.254 0.2286)
						)
						(arc
							(start 0.254 -0.2286)
							(mid 0.239121 -0.264521)
							(end 0.2032 -0.2794)
						)
					)
					(width 0)
					(fill yes)
				)
			)
		)
	)
	(footprint ""
		(layer "F.Cu")
		(at 73.66 -37.465 90)
		(property "Reference" "R415"
			(at 0 0 90)
			(layer "F.SilkS")
			(hide yes)
			(effects
				(font
					(size 1.27 1.27)
				)
			)
		)
		(property "Value" "4K7R2F-GP"
			(at 1.7907 -1.1176 90)
			(unlocked yes)
			(layer "F.Fab")
			(hide yes)
			(effects
				(font
					(size 1.016 1.016)
					(thickness 0.1524)
				)
			)
		)
		(property "Device Type" "R402H16"
			(at 1.7907 -2.6416 90)
			(unlocked yes)
			(layer "F.Fab")
			(hide yes)
			(effects
				(font
					(size 1.016 1.016)
					(thickness 0.1524)
				)
			)
		)
		(duplicate_pad_numbers_are_jumpers no)
		(fp_rect
			(start -0.381 0.8382)
			(end 0.381 -0.8382)
			(stroke
				(width 0)
				(type default)
			)
			(fill no)
			(layer "F.CrtYd")
		)
		(fp_rect
			(start -0.381 0.8382)
			(end 0.381 -0.8382)
			(stroke
				(width 0)
				(type default)
			)
			(fill no)
			(layer "F.Fab")
		)
		(pad "1" smd custom
			(at 0 -0.4318 90)
			(size 0.127 0.127)
			(layers "F.Cu" "F.Mask" "F.Paste")
			(net "P3V3_CPU")
			(options
				(clearance outline)
				(anchor circle)
			)
			(primitives
				(gr_poly
					(pts
						(arc
							(start -0.2032 -0.2794)
							(mid -0.239121 -0.264521)
							(end -0.254 -0.2286)
						)
						(arc
							(start -0.254 0.2286)
							(mid -0.239121 0.264521)
							(end -0.2032 0.2794)
						)
						(arc
							(start 0.2032 0.2794)
							(mid 0.239121 0.264521)
							(end 0.254 0.2286)
						)
						(arc
							(start 0.254 -0.2286)
							(mid 0.239121 -0.264521)
							(end 0.2032 -0.2794)
						)
					)
					(width 0)
					(fill yes)
				)
			)
		)
		(pad "2" smd custom
			(at 0 0.4318 90)
			(size 0.127 0.127)
			(layers "F.Cu" "F.Mask" "F.Paste")
			(net "USB_OC#")
			(options
				(clearance outline)
				(anchor circle)
			)
			(primitives
				(gr_poly
					(pts
						(arc
							(start -0.2032 -0.2794)
							(mid -0.239121 -0.264521)
							(end -0.254 -0.2286)
						)
						(arc
							(start -0.254 0.2286)
							(mid -0.239121 0.264521)
							(end -0.2032 0.2794)
						)
						(arc
							(start 0.2032 0.2794)
							(mid 0.239121 0.264521)
							(end 0.254 0.2286)
						)
						(arc
							(start 0.254 -0.2286)
							(mid 0.239121 -0.264521)
							(end 0.2032 -0.2794)
						)
					)
					(width 0)
					(fill yes)
				)
			)
		)
	)
	(footprint ""
		(layer "F.Cu")
		(at 53.2892 -51.308 180)
		(property "Reference" "PC110"
			(at 0 0 180)
			(layer "F.SilkS")
			(hide yes)
			(effects
				(font
					(size 1.27 1.27)
				)
			)
		)
		(property "Value" "SC1U16V3KX-5GP"
			(at -0.0254 -2.0193 180)
			(unlocked yes)
			(layer "F.Fab")
			(hide yes)
			(effects
				(font
					(size 1.016 1.016)
					(thickness 0.1524)
				)
			)
		)
		(property "Device Type" "C603H36"
			(at -0.0254 -3.5433 180)
			(unlocked yes)
			(layer "F.Fab")
			(hide yes)
			(effects
				(font
					(size 1.016 1.016)
					(thickness 0.1524)
				)
			)
		)
		(duplicate_pad_numbers_are_jumpers no)
		(fp_line
			(start -0.4064 0)
			(end 0.4064 0)
			(stroke
				(width 0.2286)
				(type default)
			)
			(layer "F.SilkS")
		)
		(fp_rect
			(start -0.635 1.1811)
			(end 0.635 -1.1811)
			(stroke
				(width 0)
				(type default)
			)
			(fill no)
			(layer "F.CrtYd")
		)
		(fp_rect
			(start -0.635 1.1811)
			(end 0.635 -1.1811)
			(stroke
				(width 0)
				(type default)
			)
			(fill no)
			(layer "F.Fab")
		)
		(pad "1" smd custom
			(at 0 -0.6604 180)
			(size 0.19685 0.19685)
			(layers "F.Cu" "F.Mask" "F.Paste")
			(net "VR_AVIN_P1V0_STBY")
			(options
				(clearance outline)
				(anchor circle)
			)
			(primitives
				(gr_poly
					(pts
						(arc
							(start 0.508 -0.2921)
							(mid 0.478242 -0.363942)
							(end 0.4064 -0.3937)
						)
						(arc
							(start -0.4064 -0.3937)
							(mid -0.478242 -0.363942)
							(end -0.508 -0.2921)
						)
						(arc
							(start -0.508 0.2921)
							(mid -0.478242 0.363942)
							(end -0.4064 0.3937)
						)
						(arc
							(start 0.4064 0.3937)
							(mid 0.478242 0.363942)
							(end 0.508 0.2921)
						)
					)
					(width 0)
					(fill yes)
				)
			)
		)
		(pad "2" smd custom
			(at 0 0.6604 180)
			(size 0.19685 0.19685)
			(layers "F.Cu" "F.Mask" "F.Paste")
			(net "AGND_P1V0_STBY")
			(options
				(clearance outline)
				(anchor circle)
			)
			(primitives
				(gr_poly
					(pts
						(arc
							(start 0.508 -0.2921)
							(mid 0.478242 -0.363942)
							(end 0.4064 -0.3937)
						)
						(arc
							(start -0.4064 -0.3937)
							(mid -0.478242 -0.363942)
							(end -0.508 -0.2921)
						)
						(arc
							(start -0.508 0.2921)
							(mid -0.478242 0.363942)
							(end -0.4064 0.3937)
						)
						(arc
							(start 0.4064 0.3937)
							(mid 0.478242 0.363942)
							(end 0.508 0.2921)
						)
					)
					(width 0)
					(fill yes)
				)
			)
		)
	)
	(footprint ""
		(layer "F.Cu")
		(at 118.849902 -11.500104)
		(property "Reference" "CN2"
			(at 0 0 0)
			(layer "F.SilkS")
			(hide yes)
			(effects
				(font
					(size 1.27 1.27)
				)
			)
		)
		(property "Value" "PIN-CON2-6-GP-U"
			(at -4.9657 1.2954 0)
			(unlocked yes)
			(layer "F.Fab")
			(hide yes)
			(effects
				(font
					(size 1.016 1.016)
					(thickness 0.1524)
				)
			)
		)
		(property "Device Type" "21U-91-03TB22-U"
			(at -4.9657 -0.2286 0)
			(unlocked yes)
			(layer "F.Fab")
			(hide yes)
			(effects
				(font
					(size 1.016 1.016)
					(thickness 0.1524)
				)
			)
		)
		(duplicate_pad_numbers_are_jumpers no)
		(fp_line
			(start -3.937 -1.4986)
			(end 3.937 -1.4986)
			(stroke
				(width 0.1524)
				(type default)
			)
			(layer "F.SilkS")
		)
		(fp_line
			(start -3.937 1.4986)
			(end -3.937 -1.4986)
			(stroke
				(width 0.1524)
				(type default)
			)
			(layer "F.SilkS")
		)
		(fp_line
			(start 3.937 -1.4986)
			(end 3.937 1.4986)
			(stroke
				(width 0.1524)
				(type default)
			)
			(layer "F.SilkS")
		)
		(fp_line
			(start 3.937 1.4986)
			(end -3.937 1.4986)
			(stroke
				(width 0.1524)
				(type default)
			)
			(layer "F.SilkS")
		)
		(fp_circle
			(center -2.54 0)
			(end -1.4732 0)
			(stroke
				(width 0.3048)
				(type default)
			)
			(fill no)
			(layer "F.SilkS")
		)
		(fp_circle
			(center 2.54 0)
			(end 3.6068 0)
			(stroke
				(width 0.3048)
				(type default)
			)
			(fill no)
			(layer "F.SilkS")
		)
		(fp_rect
			(start -3.683 1.2446)
			(end 3.683 -1.2446)
			(stroke
				(width 0)
				(type default)
			)
			(fill no)
			(layer "F.CrtYd")
		)
		(fp_poly
			(pts
				(xy -4.191 1.7526) (xy -4.191 -1.7526) (xy 4.191 -1.7526) (xy 4.191 -0.00635) (xy 3.683 -0.00635)
				(xy 3.683 -1.2446) (xy -3.683 -1.2446) (xy -3.683 1.2446) (xy 3.683 1.2446) (xy 3.683 0.00635) (xy 4.191 0.00635)
				(xy 4.191 1.7526)
			)
			(stroke
				(width 0)
				(type default)
			)
			(fill no)
			(layer "F.CrtYd")
		)
		(fp_rect
			(start -4.191 1.7526)
			(end 4.191 -1.7526)
			(stroke
				(width 0)
				(type default)
			)
			(fill no)
			(layer "F.Fab")
		)
		(pad "1" thru_hole circle
			(at -2.54 0)
			(size 1.4224 1.4224)
			(drill 1.016)
			(layers "*.Cu" "*.Mask")
			(remove_unused_layers no)
			(net "DYMMY_NET2")
			(clearance 0.1524)
			(thermal_gap 0.1524)
		)
		(pad "2" thru_hole circle
			(at 2.54 0)
			(size 1.4224 1.4224)
			(drill 1.016)
			(layers "*.Cu" "*.Mask")
			(remove_unused_layers no)
			(net "DYMMY_NET2")
			(clearance 0.1524)
			(thermal_gap 0.1524)
		)
	)
	(footprint ""
		(layer "F.Cu")
		(at 74.168 -44.069 90)
		(property "Reference" "R416"
			(at 0 0 90)
			(layer "F.SilkS")
			(hide yes)
			(effects
				(font
					(size 1.27 1.27)
				)
			)
		)
		(property "Value" "10KR2F-2-GP"
			(at 1.7907 -1.1176 90)
			(unlocked yes)
			(layer "F.Fab")
			(hide yes)
			(effects
				(font
					(size 1.016 1.016)
					(thickness 0.1524)
				)
			)
		)
		(property "Device Type" "R402H16"
			(at 1.7907 -2.6416 90)
			(unlocked yes)
			(layer "F.Fab")
			(hide yes)
			(effects
				(font
					(size 1.016 1.016)
					(thickness 0.1524)
				)
			)
		)
		(duplicate_pad_numbers_are_jumpers no)
		(fp_rect
			(start -0.381 0.8382)
			(end 0.381 -0.8382)
			(stroke
				(width 0)
				(type default)
			)
			(fill no)
			(layer "F.CrtYd")
		)
		(fp_rect
			(start -0.381 0.8382)
			(end 0.381 -0.8382)
			(stroke
				(width 0)
				(type default)
			)
			(fill no)
			(layer "F.Fab")
		)
		(pad "1" smd custom
			(at 0 -0.4318 90)
			(size 0.127 0.127)
			(layers "F.Cu" "F.Mask" "F.Paste")
			(net "P3V3")
			(options
				(clearance outline)
				(anchor circle)
			)
			(primitives
				(gr_poly
					(pts
						(arc
							(start -0.2032 -0.2794)
							(mid -0.239121 -0.264521)
							(end -0.254 -0.2286)
						)
						(arc
							(start -0.254 0.2286)
							(mid -0.239121 0.264521)
							(end -0.2032 0.2794)
						)
						(arc
							(start 0.2032 0.2794)
							(mid 0.239121 0.264521)
							(end 0.254 0.2286)
						)
						(arc
							(start 0.254 -0.2286)
							(mid 0.239121 -0.264521)
							(end 0.2032 -0.2794)
						)
					)
					(width 0)
					(fill yes)
				)
			)
		)
		(pad "2" smd custom
			(at 0 0.4318 90)
			(size 0.127 0.127)
			(layers "F.Cu" "F.Mask" "F.Paste")
			(net "SMBUS_SW_R_EN")
			(options
				(clearance outline)
				(anchor circle)
			)
			(primitives
				(gr_poly
					(pts
						(arc
							(start -0.2032 -0.2794)
							(mid -0.239121 -0.264521)
							(end -0.254 -0.2286)
						)
						(arc
							(start -0.254 0.2286)
							(mid -0.239121 0.264521)
							(end -0.2032 0.2794)
						)
						(arc
							(start 0.2032 0.2794)
							(mid 0.239121 0.264521)
							(end 0.254 0.2286)
						)
						(arc
							(start 0.254 -0.2286)
							(mid 0.239121 -0.264521)
							(end 0.2032 -0.2794)
						)
					)
					(width 0)
					(fill yes)
				)
			)
		)
	)
	(footprint ""
		(layer "F.Cu")
		(at 15.5702 -63.9064 180)
		(property "Reference" "PR37"
			(at 0 0 180)
			(layer "F.SilkS")
			(hide yes)
			(effects
				(font
					(size 1.27 1.27)
				)
			)
		)
		(property "Value" "0R2J-2-GP"
			(at 1.7907 -1.1176 180)
			(unlocked yes)
			(layer "F.Fab")
			(hide yes)
			(effects
				(font
					(size 1.016 1.016)
					(thickness 0.1524)
				)
			)
		)
		(property "Device Type" "R402H16"
			(at 1.7907 -2.6416 180)
			(unlocked yes)
			(layer "F.Fab")
			(hide yes)
			(effects
				(font
					(size 1.016 1.016)
					(thickness 0.1524)
				)
			)
		)
		(duplicate_pad_numbers_are_jumpers no)
		(fp_rect
			(start -0.381 0.8382)
			(end 0.381 -0.8382)
			(stroke
				(width 0)
				(type default)
			)
			(fill no)
			(layer "F.CrtYd")
		)
		(fp_rect
			(start -0.381 0.8382)
			(end 0.381 -0.8382)
			(stroke
				(width 0)
				(type default)
			)
			(fill no)
			(layer "F.Fab")
		)
		(pad "1" smd custom
			(at 0 -0.4318 180)
			(size 0.127 0.127)
			(layers "F.Cu" "F.Mask" "F.Paste")
			(net "PWRGD_R_PVNN")
			(options
				(clearance outline)
				(anchor circle)
			)
			(primitives
				(gr_poly
					(pts
						(arc
							(start -0.2032 -0.2794)
							(mid -0.239121 -0.264521)
							(end -0.254 -0.2286)
						)
						(arc
							(start -0.254 0.2286)
							(mid -0.239121 0.264521)
							(end -0.2032 0.2794)
						)
						(arc
							(start 0.2032 0.2794)
							(mid 0.239121 0.264521)
							(end 0.254 0.2286)
						)
						(arc
							(start 0.254 -0.2286)
							(mid 0.239121 -0.264521)
							(end 0.2032 -0.2794)
						)
					)
					(width 0)
					(fill yes)
				)
			)
		)
		(pad "2" smd custom
			(at 0 0.4318 180)
			(size 0.127 0.127)
			(layers "F.Cu" "F.Mask" "F.Paste")
			(net "PWRGD_PVCCP_VNN_PG")
			(options
				(clearance outline)
				(anchor circle)
			)
			(primitives
				(gr_poly
					(pts
						(arc
							(start -0.2032 -0.2794)
							(mid -0.239121 -0.264521)
							(end -0.254 -0.2286)
						)
						(arc
							(start -0.254 0.2286)
							(mid -0.239121 0.264521)
							(end -0.2032 0.2794)
						)
						(arc
							(start 0.2032 0.2794)
							(mid 0.239121 0.264521)
							(end 0.254 0.2286)
						)
						(arc
							(start 0.254 -0.2286)
							(mid 0.239121 -0.264521)
							(end 0.2032 -0.2794)
						)
					)
					(width 0)
					(fill yes)
				)
			)
		)
	)
	(footprint ""
		(layer "F.Cu")
		(at 154.94 -24.384 90)
		(property "Reference" "C74"
			(at 0 0 90)
			(layer "F.SilkS")
			(hide yes)
			(effects
				(font
					(size 1.27 1.27)
				)
			)
		)
		(property "Value" "SCD1U10V2KX-5GP"
			(at 1.1811 -2.7051 90)
			(unlocked yes)
			(layer "F.Fab")
			(hide yes)
			(effects
				(font
					(size 1.016 1.016)
					(thickness 0.1524)
				)
			)
		)
		(property "Device Type" "C402H22"
			(at 1.1811 -4.2291 90)
			(unlocked yes)
			(layer "F.Fab")
			(hide yes)
			(effects
				(font
					(size 1.016 1.016)
					(thickness 0.1524)
				)
			)
		)
		(duplicate_pad_numbers_are_jumpers no)
		(fp_rect
			(start -0.381 0.7366)
			(end 0.381 -0.7366)
			(stroke
				(width 0)
				(type default)
			)
			(fill no)
			(layer "F.CrtYd")
		)
		(fp_rect
			(start -0.381 0.7366)
			(end 0.381 -0.7366)
			(stroke
				(width 0)
				(type default)
			)
			(fill no)
			(layer "F.Fab")
		)
		(pad "1" smd custom
			(at 0 -0.4572 90)
			(size 0.1143 0.1143)
			(layers "F.Cu" "F.Mask" "F.Paste")
			(net "P1V2_FPGA_A")
			(options
				(clearance outline)
				(anchor circle)
			)
			(primitives
				(gr_poly
					(pts
						(arc
							(start -0.254 -0.1778)
							(mid -0.239121 -0.213721)
							(end -0.2032 -0.2286)
						)
						(arc
							(start 0.2032 -0.2286)
							(mid 0.239121 -0.213721)
							(end 0.254 -0.1778)
						)
						(arc
							(start 0.254 0.1778)
							(mid 0.239121 0.213721)
							(end 0.2032 0.2286)
						)
						(arc
							(start -0.2032 0.2286)
							(mid -0.239121 0.213721)
							(end -0.254 0.1778)
						)
					)
					(width 0)
					(fill yes)
				)
			)
		)
		(pad "2" smd custom
			(at 0 0.4572 90)
			(size 0.1143 0.1143)
			(layers "F.Cu" "F.Mask" "F.Paste")
			(net "GND")
			(options
				(clearance outline)
				(anchor circle)
			)
			(primitives
				(gr_poly
					(pts
						(arc
							(start -0.254 -0.1778)
							(mid -0.239121 -0.213721)
							(end -0.2032 -0.2286)
						)
						(arc
							(start 0.2032 -0.2286)
							(mid 0.239121 -0.213721)
							(end 0.254 -0.1778)
						)
						(arc
							(start 0.254 0.1778)
							(mid 0.239121 0.213721)
							(end 0.2032 0.2286)
						)
						(arc
							(start -0.2032 0.2286)
							(mid -0.239121 0.213721)
							(end -0.254 0.1778)
						)
					)
					(width 0)
					(fill yes)
				)
			)
		)
	)
	(footprint ""
		(layer "F.Cu")
		(at 184.2008 -30.0228 180)
		(property "Reference" "PR156"
			(at 0 0 180)
			(layer "F.SilkS")
			(hide yes)
			(effects
				(font
					(size 1.27 1.27)
				)
			)
		)
		(property "Value" "3K3R2F-2-GP"
			(at 1.7907 -1.1176 180)
			(unlocked yes)
			(layer "F.Fab")
			(hide yes)
			(effects
				(font
					(size 1.016 1.016)
					(thickness 0.1524)
				)
			)
		)
		(property "Device Type" "R402H16"
			(at 1.7907 -2.6416 180)
			(unlocked yes)
			(layer "F.Fab")
			(hide yes)
			(effects
				(font
					(size 1.016 1.016)
					(thickness 0.1524)
				)
			)
		)
		(duplicate_pad_numbers_are_jumpers no)
		(fp_rect
			(start -0.381 0.8382)
			(end 0.381 -0.8382)
			(stroke
				(width 0)
				(type default)
			)
			(fill no)
			(layer "F.CrtYd")
		)
		(fp_rect
			(start -0.381 0.8382)
			(end 0.381 -0.8382)
			(stroke
				(width 0)
				(type default)
			)
			(fill no)
			(layer "F.Fab")
		)
		(pad "1" smd custom
			(at 0 -0.4318 180)
			(size 0.127 0.127)
			(layers "F.Cu" "F.Mask" "F.Paste")
			(net "VR_PVDDR_A_FB_COMP")
			(options
				(clearance outline)
				(anchor circle)
			)
			(primitives
				(gr_poly
					(pts
						(arc
							(start -0.2032 -0.2794)
							(mid -0.239121 -0.264521)
							(end -0.254 -0.2286)
						)
						(arc
							(start -0.254 0.2286)
							(mid -0.239121 0.264521)
							(end -0.2032 0.2794)
						)
						(arc
							(start 0.2032 0.2794)
							(mid 0.239121 0.264521)
							(end 0.254 0.2286)
						)
						(arc
							(start 0.254 -0.2286)
							(mid 0.239121 -0.264521)
							(end 0.2032 -0.2794)
						)
					)
					(width 0)
					(fill yes)
				)
			)
		)
		(pad "2" smd custom
			(at 0 0.4318 180)
			(size 0.127 0.127)
			(layers "F.Cu" "F.Mask" "F.Paste")
			(net "VR_PVDDR_A_FB")
			(options
				(clearance outline)
				(anchor circle)
			)
			(primitives
				(gr_poly
					(pts
						(arc
							(start -0.2032 -0.2794)
							(mid -0.239121 -0.264521)
							(end -0.254 -0.2286)
						)
						(arc
							(start -0.254 0.2286)
							(mid -0.239121 0.264521)
							(end -0.2032 0.2794)
						)
						(arc
							(start 0.2032 0.2794)
							(mid 0.239121 0.264521)
							(end 0.254 0.2286)
						)
						(arc
							(start 0.254 -0.2286)
							(mid 0.239121 -0.264521)
							(end 0.2032 -0.2794)
						)
					)
					(width 0)
					(fill yes)
				)
			)
		)
	)
	(footprint ""
		(layer "F.Cu")
		(at 162.179 -41.402 90)
		(property "Reference" "R131"
			(at 0 0 90)
			(layer "F.SilkS")
			(hide yes)
			(effects
				(font
					(size 1.27 1.27)
				)
			)
		)
		(property "Value" "300R2F-GP"
			(at 0.064008 -3.993896 90)
			(unlocked yes)
			(layer "F.Fab")
			(hide yes)
			(effects
				(font
					(size 1.016 1.016)
					(thickness 0.1524)
				)
			)
		)
		(property "Device Type" "R402H16"
			(at 0.064008 -5.517896 90)
			(unlocked yes)
			(layer "F.Fab")
			(hide yes)
			(effects
				(font
					(size 1.016 1.016)
					(thickness 0.1524)
				)
			)
		)
		(duplicate_pad_numbers_are_jumpers no)
		(fp_rect
			(start -0.381 0.8382)
			(end 0.381 -0.8382)
			(stroke
				(width 0)
				(type default)
			)
			(fill no)
			(layer "F.CrtYd")
		)
		(fp_rect
			(start -0.381 0.8382)
			(end 0.381 -0.8382)
			(stroke
				(width 0)
				(type default)
			)
			(fill no)
			(layer "F.Fab")
		)
		(pad "1" smd custom
			(at 0 -0.4318 90)
			(size 0.127 0.127)
			(layers "F.Cu" "F.Mask" "F.Paste")
			(net "C_LED_NSTATUS#")
			(options
				(clearance outline)
				(anchor circle)
			)
			(primitives
				(gr_poly
					(pts
						(arc
							(start -0.2032 -0.2794)
							(mid -0.239121 -0.264521)
							(end -0.254 -0.2286)
						)
						(arc
							(start -0.254 0.2286)
							(mid -0.239121 0.264521)
							(end -0.2032 0.2794)
						)
						(arc
							(start 0.2032 0.2794)
							(mid 0.239121 0.264521)
							(end 0.254 0.2286)
						)
						(arc
							(start 0.254 -0.2286)
							(mid 0.239121 -0.264521)
							(end 0.2032 -0.2794)
						)
					)
					(width 0)
					(fill yes)
				)
			)
		)
		(pad "2" smd custom
			(at 0 0.4318 90)
			(size 0.127 0.127)
			(layers "F.Cu" "F.Mask" "F.Paste")
			(net "P3V3_STBY")
			(options
				(clearance outline)
				(anchor circle)
			)
			(primitives
				(gr_poly
					(pts
						(arc
							(start -0.2032 -0.2794)
							(mid -0.239121 -0.264521)
							(end -0.254 -0.2286)
						)
						(arc
							(start -0.254 0.2286)
							(mid -0.239121 0.264521)
							(end -0.2032 0.2794)
						)
						(arc
							(start 0.2032 0.2794)
							(mid 0.239121 0.264521)
							(end 0.254 0.2286)
						)
						(arc
							(start 0.254 -0.2286)
							(mid 0.239121 -0.264521)
							(end 0.2032 -0.2794)
						)
					)
					(width 0)
					(fill yes)
				)
			)
		)
	)
	(footprint ""
		(layer "F.Cu")
		(at 197.612 -32.6644 90)
		(property "Reference" "PR110"
			(at 0 0 90)
			(layer "F.SilkS")
			(hide yes)
			(effects
				(font
					(size 1.27 1.27)
				)
			)
		)
		(property "Value" "10KR2F-2-GP"
			(at 1.7907 -1.1176 90)
			(unlocked yes)
			(layer "F.Fab")
			(hide yes)
			(effects
				(font
					(size 1.016 1.016)
					(thickness 0.1524)
				)
			)
		)
		(property "Device Type" "R402H16"
			(at 1.7907 -2.6416 90)
			(unlocked yes)
			(layer "F.Fab")
			(hide yes)
			(effects
				(font
					(size 1.016 1.016)
					(thickness 0.1524)
				)
			)
		)
		(duplicate_pad_numbers_are_jumpers no)
		(fp_rect
			(start -0.381 0.8382)
			(end 0.381 -0.8382)
			(stroke
				(width 0)
				(type default)
			)
			(fill no)
			(layer "F.CrtYd")
		)
		(fp_rect
			(start -0.381 0.8382)
			(end 0.381 -0.8382)
			(stroke
				(width 0)
				(type default)
			)
			(fill no)
			(layer "F.Fab")
		)
		(pad "1" smd custom
			(at 0 -0.4318 90)
			(size 0.127 0.127)
			(layers "F.Cu" "F.Mask" "F.Paste")
			(net "VR_PVDDR_A_PHASE1")
			(options
				(clearance outline)
				(anchor circle)
			)
			(primitives
				(gr_poly
					(pts
						(arc
							(start -0.2032 -0.2794)
							(mid -0.239121 -0.264521)
							(end -0.254 -0.2286)
						)
						(arc
							(start -0.254 0.2286)
							(mid -0.239121 0.264521)
							(end -0.2032 0.2794)
						)
						(arc
							(start 0.2032 0.2794)
							(mid 0.239121 0.264521)
							(end 0.254 0.2286)
						)
						(arc
							(start 0.254 -0.2286)
							(mid 0.239121 -0.264521)
							(end 0.2032 -0.2794)
						)
					)
					(width 0)
					(fill yes)
				)
			)
		)
		(pad "2" smd custom
			(at 0 0.4318 90)
			(size 0.127 0.127)
			(layers "F.Cu" "F.Mask" "F.Paste")
			(net "VR_PVDDR_A_GH1_R")
			(options
				(clearance outline)
				(anchor circle)
			)
			(primitives
				(gr_poly
					(pts
						(arc
							(start -0.2032 -0.2794)
							(mid -0.239121 -0.264521)
							(end -0.254 -0.2286)
						)
						(arc
							(start -0.254 0.2286)
							(mid -0.239121 0.264521)
							(end -0.2032 0.2794)
						)
						(arc
							(start 0.2032 0.2794)
							(mid 0.239121 0.264521)
							(end 0.254 0.2286)
						)
						(arc
							(start 0.254 -0.2286)
							(mid 0.239121 -0.264521)
							(end 0.2032 -0.2794)
						)
					)
					(width 0)
					(fill yes)
				)
			)
		)
	)
	(footprint ""
		(layer "F.Cu")
		(at 181.102 -38.1 90)
		(property "Reference" "PR130"
			(at 0 0 90)
			(layer "F.SilkS")
			(hide yes)
			(effects
				(font
					(size 1.27 1.27)
				)
			)
		)
		(property "Value" "0R2J-2-GP"
			(at 0.064008 -3.993896 90)
			(unlocked yes)
			(layer "F.Fab")
			(hide yes)
			(effects
				(font
					(size 1.016 1.016)
					(thickness 0.1524)
				)
			)
		)
		(property "Device Type" "R402H16"
			(at 0.064008 -5.517896 90)
			(unlocked yes)
			(layer "F.Fab")
			(hide yes)
			(effects
				(font
					(size 1.016 1.016)
					(thickness 0.1524)
				)
			)
		)
		(duplicate_pad_numbers_are_jumpers no)
		(fp_rect
			(start -0.381 0.8382)
			(end 0.381 -0.8382)
			(stroke
				(width 0)
				(type default)
			)
			(fill no)
			(layer "F.CrtYd")
		)
		(fp_rect
			(start -0.381 0.8382)
			(end 0.381 -0.8382)
			(stroke
				(width 0)
				(type default)
			)
			(fill no)
			(layer "F.Fab")
		)
		(pad "1" smd custom
			(at 0 -0.4318 90)
			(size 0.127 0.127)
			(layers "F.Cu" "F.Mask" "F.Paste")
			(net "P1V0")
			(options
				(clearance outline)
				(anchor circle)
			)
			(primitives
				(gr_poly
					(pts
						(arc
							(start -0.2032 -0.2794)
							(mid -0.239121 -0.264521)
							(end -0.254 -0.2286)
						)
						(arc
							(start -0.254 0.2286)
							(mid -0.239121 0.264521)
							(end -0.2032 0.2794)
						)
						(arc
							(start 0.2032 0.2794)
							(mid 0.239121 0.264521)
							(end 0.254 0.2286)
						)
						(arc
							(start 0.254 -0.2286)
							(mid 0.239121 -0.264521)
							(end 0.2032 -0.2794)
						)
					)
					(width 0)
					(fill yes)
				)
			)
		)
		(pad "2" smd custom
			(at 0 0.4318 90)
			(size 0.127 0.127)
			(layers "F.Cu" "F.Mask" "F.Paste")
			(net "SVID_CPU_ALERT#")
			(options
				(clearance outline)
				(anchor circle)
			)
			(primitives
				(gr_poly
					(pts
						(arc
							(start -0.2032 -0.2794)
							(mid -0.239121 -0.264521)
							(end -0.254 -0.2286)
						)
						(arc
							(start -0.254 0.2286)
							(mid -0.239121 0.264521)
							(end -0.2032 0.2794)
						)
						(arc
							(start 0.2032 0.2794)
							(mid 0.239121 0.264521)
							(end 0.254 0.2286)
						)
						(arc
							(start 0.254 -0.2286)
							(mid 0.239121 -0.264521)
							(end 0.2032 -0.2794)
						)
					)
					(width 0)
					(fill yes)
				)
			)
		)
	)
	(footprint ""
		(layer "F.Cu")
		(at 168.4528 -52.832 -90)
		(property "Reference" "R188"
			(at 0 0 270)
			(layer "F.SilkS")
			(hide yes)
			(effects
				(font
					(size 1.27 1.27)
				)
			)
		)
		(property "Value" "33R2F-3-GP"
			(at 1.7907 -1.1176 270)
			(unlocked yes)
			(layer "F.Fab")
			(hide yes)
			(effects
				(font
					(size 1.016 1.016)
					(thickness 0.1524)
				)
			)
		)
		(property "Device Type" "R402H16"
			(at 1.7907 -2.6416 270)
			(unlocked yes)
			(layer "F.Fab")
			(hide yes)
			(effects
				(font
					(size 1.016 1.016)
					(thickness 0.1524)
				)
			)
		)
		(duplicate_pad_numbers_are_jumpers no)
		(fp_rect
			(start -0.381 0.8382)
			(end 0.381 -0.8382)
			(stroke
				(width 0)
				(type default)
			)
			(fill no)
			(layer "F.CrtYd")
		)
		(fp_rect
			(start -0.381 0.8382)
			(end 0.381 -0.8382)
			(stroke
				(width 0)
				(type default)
			)
			(fill no)
			(layer "F.Fab")
		)
		(pad "1" smd custom
			(at 0 -0.4318 270)
			(size 0.127 0.127)
			(layers "F.Cu" "F.Mask" "F.Paste")
			(net "C_DATA0")
			(options
				(clearance outline)
				(anchor circle)
			)
			(primitives
				(gr_poly
					(pts
						(arc
							(start -0.2032 -0.2794)
							(mid -0.239121 -0.264521)
							(end -0.254 -0.2286)
						)
						(arc
							(start -0.254 0.2286)
							(mid -0.239121 0.264521)
							(end -0.2032 0.2794)
						)
						(arc
							(start 0.2032 0.2794)
							(mid 0.239121 0.264521)
							(end 0.254 0.2286)
						)
						(arc
							(start 0.254 -0.2286)
							(mid 0.239121 -0.264521)
							(end 0.2032 -0.2794)
						)
					)
					(width 0)
					(fill yes)
				)
			)
		)
		(pad "2" smd custom
			(at 0 0.4318 270)
			(size 0.127 0.127)
			(layers "F.Cu" "F.Mask" "F.Paste")
			(net "C_R_DATA0")
			(options
				(clearance outline)
				(anchor circle)
			)
			(primitives
				(gr_poly
					(pts
						(arc
							(start -0.2032 -0.2794)
							(mid -0.239121 -0.264521)
							(end -0.254 -0.2286)
						)
						(arc
							(start -0.254 0.2286)
							(mid -0.239121 0.264521)
							(end -0.2032 0.2794)
						)
						(arc
							(start 0.2032 0.2794)
							(mid 0.239121 0.264521)
							(end 0.254 0.2286)
						)
						(arc
							(start 0.254 -0.2286)
							(mid 0.239121 -0.264521)
							(end 0.2032 -0.2794)
						)
					)
					(width 0)
					(fill yes)
				)
			)
		)
	)
	(footprint ""
		(layer "F.Cu")
		(at 131.445 -56.388 180)
		(property "Reference" "PC49"
			(at 0 0 180)
			(layer "F.SilkS")
			(hide yes)
			(effects
				(font
					(size 1.27 1.27)
				)
			)
		)
		(property "Value" "SC10U6D3V3MX-GP"
			(at 0 -2.8194 180)
			(unlocked yes)
			(layer "F.Fab")
			(hide yes)
			(effects
				(font
					(size 1.016 1.016)
					(thickness 0.1524)
				)
			)
		)
		(property "Device Type" "C603H38"
			(at 0 -4.3434 180)
			(unlocked yes)
			(layer "F.Fab")
			(hide yes)
			(effects
				(font
					(size 1.016 1.016)
					(thickness 0.1524)
				)
			)
		)
		(duplicate_pad_numbers_are_jumpers no)
		(fp_line
			(start -0.4064 0)
			(end 0.4064 0)
			(stroke
				(width 0.2286)
				(type default)
			)
			(layer "F.SilkS")
		)
		(fp_rect
			(start -0.635 1.1811)
			(end 0.635 -1.1811)
			(stroke
				(width 0)
				(type default)
			)
			(fill no)
			(layer "F.CrtYd")
		)
		(fp_rect
			(start -0.635 1.1811)
			(end 0.635 -1.1811)
			(stroke
				(width 0)
				(type default)
			)
			(fill no)
			(layer "F.Fab")
		)
		(pad "1" smd custom
			(at 0 -0.6604 180)
			(size 0.19685 0.19685)
			(layers "F.Cu" "F.Mask" "F.Paste")
			(net "GND")
			(options
				(clearance outline)
				(anchor circle)
			)
			(primitives
				(gr_poly
					(pts
						(arc
							(start 0.508 -0.2921)
							(mid 0.478242 -0.363942)
							(end 0.4064 -0.3937)
						)
						(arc
							(start -0.4064 -0.3937)
							(mid -0.478242 -0.363942)
							(end -0.508 -0.2921)
						)
						(arc
							(start -0.508 0.2921)
							(mid -0.478242 0.363942)
							(end -0.4064 0.3937)
						)
						(arc
							(start 0.4064 0.3937)
							(mid 0.478242 0.363942)
							(end 0.508 0.2921)
						)
					)
					(width 0)
					(fill yes)
				)
			)
		)
		(pad "2" smd custom
			(at 0 0.6604 180)
			(size 0.19685 0.19685)
			(layers "F.Cu" "F.Mask" "F.Paste")
			(net "PV_VTT_DDR_A")
			(options
				(clearance outline)
				(anchor circle)
			)
			(primitives
				(gr_poly
					(pts
						(arc
							(start 0.508 -0.2921)
							(mid 0.478242 -0.363942)
							(end 0.4064 -0.3937)
						)
						(arc
							(start -0.4064 -0.3937)
							(mid -0.478242 -0.363942)
							(end -0.508 -0.2921)
						)
						(arc
							(start -0.508 0.2921)
							(mid -0.478242 0.363942)
							(end -0.4064 0.3937)
						)
						(arc
							(start 0.4064 0.3937)
							(mid 0.478242 0.363942)
							(end 0.508 0.2921)
						)
					)
					(width 0)
					(fill yes)
				)
			)
		)
	)
	(footprint ""
		(layer "F.Cu")
		(at 155.702 -28.956 180)
		(property "Reference" "R140"
			(at 0 0 180)
			(layer "F.SilkS")
			(hide yes)
			(effects
				(font
					(size 1.27 1.27)
				)
			)
		)
		(property "Value" "4K7R2F-GP"
			(at 0.064008 -3.993896 180)
			(unlocked yes)
			(layer "F.Fab")
			(hide yes)
			(effects
				(font
					(size 1.016 1.016)
					(thickness 0.1524)
				)
			)
		)
		(property "Device Type" "R402H16"
			(at 0.064008 -5.517896 180)
			(unlocked yes)
			(layer "F.Fab")
			(hide yes)
			(effects
				(font
					(size 1.016 1.016)
					(thickness 0.1524)
				)
			)
		)
		(duplicate_pad_numbers_are_jumpers no)
		(fp_rect
			(start -0.381 0.8382)
			(end 0.381 -0.8382)
			(stroke
				(width 0)
				(type default)
			)
			(fill no)
			(layer "F.CrtYd")
		)
		(fp_rect
			(start -0.381 0.8382)
			(end 0.381 -0.8382)
			(stroke
				(width 0)
				(type default)
			)
			(fill no)
			(layer "F.Fab")
		)
		(pad "1" smd custom
			(at 0 -0.4318 180)
			(size 0.127 0.127)
			(layers "F.Cu" "F.Mask" "F.Paste")
			(net "P3V3_STBY")
			(options
				(clearance outline)
				(anchor circle)
			)
			(primitives
				(gr_poly
					(pts
						(arc
							(start -0.2032 -0.2794)
							(mid -0.239121 -0.264521)
							(end -0.254 -0.2286)
						)
						(arc
							(start -0.254 0.2286)
							(mid -0.239121 0.264521)
							(end -0.2032 0.2794)
						)
						(arc
							(start 0.2032 0.2794)
							(mid 0.239121 0.264521)
							(end 0.254 0.2286)
						)
						(arc
							(start 0.254 -0.2286)
							(mid 0.239121 -0.264521)
							(end 0.2032 -0.2794)
						)
					)
					(width 0)
					(fill yes)
				)
			)
		)
		(pad "2" smd custom
			(at 0 0.4318 180)
			(size 0.127 0.127)
			(layers "F.Cu" "F.Mask" "F.Paste")
			(net "FPGA_SMB_HOST_CLK")
			(options
				(clearance outline)
				(anchor circle)
			)
			(primitives
				(gr_poly
					(pts
						(arc
							(start -0.2032 -0.2794)
							(mid -0.239121 -0.264521)
							(end -0.254 -0.2286)
						)
						(arc
							(start -0.254 0.2286)
							(mid -0.239121 0.264521)
							(end -0.2032 0.2794)
						)
						(arc
							(start 0.2032 0.2794)
							(mid 0.239121 0.264521)
							(end 0.254 0.2286)
						)
						(arc
							(start 0.254 -0.2286)
							(mid 0.239121 -0.264521)
							(end 0.2032 -0.2794)
						)
					)
					(width 0)
					(fill yes)
				)
			)
		)
	)
	(footprint ""
		(layer "F.Cu")
		(at 13.335 -60.071 180)
		(property "Reference" "PR49"
			(at 0 0 180)
			(layer "F.SilkS")
			(hide yes)
			(effects
				(font
					(size 1.27 1.27)
				)
			)
		)
		(property "Value" "0R2J-2-GP"
			(at 1.7907 -1.1176 180)
			(unlocked yes)
			(layer "F.Fab")
			(hide yes)
			(effects
				(font
					(size 1.016 1.016)
					(thickness 0.1524)
				)
			)
		)
		(property "Device Type" "R402H16"
			(at 1.7907 -2.6416 180)
			(unlocked yes)
			(layer "F.Fab")
			(hide yes)
			(effects
				(font
					(size 1.016 1.016)
					(thickness 0.1524)
				)
			)
		)
		(duplicate_pad_numbers_are_jumpers no)
		(fp_rect
			(start -0.381 0.8382)
			(end 0.381 -0.8382)
			(stroke
				(width 0)
				(type default)
			)
			(fill no)
			(layer "F.CrtYd")
		)
		(fp_rect
			(start -0.381 0.8382)
			(end 0.381 -0.8382)
			(stroke
				(width 0)
				(type default)
			)
			(fill no)
			(layer "F.Fab")
		)
		(pad "1" smd custom
			(at 0 -0.4318 180)
			(size 0.127 0.127)
			(layers "F.Cu" "F.Mask" "F.Paste")
			(net "TP_PVCCP_CLK")
			(options
				(clearance outline)
				(anchor circle)
			)
			(primitives
				(gr_poly
					(pts
						(arc
							(start -0.2032 -0.2794)
							(mid -0.239121 -0.264521)
							(end -0.254 -0.2286)
						)
						(arc
							(start -0.254 0.2286)
							(mid -0.239121 0.264521)
							(end -0.2032 0.2794)
						)
						(arc
							(start 0.2032 0.2794)
							(mid 0.239121 0.264521)
							(end 0.254 0.2286)
						)
						(arc
							(start 0.254 -0.2286)
							(mid 0.239121 -0.264521)
							(end 0.2032 -0.2794)
						)
					)
					(width 0)
					(fill yes)
				)
			)
		)
		(pad "2" smd custom
			(at 0 0.4318 180)
			(size 0.127 0.127)
			(layers "F.Cu" "F.Mask" "F.Paste")
			(net "SVID_CPU_CLK")
			(options
				(clearance outline)
				(anchor circle)
			)
			(primitives
				(gr_poly
					(pts
						(arc
							(start -0.2032 -0.2794)
							(mid -0.239121 -0.264521)
							(end -0.254 -0.2286)
						)
						(arc
							(start -0.254 0.2286)
							(mid -0.239121 0.264521)
							(end -0.2032 0.2794)
						)
						(arc
							(start 0.2032 0.2794)
							(mid 0.239121 0.264521)
							(end 0.254 0.2286)
						)
						(arc
							(start 0.254 -0.2286)
							(mid 0.239121 -0.264521)
							(end 0.2032 -0.2794)
						)
					)
					(width 0)
					(fill yes)
				)
			)
		)
	)
	(footprint ""
		(layer "F.Cu")
		(at 136.525 -15.113)
		(property "Reference" "C323"
			(at 0 0 0)
			(layer "F.SilkS")
			(hide yes)
			(effects
				(font
					(size 1.27 1.27)
				)
			)
		)
		(property "Value" "SCD1U10V2KX-5GP"
			(at 1.8923 -1.2065 0)
			(unlocked yes)
			(layer "F.Fab")
			(hide yes)
			(effects
				(font
					(size 1.016 1.016)
					(thickness 0.1524)
				)
			)
		)
		(property "Device Type" "C402H22"
			(at 1.8923 -2.7305 0)
			(unlocked yes)
			(layer "F.Fab")
			(hide yes)
			(effects
				(font
					(size 1.016 1.016)
					(thickness 0.1524)
				)
			)
		)
		(duplicate_pad_numbers_are_jumpers no)
		(fp_rect
			(start -0.381 0.7366)
			(end 0.381 -0.7366)
			(stroke
				(width 0)
				(type default)
			)
			(fill no)
			(layer "F.CrtYd")
		)
		(fp_rect
			(start -0.381 0.7366)
			(end 0.381 -0.7366)
			(stroke
				(width 0)
				(type default)
			)
			(fill no)
			(layer "F.Fab")
		)
		(pad "1" smd custom
			(at 0 -0.4572)
			(size 0.1143 0.1143)
			(layers "F.Cu" "F.Mask" "F.Paste")
			(net "HOST_LV_D_RSTBTN#")
			(options
				(clearance outline)
				(anchor circle)
			)
			(primitives
				(gr_poly
					(pts
						(arc
							(start -0.254 -0.1778)
							(mid -0.239121 -0.213721)
							(end -0.2032 -0.2286)
						)
						(arc
							(start 0.2032 -0.2286)
							(mid 0.239121 -0.213721)
							(end 0.254 -0.1778)
						)
						(arc
							(start 0.254 0.1778)
							(mid 0.239121 0.213721)
							(end 0.2032 0.2286)
						)
						(arc
							(start -0.2032 0.2286)
							(mid -0.239121 0.213721)
							(end -0.254 0.1778)
						)
					)
					(width 0)
					(fill yes)
				)
			)
		)
		(pad "2" smd custom
			(at 0 0.4572)
			(size 0.1143 0.1143)
			(layers "F.Cu" "F.Mask" "F.Paste")
			(net "GND")
			(options
				(clearance outline)
				(anchor circle)
			)
			(primitives
				(gr_poly
					(pts
						(arc
							(start -0.254 -0.1778)
							(mid -0.239121 -0.213721)
							(end -0.2032 -0.2286)
						)
						(arc
							(start 0.2032 -0.2286)
							(mid 0.239121 -0.213721)
							(end 0.254 -0.1778)
						)
						(arc
							(start 0.254 0.1778)
							(mid 0.239121 0.213721)
							(end 0.2032 0.2286)
						)
						(arc
							(start -0.2032 0.2286)
							(mid -0.239121 0.213721)
							(end -0.254 0.1778)
						)
					)
					(width 0)
					(fill yes)
				)
			)
		)
	)
	(footprint ""
		(layer "F.Cu")
		(at 32.893 -20.193 180)
		(property "Reference" "R264"
			(at 0 0 180)
			(layer "F.SilkS")
			(hide yes)
			(effects
				(font
					(size 1.27 1.27)
				)
			)
		)
		(property "Value" "0R2J-2-GP"
			(at 0.064008 -3.993896 180)
			(unlocked yes)
			(layer "F.Fab")
			(hide yes)
			(effects
				(font
					(size 1.016 1.016)
					(thickness 0.1524)
				)
			)
		)
		(property "Device Type" "R402H16"
			(at 0.064008 -5.517896 180)
			(unlocked yes)
			(layer "F.Fab")
			(hide yes)
			(effects
				(font
					(size 1.016 1.016)
					(thickness 0.1524)
				)
			)
		)
		(duplicate_pad_numbers_are_jumpers no)
		(fp_rect
			(start -0.381 0.8382)
			(end 0.381 -0.8382)
			(stroke
				(width 0)
				(type default)
			)
			(fill no)
			(layer "F.CrtYd")
		)
		(fp_rect
			(start -0.381 0.8382)
			(end 0.381 -0.8382)
			(stroke
				(width 0)
				(type default)
			)
			(fill no)
			(layer "F.Fab")
		)
		(pad "1" smd custom
			(at 0 -0.4318 180)
			(size 0.127 0.127)
			(layers "F.Cu" "F.Mask" "F.Paste")
			(net "XDP_DFX_PORT_R_CLK1")
			(options
				(clearance outline)
				(anchor circle)
			)
			(primitives
				(gr_poly
					(pts
						(arc
							(start -0.2032 -0.2794)
							(mid -0.239121 -0.264521)
							(end -0.254 -0.2286)
						)
						(arc
							(start -0.254 0.2286)
							(mid -0.239121 0.264521)
							(end -0.2032 0.2794)
						)
						(arc
							(start 0.2032 0.2794)
							(mid 0.239121 0.264521)
							(end 0.254 0.2286)
						)
						(arc
							(start 0.254 -0.2286)
							(mid 0.239121 -0.264521)
							(end 0.2032 -0.2794)
						)
					)
					(width 0)
					(fill yes)
				)
			)
		)
		(pad "2" smd custom
			(at 0 0.4318 180)
			(size 0.127 0.127)
			(layers "F.Cu" "F.Mask" "F.Paste")
			(net "XDP_DFX_PORT_CLK1")
			(options
				(clearance outline)
				(anchor circle)
			)
			(primitives
				(gr_poly
					(pts
						(arc
							(start -0.2032 -0.2794)
							(mid -0.239121 -0.264521)
							(end -0.254 -0.2286)
						)
						(arc
							(start -0.254 0.2286)
							(mid -0.239121 0.264521)
							(end -0.2032 0.2794)
						)
						(arc
							(start 0.2032 0.2794)
							(mid 0.239121 0.264521)
							(end 0.254 0.2286)
						)
						(arc
							(start 0.254 -0.2286)
							(mid 0.239121 -0.264521)
							(end 0.2032 -0.2794)
						)
					)
					(width 0)
					(fill yes)
				)
			)
		)
	)
	(footprint ""
		(layer "F.Cu")
		(at 141.859 -49.403 180)
		(property "Reference" "TP41"
			(at 0 0 180)
			(layer "F.SilkS")
			(hide yes)
			(effects
				(font
					(size 1.27 1.27)
				)
			)
		)
		(property "Value" "TPAD32-GP"
			(at 0 -3.166364 180)
			(unlocked yes)
			(layer "F.Fab")
			(hide yes)
			(effects
				(font
					(size 1.016 1.016)
					(thickness 0.1524)
				)
			)
		)
		(property "Device Type" "TPAD32"
			(at 0 -4.690618 180)
			(unlocked yes)
			(layer "F.Fab")
			(hide yes)
			(effects
				(font
					(size 1.016 1.016)
					(thickness 0.1524)
				)
			)
		)
		(duplicate_pad_numbers_are_jumpers no)
		(fp_poly
			(pts
				(arc
					(start -0.7112 0)
					(mid 0.7112 0)
					(end -0.7112 0)
				)
			)
			(stroke
				(width 0)
				(type default)
			)
			(fill no)
			(layer "F.CrtYd")
		)
		(fp_poly
			(pts
				(arc
					(start -0.7112 0)
					(mid 0.7112 0)
					(end -0.7112 0)
				)
			)
			(stroke
				(width 0)
				(type default)
			)
			(fill no)
			(layer "F.Fab")
		)
		(pad "1" smd circle
			(at 0 0 180)
			(size 0.8128 0.8128)
			(layers "F.Cu" "F.Mask" "F.Paste")
			(net "C_NCONFIG#")
		)
	)
	(footprint ""
		(layer "F.Cu")
		(at 46.101 -19.177 90)
		(property "Reference" "C206"
			(at 0 0 90)
			(layer "F.SilkS")
			(hide yes)
			(effects
				(font
					(size 1.27 1.27)
				)
			)
		)
		(property "Value" "SCD1U10V2KX-5GP"
			(at 1.1811 -2.7051 90)
			(unlocked yes)
			(layer "F.Fab")
			(hide yes)
			(effects
				(font
					(size 1.016 1.016)
					(thickness 0.1524)
				)
			)
		)
		(property "Device Type" "C402H22"
			(at 1.1811 -4.2291 90)
			(unlocked yes)
			(layer "F.Fab")
			(hide yes)
			(effects
				(font
					(size 1.016 1.016)
					(thickness 0.1524)
				)
			)
		)
		(duplicate_pad_numbers_are_jumpers no)
		(fp_rect
			(start -0.381 0.7366)
			(end 0.381 -0.7366)
			(stroke
				(width 0)
				(type default)
			)
			(fill no)
			(layer "F.CrtYd")
		)
		(fp_rect
			(start -0.381 0.7366)
			(end 0.381 -0.7366)
			(stroke
				(width 0)
				(type default)
			)
			(fill no)
			(layer "F.Fab")
		)
		(pad "1" smd custom
			(at 0 -0.4572 90)
			(size 0.1143 0.1143)
			(layers "F.Cu" "F.Mask" "F.Paste")
			(net "P3V3_VDD_CLKBUFF")
			(options
				(clearance outline)
				(anchor circle)
			)
			(primitives
				(gr_poly
					(pts
						(arc
							(start -0.254 -0.1778)
							(mid -0.239121 -0.213721)
							(end -0.2032 -0.2286)
						)
						(arc
							(start 0.2032 -0.2286)
							(mid 0.239121 -0.213721)
							(end 0.254 -0.1778)
						)
						(arc
							(start 0.254 0.1778)
							(mid 0.239121 0.213721)
							(end 0.2032 0.2286)
						)
						(arc
							(start -0.2032 0.2286)
							(mid -0.239121 0.213721)
							(end -0.254 0.1778)
						)
					)
					(width 0)
					(fill yes)
				)
			)
		)
		(pad "2" smd custom
			(at 0 0.4572 90)
			(size 0.1143 0.1143)
			(layers "F.Cu" "F.Mask" "F.Paste")
			(net "GND")
			(options
				(clearance outline)
				(anchor circle)
			)
			(primitives
				(gr_poly
					(pts
						(arc
							(start -0.254 -0.1778)
							(mid -0.239121 -0.213721)
							(end -0.2032 -0.2286)
						)
						(arc
							(start 0.2032 -0.2286)
							(mid 0.239121 -0.213721)
							(end 0.254 -0.1778)
						)
						(arc
							(start 0.254 0.1778)
							(mid 0.239121 0.213721)
							(end 0.2032 0.2286)
						)
						(arc
							(start -0.2032 0.2286)
							(mid -0.239121 0.213721)
							(end -0.254 0.1778)
						)
					)
					(width 0)
					(fill yes)
				)
			)
		)
	)
	(footprint ""
		(layer "F.Cu")
		(at 56.515 -44.577)
		(property "Reference" "R54"
			(at 0 0 0)
			(layer "F.SilkS")
			(hide yes)
			(effects
				(font
					(size 1.27 1.27)
				)
			)
		)
		(property "Value" "0R2J-2-GP"
			(at 0.064008 -3.993896 0)
			(unlocked yes)
			(layer "F.Fab")
			(hide yes)
			(effects
				(font
					(size 1.016 1.016)
					(thickness 0.1524)
				)
			)
		)
		(property "Device Type" "R402H16"
			(at 0.064008 -5.517896 0)
			(unlocked yes)
			(layer "F.Fab")
			(hide yes)
			(effects
				(font
					(size 1.016 1.016)
					(thickness 0.1524)
				)
			)
		)
		(duplicate_pad_numbers_are_jumpers no)
		(fp_rect
			(start -0.381 0.8382)
			(end 0.381 -0.8382)
			(stroke
				(width 0)
				(type default)
			)
			(fill no)
			(layer "F.CrtYd")
		)
		(fp_rect
			(start -0.381 0.8382)
			(end 0.381 -0.8382)
			(stroke
				(width 0)
				(type default)
			)
			(fill no)
			(layer "F.Fab")
		)
		(pad "1" smd custom
			(at 0 -0.4318)
			(size 0.127 0.127)
			(layers "F.Cu" "F.Mask" "F.Paste")
			(net "PWRGD_P1V8_PG")
			(options
				(clearance outline)
				(anchor circle)
			)
			(primitives
				(gr_poly
					(pts
						(arc
							(start -0.2032 -0.2794)
							(mid -0.239121 -0.264521)
							(end -0.254 -0.2286)
						)
						(arc
							(start -0.254 0.2286)
							(mid -0.239121 0.264521)
							(end -0.2032 0.2794)
						)
						(arc
							(start 0.2032 0.2794)
							(mid 0.239121 0.264521)
							(end 0.254 0.2286)
						)
						(arc
							(start 0.254 -0.2286)
							(mid 0.239121 -0.264521)
							(end 0.2032 -0.2794)
						)
					)
					(width 0)
					(fill yes)
				)
			)
		)
		(pad "2" smd custom
			(at 0 0.4318)
			(size 0.127 0.127)
			(layers "F.Cu" "F.Mask" "F.Paste")
			(net "SW_P3V3_EN_G2")
			(options
				(clearance outline)
				(anchor circle)
			)
			(primitives
				(gr_poly
					(pts
						(arc
							(start -0.2032 -0.2794)
							(mid -0.239121 -0.264521)
							(end -0.254 -0.2286)
						)
						(arc
							(start -0.254 0.2286)
							(mid -0.239121 0.264521)
							(end -0.2032 0.2794)
						)
						(arc
							(start 0.2032 0.2794)
							(mid 0.239121 0.264521)
							(end 0.254 0.2286)
						)
						(arc
							(start 0.254 -0.2286)
							(mid 0.239121 -0.264521)
							(end 0.2032 -0.2794)
						)
					)
					(width 0)
					(fill yes)
				)
			)
		)
	)
	(footprint ""
		(layer "F.Cu")
		(at 177.165 -57.15)
		(property "Reference" "R173"
			(at 0 0 0)
			(layer "F.SilkS")
			(hide yes)
			(effects
				(font
					(size 1.27 1.27)
				)
			)
		)
		(property "Value" "4K7R2F-GP"
			(at 0.064008 -3.993896 0)
			(unlocked yes)
			(layer "F.Fab")
			(hide yes)
			(effects
				(font
					(size 1.016 1.016)
					(thickness 0.1524)
				)
			)
		)
		(property "Device Type" "R402H16"
			(at 0.064008 -5.517896 0)
			(unlocked yes)
			(layer "F.Fab")
			(hide yes)
			(effects
				(font
					(size 1.016 1.016)
					(thickness 0.1524)
				)
			)
		)
		(duplicate_pad_numbers_are_jumpers no)
		(fp_rect
			(start -0.381 0.8382)
			(end 0.381 -0.8382)
			(stroke
				(width 0)
				(type default)
			)
			(fill no)
			(layer "F.CrtYd")
		)
		(fp_rect
			(start -0.381 0.8382)
			(end 0.381 -0.8382)
			(stroke
				(width 0)
				(type default)
			)
			(fill no)
			(layer "F.Fab")
		)
		(pad "1" smd custom
			(at 0 -0.4318)
			(size 0.127 0.127)
			(layers "F.Cu" "F.Mask" "F.Paste")
			(net "P3V3_STBY")
			(options
				(clearance outline)
				(anchor circle)
			)
			(primitives
				(gr_poly
					(pts
						(arc
							(start -0.2032 -0.2794)
							(mid -0.239121 -0.264521)
							(end -0.254 -0.2286)
						)
						(arc
							(start -0.254 0.2286)
							(mid -0.239121 0.264521)
							(end -0.2032 0.2794)
						)
						(arc
							(start 0.2032 0.2794)
							(mid 0.239121 0.264521)
							(end 0.254 0.2286)
						)
						(arc
							(start 0.254 -0.2286)
							(mid 0.239121 -0.264521)
							(end 0.2032 -0.2794)
						)
					)
					(width 0)
					(fill yes)
				)
			)
		)
		(pad "2" smd custom
			(at 0 0.4318)
			(size 0.127 0.127)
			(layers "F.Cu" "F.Mask" "F.Paste")
			(net "EEPROM_A0")
			(options
				(clearance outline)
				(anchor circle)
			)
			(primitives
				(gr_poly
					(pts
						(arc
							(start -0.2032 -0.2794)
							(mid -0.239121 -0.264521)
							(end -0.254 -0.2286)
						)
						(arc
							(start -0.254 0.2286)
							(mid -0.239121 0.264521)
							(end -0.2032 0.2794)
						)
						(arc
							(start 0.2032 0.2794)
							(mid 0.239121 0.264521)
							(end 0.254 0.2286)
						)
						(arc
							(start 0.254 -0.2286)
							(mid 0.239121 -0.264521)
							(end 0.2032 -0.2794)
						)
					)
					(width 0)
					(fill yes)
				)
			)
		)
	)
	(footprint ""
		(layer "F.Cu")
		(at 49.022 -44.958 -90)
		(property "Reference" "C20"
			(at 0 0 270)
			(layer "F.SilkS")
			(hide yes)
			(effects
				(font
					(size 1.27 1.27)
				)
			)
		)
		(property "Value" "SC1U25V3KX-GP"
			(at -0.0254 -2.0193 270)
			(unlocked yes)
			(layer "F.Fab")
			(hide yes)
			(effects
				(font
					(size 1.016 1.016)
					(thickness 0.1524)
				)
			)
		)
		(property "Device Type" "C603H36"
			(at -0.0254 -3.5433 270)
			(unlocked yes)
			(layer "F.Fab")
			(hide yes)
			(effects
				(font
					(size 1.016 1.016)
					(thickness 0.1524)
				)
			)
		)
		(duplicate_pad_numbers_are_jumpers no)
		(fp_line
			(start -0.4064 0)
			(end 0.4064 0)
			(stroke
				(width 0.2286)
				(type default)
			)
			(layer "F.SilkS")
		)
		(fp_rect
			(start -0.635 1.1811)
			(end 0.635 -1.1811)
			(stroke
				(width 0)
				(type default)
			)
			(fill no)
			(layer "F.CrtYd")
		)
		(fp_rect
			(start -0.635 1.1811)
			(end 0.635 -1.1811)
			(stroke
				(width 0)
				(type default)
			)
			(fill no)
			(layer "F.Fab")
		)
		(pad "1" smd custom
			(at 0 -0.6604 270)
			(size 0.19685 0.19685)
			(layers "F.Cu" "F.Mask" "F.Paste")
			(net "SW_P3V3_EN_LV_D")
			(options
				(clearance outline)
				(anchor circle)
			)
			(primitives
				(gr_poly
					(pts
						(arc
							(start 0.508 -0.2921)
							(mid 0.478242 -0.363942)
							(end 0.4064 -0.3937)
						)
						(arc
							(start -0.4064 -0.3937)
							(mid -0.478242 -0.363942)
							(end -0.508 -0.2921)
						)
						(arc
							(start -0.508 0.2921)
							(mid -0.478242 0.363942)
							(end -0.4064 0.3937)
						)
						(arc
							(start 0.4064 0.3937)
							(mid 0.478242 0.363942)
							(end 0.508 0.2921)
						)
					)
					(width 0)
					(fill yes)
				)
			)
		)
		(pad "2" smd custom
			(at 0 0.6604 270)
			(size 0.19685 0.19685)
			(layers "F.Cu" "F.Mask" "F.Paste")
			(net "GND")
			(options
				(clearance outline)
				(anchor circle)
			)
			(primitives
				(gr_poly
					(pts
						(arc
							(start 0.508 -0.2921)
							(mid 0.478242 -0.363942)
							(end 0.4064 -0.3937)
						)
						(arc
							(start -0.4064 -0.3937)
							(mid -0.478242 -0.363942)
							(end -0.508 -0.2921)
						)
						(arc
							(start -0.508 0.2921)
							(mid -0.478242 0.363942)
							(end -0.4064 0.3937)
						)
						(arc
							(start 0.4064 0.3937)
							(mid 0.478242 0.363942)
							(end 0.508 0.2921)
						)
					)
					(width 0)
					(fill yes)
				)
			)
		)
	)
	(footprint ""
		(layer "F.Cu")
		(at 23.0632 -52.6034 90)
		(property "Reference" "PC61"
			(at 0 0 90)
			(layer "F.SilkS")
			(hide yes)
			(effects
				(font
					(size 1.27 1.27)
				)
			)
		)
		(property "Value" "SCD068U16V2KX-GP"
			(at 1.8923 -1.2065 90)
			(unlocked yes)
			(layer "F.Fab")
			(hide yes)
			(effects
				(font
					(size 1.016 1.016)
					(thickness 0.1524)
				)
			)
		)
		(property "Device Type" "C402H22"
			(at 1.8923 -2.7305 90)
			(unlocked yes)
			(layer "F.Fab")
			(hide yes)
			(effects
				(font
					(size 1.016 1.016)
					(thickness 0.1524)
				)
			)
		)
		(duplicate_pad_numbers_are_jumpers no)
		(fp_rect
			(start -0.381 0.7366)
			(end 0.381 -0.7366)
			(stroke
				(width 0)
				(type default)
			)
			(fill no)
			(layer "F.CrtYd")
		)
		(fp_rect
			(start -0.381 0.7366)
			(end 0.381 -0.7366)
			(stroke
				(width 0)
				(type default)
			)
			(fill no)
			(layer "F.Fab")
		)
		(pad "1" smd custom
			(at 0 -0.4572 90)
			(size 0.1143 0.1143)
			(layers "F.Cu" "F.Mask" "F.Paste")
			(net "VR_PVCCP_VSEN")
			(options
				(clearance outline)
				(anchor circle)
			)
			(primitives
				(gr_poly
					(pts
						(arc
							(start -0.254 -0.1778)
							(mid -0.239121 -0.213721)
							(end -0.2032 -0.2286)
						)
						(arc
							(start 0.2032 -0.2286)
							(mid 0.239121 -0.213721)
							(end 0.254 -0.1778)
						)
						(arc
							(start 0.254 0.1778)
							(mid 0.239121 0.213721)
							(end 0.2032 0.2286)
						)
						(arc
							(start -0.2032 0.2286)
							(mid -0.239121 0.213721)
							(end -0.254 0.1778)
						)
					)
					(width 0)
					(fill yes)
				)
			)
		)
		(pad "2" smd custom
			(at 0 0.4572 90)
			(size 0.1143 0.1143)
			(layers "F.Cu" "F.Mask" "F.Paste")
			(net "VR_PVCCP_RTN")
			(options
				(clearance outline)
				(anchor circle)
			)
			(primitives
				(gr_poly
					(pts
						(arc
							(start -0.254 -0.1778)
							(mid -0.239121 -0.213721)
							(end -0.2032 -0.2286)
						)
						(arc
							(start 0.2032 -0.2286)
							(mid 0.239121 -0.213721)
							(end 0.254 -0.1778)
						)
						(arc
							(start 0.254 0.1778)
							(mid 0.239121 0.213721)
							(end 0.2032 0.2286)
						)
						(arc
							(start -0.2032 0.2286)
							(mid -0.239121 0.213721)
							(end -0.254 0.1778)
						)
					)
					(width 0)
					(fill yes)
				)
			)
		)
	)
	(footprint ""
		(layer "F.Cu")
		(at 19.9644 -52.6288 -90)
		(property "Reference" "PR93"
			(at 0 0 270)
			(layer "F.SilkS")
			(hide yes)
			(effects
				(font
					(size 1.27 1.27)
				)
			)
		)
		(property "Value" "1KR2F-3-GP"
			(at 1.7907 -1.1176 270)
			(unlocked yes)
			(layer "F.Fab")
			(hide yes)
			(effects
				(font
					(size 1.016 1.016)
					(thickness 0.1524)
				)
			)
		)
		(property "Device Type" "R402H16"
			(at 1.7907 -2.6416 270)
			(unlocked yes)
			(layer "F.Fab")
			(hide yes)
			(effects
				(font
					(size 1.016 1.016)
					(thickness 0.1524)
				)
			)
		)
		(duplicate_pad_numbers_are_jumpers no)
		(fp_rect
			(start -0.381 0.8382)
			(end 0.381 -0.8382)
			(stroke
				(width 0)
				(type default)
			)
			(fill no)
			(layer "F.CrtYd")
		)
		(fp_rect
			(start -0.381 0.8382)
			(end 0.381 -0.8382)
			(stroke
				(width 0)
				(type default)
			)
			(fill no)
			(layer "F.Fab")
		)
		(pad "1" smd custom
			(at 0 -0.4318 270)
			(size 0.127 0.127)
			(layers "F.Cu" "F.Mask" "F.Paste")
			(net "VR_PVCCP_FB")
			(options
				(clearance outline)
				(anchor circle)
			)
			(primitives
				(gr_poly
					(pts
						(arc
							(start -0.2032 -0.2794)
							(mid -0.239121 -0.264521)
							(end -0.254 -0.2286)
						)
						(arc
							(start -0.254 0.2286)
							(mid -0.239121 0.264521)
							(end -0.2032 0.2794)
						)
						(arc
							(start 0.2032 0.2794)
							(mid 0.239121 0.264521)
							(end 0.254 0.2286)
						)
						(arc
							(start 0.254 -0.2286)
							(mid 0.239121 -0.264521)
							(end 0.2032 -0.2794)
						)
					)
					(width 0)
					(fill yes)
				)
			)
		)
		(pad "2" smd custom
			(at 0 0.4318 270)
			(size 0.127 0.127)
			(layers "F.Cu" "F.Mask" "F.Paste")
			(net "VR_PVCCP_FB_RC2")
			(options
				(clearance outline)
				(anchor circle)
			)
			(primitives
				(gr_poly
					(pts
						(arc
							(start -0.2032 -0.2794)
							(mid -0.239121 -0.264521)
							(end -0.254 -0.2286)
						)
						(arc
							(start -0.254 0.2286)
							(mid -0.239121 0.264521)
							(end -0.2032 0.2794)
						)
						(arc
							(start 0.2032 0.2794)
							(mid 0.239121 0.264521)
							(end 0.254 0.2286)
						)
						(arc
							(start 0.254 -0.2286)
							(mid 0.239121 -0.264521)
							(end 0.2032 -0.2794)
						)
					)
					(width 0)
					(fill yes)
				)
			)
		)
	)
	(footprint ""
		(layer "F.Cu")
		(at 71.882 -57.15 90)
		(property "Reference" "R301"
			(at 0 0 90)
			(layer "F.SilkS")
			(hide yes)
			(effects
				(font
					(size 1.27 1.27)
				)
			)
		)
		(property "Value" "4K7R2F-GP"
			(at 0.064008 -3.993896 90)
			(unlocked yes)
			(layer "F.Fab")
			(hide yes)
			(effects
				(font
					(size 1.016 1.016)
					(thickness 0.1524)
				)
			)
		)
		(property "Device Type" "R402H16"
			(at 0.064008 -5.517896 90)
			(unlocked yes)
			(layer "F.Fab")
			(hide yes)
			(effects
				(font
					(size 1.016 1.016)
					(thickness 0.1524)
				)
			)
		)
		(duplicate_pad_numbers_are_jumpers no)
		(fp_rect
			(start -0.381 0.8382)
			(end 0.381 -0.8382)
			(stroke
				(width 0)
				(type default)
			)
			(fill no)
			(layer "F.CrtYd")
		)
		(fp_rect
			(start -0.381 0.8382)
			(end 0.381 -0.8382)
			(stroke
				(width 0)
				(type default)
			)
			(fill no)
			(layer "F.Fab")
		)
		(pad "1" smd custom
			(at 0 -0.4318 90)
			(size 0.127 0.127)
			(layers "F.Cu" "F.Mask" "F.Paste")
			(net "P3V3_STBY")
			(options
				(clearance outline)
				(anchor circle)
			)
			(primitives
				(gr_poly
					(pts
						(arc
							(start -0.2032 -0.2794)
							(mid -0.239121 -0.264521)
							(end -0.254 -0.2286)
						)
						(arc
							(start -0.254 0.2286)
							(mid -0.239121 0.264521)
							(end -0.2032 0.2794)
						)
						(arc
							(start 0.2032 0.2794)
							(mid 0.239121 0.264521)
							(end 0.254 0.2286)
						)
						(arc
							(start 0.254 -0.2286)
							(mid 0.239121 -0.264521)
							(end 0.2032 -0.2794)
						)
					)
					(width 0)
					(fill yes)
				)
			)
		)
		(pad "2" smd custom
			(at 0 0.4318 90)
			(size 0.127 0.127)
			(layers "F.Cu" "F.Mask" "F.Paste")
			(net "BMC_I2C_CLK")
			(options
				(clearance outline)
				(anchor circle)
			)
			(primitives
				(gr_poly
					(pts
						(arc
							(start -0.2032 -0.2794)
							(mid -0.239121 -0.264521)
							(end -0.254 -0.2286)
						)
						(arc
							(start -0.254 0.2286)
							(mid -0.239121 0.264521)
							(end -0.2032 0.2794)
						)
						(arc
							(start 0.2032 0.2794)
							(mid 0.239121 0.264521)
							(end 0.254 0.2286)
						)
						(arc
							(start 0.254 -0.2286)
							(mid 0.239121 -0.264521)
							(end 0.2032 -0.2794)
						)
					)
					(width 0)
					(fill yes)
				)
			)
		)
	)
	(footprint ""
		(layer "F.Cu")
		(at 12.954 -58.293 -90)
		(property "Reference" "TP6"
			(at 0 0 270)
			(layer "F.SilkS")
			(hide yes)
			(effects
				(font
					(size 1.27 1.27)
				)
			)
		)
		(property "Value" "TPAD28-1-GP-U"
			(at 0.0508 -1.9304 270)
			(unlocked yes)
			(layer "F.Fab")
			(hide yes)
			(effects
				(font
					(size 1.016 1.016)
					(thickness 0.1524)
				)
			)
		)
		(property "Device Type" "TPAD28-1-U"
			(at 0.0508 -3.4544 270)
			(unlocked yes)
			(layer "F.Fab")
			(hide yes)
			(effects
				(font
					(size 1.016 1.016)
					(thickness 0.1524)
				)
			)
		)
		(duplicate_pad_numbers_are_jumpers no)
		(fp_poly
			(pts
				(arc
					(start 0 -0.3556)
					(mid 0 0.3556)
					(end 0 -0.3556)
				)
			)
			(stroke
				(width 0)
				(type default)
			)
			(fill no)
			(layer "F.CrtYd")
		)
		(fp_poly
			(pts
				(arc
					(start 0 -0.9525)
					(mid 0 0.9525)
					(end 0 -0.9525)
				)
			)
			(stroke
				(width 0)
				(type default)
			)
			(fill no)
			(layer "F.Fab")
		)
		(pad "1" smd circle
			(at 0 0 270)
			(size 0.7112 0.7112)
			(layers "F.Cu" "F.Mask" "F.Paste")
			(net "TP_PVCCP_CLK")
		)
	)
	(footprint ""
		(layer "F.Cu")
		(at 160.909 -12.828778 180)
		(property "Reference" "C344"
			(at 0 0 180)
			(layer "F.SilkS")
			(hide yes)
			(effects
				(font
					(size 1.27 1.27)
				)
			)
		)
		(property "Value" "SCD1U16V2KX-3GP"
			(at 1.8923 -1.2065 180)
			(unlocked yes)
			(layer "F.Fab")
			(hide yes)
			(effects
				(font
					(size 1.016 1.016)
					(thickness 0.1524)
				)
			)
		)
		(property "Device Type" "C402H22"
			(at 1.8923 -2.7305 180)
			(unlocked yes)
			(layer "F.Fab")
			(hide yes)
			(effects
				(font
					(size 1.016 1.016)
					(thickness 0.1524)
				)
			)
		)
		(duplicate_pad_numbers_are_jumpers no)
		(fp_rect
			(start -0.381 0.7366)
			(end 0.381 -0.7366)
			(stroke
				(width 0)
				(type default)
			)
			(fill no)
			(layer "F.CrtYd")
		)
		(fp_rect
			(start -0.381 0.7366)
			(end 0.381 -0.7366)
			(stroke
				(width 0)
				(type default)
			)
			(fill no)
			(layer "F.Fab")
		)
		(pad "1" smd custom
			(at 0 -0.4572 180)
			(size 0.1143 0.1143)
			(layers "F.Cu" "F.Mask" "F.Paste")
			(net "PV_VDDR")
			(options
				(clearance outline)
				(anchor circle)
			)
			(primitives
				(gr_poly
					(pts
						(arc
							(start -0.254 -0.1778)
							(mid -0.239121 -0.213721)
							(end -0.2032 -0.2286)
						)
						(arc
							(start 0.2032 -0.2286)
							(mid 0.239121 -0.213721)
							(end 0.254 -0.1778)
						)
						(arc
							(start 0.254 0.1778)
							(mid 0.239121 0.213721)
							(end 0.2032 0.2286)
						)
						(arc
							(start -0.2032 0.2286)
							(mid -0.239121 0.213721)
							(end -0.254 0.1778)
						)
					)
					(width 0)
					(fill yes)
				)
			)
		)
		(pad "2" smd custom
			(at 0 0.4572 180)
			(size 0.1143 0.1143)
			(layers "F.Cu" "F.Mask" "F.Paste")
			(net "GND")
			(options
				(clearance outline)
				(anchor circle)
			)
			(primitives
				(gr_poly
					(pts
						(arc
							(start -0.254 -0.1778)
							(mid -0.239121 -0.213721)
							(end -0.2032 -0.2286)
						)
						(arc
							(start 0.2032 -0.2286)
							(mid 0.239121 -0.213721)
							(end 0.254 -0.1778)
						)
						(arc
							(start 0.254 0.1778)
							(mid 0.239121 0.213721)
							(end 0.2032 0.2286)
						)
						(arc
							(start -0.2032 0.2286)
							(mid -0.239121 0.213721)
							(end -0.254 0.1778)
						)
					)
					(width 0)
					(fill yes)
				)
			)
		)
	)
	(footprint ""
		(layer "F.Cu")
		(at 185.039 -43.688 -90)
		(property "Reference" "R222"
			(at 0 0 270)
			(layer "F.SilkS")
			(hide yes)
			(effects
				(font
					(size 1.27 1.27)
				)
			)
		)
		(property "Value" "0R2J-2-GP"
			(at 0.064008 -3.993896 270)
			(unlocked yes)
			(layer "F.Fab")
			(hide yes)
			(effects
				(font
					(size 1.016 1.016)
					(thickness 0.1524)
				)
			)
		)
		(property "Device Type" "R402H16"
			(at 0.064008 -5.517896 270)
			(unlocked yes)
			(layer "F.Fab")
			(hide yes)
			(effects
				(font
					(size 1.016 1.016)
					(thickness 0.1524)
				)
			)
		)
		(duplicate_pad_numbers_are_jumpers no)
		(fp_rect
			(start -0.381 0.8382)
			(end 0.381 -0.8382)
			(stroke
				(width 0)
				(type default)
			)
			(fill no)
			(layer "F.CrtYd")
		)
		(fp_rect
			(start -0.381 0.8382)
			(end 0.381 -0.8382)
			(stroke
				(width 0)
				(type default)
			)
			(fill no)
			(layer "F.Fab")
		)
		(pad "1" smd custom
			(at 0 -0.4318 270)
			(size 0.127 0.127)
			(layers "F.Cu" "F.Mask" "F.Paste")
			(net "PV_VDDR_VREF_B")
			(options
				(clearance outline)
				(anchor circle)
			)
			(primitives
				(gr_poly
					(pts
						(arc
							(start -0.2032 -0.2794)
							(mid -0.239121 -0.264521)
							(end -0.254 -0.2286)
						)
						(arc
							(start -0.254 0.2286)
							(mid -0.239121 0.264521)
							(end -0.2032 0.2794)
						)
						(arc
							(start 0.2032 0.2794)
							(mid 0.239121 0.264521)
							(end 0.254 0.2286)
						)
						(arc
							(start 0.254 -0.2286)
							(mid 0.239121 -0.264521)
							(end 0.2032 -0.2794)
						)
					)
					(width 0)
					(fill yes)
				)
			)
		)
		(pad "2" smd custom
			(at 0 0.4318 270)
			(size 0.127 0.127)
			(layers "F.Cu" "F.Mask" "F.Paste")
			(net "DDR3_M_B_VREF_DQ0")
			(options
				(clearance outline)
				(anchor circle)
			)
			(primitives
				(gr_poly
					(pts
						(arc
							(start -0.2032 -0.2794)
							(mid -0.239121 -0.264521)
							(end -0.254 -0.2286)
						)
						(arc
							(start -0.254 0.2286)
							(mid -0.239121 0.264521)
							(end -0.2032 0.2794)
						)
						(arc
							(start 0.2032 0.2794)
							(mid 0.239121 0.264521)
							(end 0.254 0.2286)
						)
						(arc
							(start 0.254 -0.2286)
							(mid 0.239121 -0.264521)
							(end 0.2032 -0.2794)
						)
					)
					(width 0)
					(fill yes)
				)
			)
		)
	)
	(footprint ""
		(layer "F.Cu")
		(at 15.494 -30.099 -90)
		(property "Reference" "PR100"
			(at 0 0 270)
			(layer "F.SilkS")
			(hide yes)
			(effects
				(font
					(size 1.27 1.27)
				)
			)
		)
		(property "Value" "3D01R5F-GP"
			(at 0 -4.9022 270)
			(unlocked yes)
			(layer "F.Fab")
			(hide yes)
			(effects
				(font
					(size 1.016 1.016)
					(thickness 0.1524)
				)
			)
		)
		(property "Device Type" "R805H24"
			(at 0 -6.8072 270)
			(unlocked yes)
			(layer "F.Fab")
			(hide yes)
			(effects
				(font
					(size 1.016 1.016)
					(thickness 0.1524)
				)
			)
		)
		(duplicate_pad_numbers_are_jumpers no)
		(fp_line
			(start -0.2794 0)
			(end -0.6096 0)
			(stroke
				(width 0.3048)
				(type default)
			)
			(layer "F.SilkS")
		)
		(fp_line
			(start 0.6096 0)
			(end 0.2794 0)
			(stroke
				(width 0.3048)
				(type default)
			)
			(layer "F.SilkS")
		)
		(fp_poly
			(pts
				(xy -0.9017 1.4351) (xy 0.9017 1.4351) (xy 0.9017 -1.4351) (xy -0.9017 -1.4351)
			)
			(stroke
				(width 0)
				(type default)
			)
			(fill no)
			(layer "F.CrtYd")
		)
		(fp_poly
			(pts
				(xy 0.9017 1.4351) (xy 0.9017 -1.4351) (xy -0.9017 -1.4351) (xy -0.9017 1.4351)
			)
			(stroke
				(width 0)
				(type default)
			)
			(fill no)
			(layer "F.Fab")
		)
		(pad "1" smd rect
			(at 0 -0.8382 270)
			(size 1.5494 0.9398)
			(layers "F.Cu" "F.Mask" "F.Paste")
			(net "P1V0_LX")
		)
		(pad "2" smd rect
			(at 0 0.8382 270)
			(size 1.5494 0.9398)
			(layers "F.Cu" "F.Mask" "F.Paste")
			(net "P1V0_SNB")
		)
	)
	(footprint ""
		(layer "F.Cu")
		(at 58.801 -41.783 -90)
		(property "Reference" "R64"
			(at 0 0 270)
			(layer "F.SilkS")
			(hide yes)
			(effects
				(font
					(size 1.27 1.27)
				)
			)
		)
		(property "Value" "4K7R2F-GP"
			(at 1.7907 -1.1176 270)
			(unlocked yes)
			(layer "F.Fab")
			(hide yes)
			(effects
				(font
					(size 1.016 1.016)
					(thickness 0.1524)
				)
			)
		)
		(property "Device Type" "R402H16"
			(at 1.7907 -2.6416 270)
			(unlocked yes)
			(layer "F.Fab")
			(hide yes)
			(effects
				(font
					(size 1.016 1.016)
					(thickness 0.1524)
				)
			)
		)
		(duplicate_pad_numbers_are_jumpers no)
		(fp_rect
			(start -0.381 0.8382)
			(end 0.381 -0.8382)
			(stroke
				(width 0)
				(type default)
			)
			(fill no)
			(layer "F.CrtYd")
		)
		(fp_rect
			(start -0.381 0.8382)
			(end 0.381 -0.8382)
			(stroke
				(width 0)
				(type default)
			)
			(fill no)
			(layer "F.Fab")
		)
		(pad "1" smd custom
			(at 0 -0.4318 270)
			(size 0.127 0.127)
			(layers "F.Cu" "F.Mask" "F.Paste")
			(net "P12V")
			(options
				(clearance outline)
				(anchor circle)
			)
			(primitives
				(gr_poly
					(pts
						(arc
							(start -0.2032 -0.2794)
							(mid -0.239121 -0.264521)
							(end -0.254 -0.2286)
						)
						(arc
							(start -0.254 0.2286)
							(mid -0.239121 0.264521)
							(end -0.2032 0.2794)
						)
						(arc
							(start 0.2032 0.2794)
							(mid 0.239121 0.264521)
							(end 0.254 0.2286)
						)
						(arc
							(start 0.254 -0.2286)
							(mid 0.239121 -0.264521)
							(end 0.2032 -0.2794)
						)
					)
					(width 0)
					(fill yes)
				)
			)
		)
		(pad "2" smd custom
			(at 0 0.4318 270)
			(size 0.127 0.127)
			(layers "F.Cu" "F.Mask" "F.Paste")
			(net "SW_P3V3_LV_G5")
			(options
				(clearance outline)
				(anchor circle)
			)
			(primitives
				(gr_poly
					(pts
						(arc
							(start -0.2032 -0.2794)
							(mid -0.239121 -0.264521)
							(end -0.254 -0.2286)
						)
						(arc
							(start -0.254 0.2286)
							(mid -0.239121 0.264521)
							(end -0.2032 0.2794)
						)
						(arc
							(start 0.2032 0.2794)
							(mid 0.239121 0.264521)
							(end 0.254 0.2286)
						)
						(arc
							(start 0.254 -0.2286)
							(mid 0.239121 -0.264521)
							(end 0.2032 -0.2794)
						)
					)
					(width 0)
					(fill yes)
				)
			)
		)
	)
	(footprint ""
		(layer "F.Cu")
		(at 132.588 -54.737 -90)
		(property "Reference" "PC66"
			(at 0 0 270)
			(layer "F.SilkS")
			(hide yes)
			(effects
				(font
					(size 1.27 1.27)
				)
			)
		)
		(property "Value" "SCD1U16V2KX-3GP"
			(at 1.1811 -2.7051 270)
			(unlocked yes)
			(layer "F.Fab")
			(hide yes)
			(effects
				(font
					(size 1.016 1.016)
					(thickness 0.1524)
				)
			)
		)
		(property "Device Type" "C402H22"
			(at 1.1811 -4.2291 270)
			(unlocked yes)
			(layer "F.Fab")
			(hide yes)
			(effects
				(font
					(size 1.016 1.016)
					(thickness 0.1524)
				)
			)
		)
		(duplicate_pad_numbers_are_jumpers no)
		(fp_rect
			(start -0.381 0.7366)
			(end 0.381 -0.7366)
			(stroke
				(width 0)
				(type default)
			)
			(fill no)
			(layer "F.CrtYd")
		)
		(fp_rect
			(start -0.381 0.7366)
			(end 0.381 -0.7366)
			(stroke
				(width 0)
				(type default)
			)
			(fill no)
			(layer "F.Fab")
		)
		(pad "1" smd custom
			(at 0 -0.4572 270)
			(size 0.1143 0.1143)
			(layers "F.Cu" "F.Mask" "F.Paste")
			(net "PV_VTT_DDR_SNS")
			(options
				(clearance outline)
				(anchor circle)
			)
			(primitives
				(gr_poly
					(pts
						(arc
							(start -0.254 -0.1778)
							(mid -0.239121 -0.213721)
							(end -0.2032 -0.2286)
						)
						(arc
							(start 0.2032 -0.2286)
							(mid 0.239121 -0.213721)
							(end 0.254 -0.1778)
						)
						(arc
							(start 0.254 0.1778)
							(mid 0.239121 0.213721)
							(end 0.2032 0.2286)
						)
						(arc
							(start -0.2032 0.2286)
							(mid -0.239121 0.213721)
							(end -0.254 0.1778)
						)
					)
					(width 0)
					(fill yes)
				)
			)
		)
		(pad "2" smd custom
			(at 0 0.4572 270)
			(size 0.1143 0.1143)
			(layers "F.Cu" "F.Mask" "F.Paste")
			(net "GND")
			(options
				(clearance outline)
				(anchor circle)
			)
			(primitives
				(gr_poly
					(pts
						(arc
							(start -0.254 -0.1778)
							(mid -0.239121 -0.213721)
							(end -0.2032 -0.2286)
						)
						(arc
							(start 0.2032 -0.2286)
							(mid 0.239121 -0.213721)
							(end 0.254 -0.1778)
						)
						(arc
							(start 0.254 0.1778)
							(mid 0.239121 0.213721)
							(end 0.2032 0.2286)
						)
						(arc
							(start -0.2032 0.2286)
							(mid -0.239121 0.213721)
							(end -0.254 0.1778)
						)
					)
					(width 0)
					(fill yes)
				)
			)
		)
	)
	(footprint ""
		(layer "F.Cu")
		(at 50.2158 -12.7)
		(property "Reference" "C313"
			(at 0 0 0)
			(layer "F.SilkS")
			(hide yes)
			(effects
				(font
					(size 1.27 1.27)
				)
			)
		)
		(property "Value" "SCD047U25V2KX-GP"
			(at 1.8923 -1.2065 0)
			(unlocked yes)
			(layer "F.Fab")
			(hide yes)
			(effects
				(font
					(size 1.016 1.016)
					(thickness 0.1524)
				)
			)
		)
		(property "Device Type" "C402H22"
			(at 1.8923 -2.7305 0)
			(unlocked yes)
			(layer "F.Fab")
			(hide yes)
			(effects
				(font
					(size 1.016 1.016)
					(thickness 0.1524)
				)
			)
		)
		(duplicate_pad_numbers_are_jumpers no)
		(fp_rect
			(start -0.381 0.7366)
			(end 0.381 -0.7366)
			(stroke
				(width 0)
				(type default)
			)
			(fill no)
			(layer "F.CrtYd")
		)
		(fp_rect
			(start -0.381 0.7366)
			(end 0.381 -0.7366)
			(stroke
				(width 0)
				(type default)
			)
			(fill no)
			(layer "F.Fab")
		)
		(pad "1" smd custom
			(at 0 -0.4572)
			(size 0.1143 0.1143)
			(layers "F.Cu" "F.Mask" "F.Paste")
			(net "CPU_GBE_TX_DP0")
			(options
				(clearance outline)
				(anchor circle)
			)
			(primitives
				(gr_poly
					(pts
						(arc
							(start -0.254 -0.1778)
							(mid -0.239121 -0.213721)
							(end -0.2032 -0.2286)
						)
						(arc
							(start 0.2032 -0.2286)
							(mid 0.239121 -0.213721)
							(end 0.254 -0.1778)
						)
						(arc
							(start 0.254 0.1778)
							(mid 0.239121 0.213721)
							(end 0.2032 0.2286)
						)
						(arc
							(start -0.2032 0.2286)
							(mid -0.239121 0.213721)
							(end -0.254 0.1778)
						)
					)
					(width 0)
					(fill yes)
				)
			)
		)
		(pad "2" smd custom
			(at 0 0.4572)
			(size 0.1143 0.1143)
			(layers "F.Cu" "F.Mask" "F.Paste")
			(net "CPU_GBE_TX_C_DP0")
			(options
				(clearance outline)
				(anchor circle)
			)
			(primitives
				(gr_poly
					(pts
						(arc
							(start -0.254 -0.1778)
							(mid -0.239121 -0.213721)
							(end -0.2032 -0.2286)
						)
						(arc
							(start 0.2032 -0.2286)
							(mid 0.239121 -0.213721)
							(end 0.254 -0.1778)
						)
						(arc
							(start 0.254 0.1778)
							(mid 0.239121 0.213721)
							(end 0.2032 0.2286)
						)
						(arc
							(start -0.2032 0.2286)
							(mid -0.239121 0.213721)
							(end -0.254 0.1778)
						)
					)
					(width 0)
					(fill yes)
				)
			)
		)
	)
	(footprint ""
		(layer "F.Cu")
		(at 128.143 -36.83 -90)
		(property "Reference" "R30"
			(at 0 0 270)
			(layer "F.SilkS")
			(hide yes)
			(effects
				(font
					(size 1.27 1.27)
				)
			)
		)
		(property "Value" "33R2F-3-GP"
			(at 0.064008 -3.993896 270)
			(unlocked yes)
			(layer "F.Fab")
			(hide yes)
			(effects
				(font
					(size 1.016 1.016)
					(thickness 0.1524)
				)
			)
		)
		(property "Device Type" "R402H16"
			(at 0.064008 -5.517896 270)
			(unlocked yes)
			(layer "F.Fab")
			(hide yes)
			(effects
				(font
					(size 1.016 1.016)
					(thickness 0.1524)
				)
			)
		)
		(duplicate_pad_numbers_are_jumpers no)
		(fp_rect
			(start -0.381 0.8382)
			(end 0.381 -0.8382)
			(stroke
				(width 0)
				(type default)
			)
			(fill no)
			(layer "F.CrtYd")
		)
		(fp_rect
			(start -0.381 0.8382)
			(end 0.381 -0.8382)
			(stroke
				(width 0)
				(type default)
			)
			(fill no)
			(layer "F.Fab")
		)
		(pad "1" smd custom
			(at 0 -0.4318 270)
			(size 0.127 0.127)
			(layers "F.Cu" "F.Mask" "F.Paste")
			(net "LPC_AD_2")
			(options
				(clearance outline)
				(anchor circle)
			)
			(primitives
				(gr_poly
					(pts
						(arc
							(start -0.2032 -0.2794)
							(mid -0.239121 -0.264521)
							(end -0.254 -0.2286)
						)
						(arc
							(start -0.254 0.2286)
							(mid -0.239121 0.264521)
							(end -0.2032 0.2794)
						)
						(arc
							(start 0.2032 0.2794)
							(mid 0.239121 0.264521)
							(end 0.254 0.2286)
						)
						(arc
							(start 0.254 -0.2286)
							(mid 0.239121 -0.264521)
							(end 0.2032 -0.2794)
						)
					)
					(width 0)
					(fill yes)
				)
			)
		)
		(pad "2" smd custom
			(at 0 0.4318 270)
			(size 0.127 0.127)
			(layers "F.Cu" "F.Mask" "F.Paste")
			(net "LPC_CPU_LAD2")
			(options
				(clearance outline)
				(anchor circle)
			)
			(primitives
				(gr_poly
					(pts
						(arc
							(start -0.2032 -0.2794)
							(mid -0.239121 -0.264521)
							(end -0.254 -0.2286)
						)
						(arc
							(start -0.254 0.2286)
							(mid -0.239121 0.264521)
							(end -0.2032 0.2794)
						)
						(arc
							(start 0.2032 0.2794)
							(mid 0.239121 0.264521)
							(end 0.254 0.2286)
						)
						(arc
							(start 0.254 -0.2286)
							(mid 0.239121 -0.264521)
							(end 0.2032 -0.2794)
						)
					)
					(width 0)
					(fill yes)
				)
			)
		)
	)
	(footprint ""
		(layer "F.Cu")
		(at 141.2748 -56.0578 -90)
		(property "Reference" "PR72"
			(at 0 0 270)
			(layer "F.SilkS")
			(hide yes)
			(effects
				(font
					(size 1.27 1.27)
				)
			)
		)
		(property "Value" "0R2J-2-GP"
			(at 0.064008 -3.993896 270)
			(unlocked yes)
			(layer "F.Fab")
			(hide yes)
			(effects
				(font
					(size 1.016 1.016)
					(thickness 0.1524)
				)
			)
		)
		(property "Device Type" "R402H16"
			(at 0.064008 -5.517896 270)
			(unlocked yes)
			(layer "F.Fab")
			(hide yes)
			(effects
				(font
					(size 1.016 1.016)
					(thickness 0.1524)
				)
			)
		)
		(duplicate_pad_numbers_are_jumpers no)
		(fp_rect
			(start -0.381 0.8382)
			(end 0.381 -0.8382)
			(stroke
				(width 0)
				(type default)
			)
			(fill no)
			(layer "F.CrtYd")
		)
		(fp_rect
			(start -0.381 0.8382)
			(end 0.381 -0.8382)
			(stroke
				(width 0)
				(type default)
			)
			(fill no)
			(layer "F.Fab")
		)
		(pad "1" smd custom
			(at 0 -0.4318 270)
			(size 0.127 0.127)
			(layers "F.Cu" "F.Mask" "F.Paste")
			(net "PVTT_DDR_EN")
			(options
				(clearance outline)
				(anchor circle)
			)
			(primitives
				(gr_poly
					(pts
						(arc
							(start -0.2032 -0.2794)
							(mid -0.239121 -0.264521)
							(end -0.254 -0.2286)
						)
						(arc
							(start -0.254 0.2286)
							(mid -0.239121 0.264521)
							(end -0.2032 0.2794)
						)
						(arc
							(start 0.2032 0.2794)
							(mid 0.239121 0.264521)
							(end 0.254 0.2286)
						)
						(arc
							(start 0.254 -0.2286)
							(mid 0.239121 -0.264521)
							(end 0.2032 -0.2794)
						)
					)
					(width 0)
					(fill yes)
				)
			)
		)
		(pad "2" smd custom
			(at 0 0.4318 270)
			(size 0.127 0.127)
			(layers "F.Cu" "F.Mask" "F.Paste")
			(net "PV_VTT_DDR_EN")
			(options
				(clearance outline)
				(anchor circle)
			)
			(primitives
				(gr_poly
					(pts
						(arc
							(start -0.2032 -0.2794)
							(mid -0.239121 -0.264521)
							(end -0.254 -0.2286)
						)
						(arc
							(start -0.254 0.2286)
							(mid -0.239121 0.264521)
							(end -0.2032 0.2794)
						)
						(arc
							(start 0.2032 0.2794)
							(mid 0.239121 0.264521)
							(end 0.254 0.2286)
						)
						(arc
							(start 0.254 -0.2286)
							(mid 0.239121 -0.264521)
							(end 0.2032 -0.2794)
						)
					)
					(width 0)
					(fill yes)
				)
			)
		)
	)
	(footprint ""
		(layer "F.Cu")
		(at 68.072 -50.292 -90)
		(property "Reference" "R460"
			(at 0 0 270)
			(layer "F.SilkS")
			(hide yes)
			(effects
				(font
					(size 1.27 1.27)
				)
			)
		)
		(property "Value" "0R2J-2-GP"
			(at 1.7907 -1.1176 270)
			(unlocked yes)
			(layer "F.Fab")
			(hide yes)
			(effects
				(font
					(size 1.016 1.016)
					(thickness 0.1524)
				)
			)
		)
		(property "Device Type" "R402H16"
			(at 1.7907 -2.6416 270)
			(unlocked yes)
			(layer "F.Fab")
			(hide yes)
			(effects
				(font
					(size 1.016 1.016)
					(thickness 0.1524)
				)
			)
		)
		(duplicate_pad_numbers_are_jumpers no)
		(fp_rect
			(start -0.381 0.8382)
			(end 0.381 -0.8382)
			(stroke
				(width 0)
				(type default)
			)
			(fill no)
			(layer "F.CrtYd")
		)
		(fp_rect
			(start -0.381 0.8382)
			(end 0.381 -0.8382)
			(stroke
				(width 0)
				(type default)
			)
			(fill no)
			(layer "F.Fab")
		)
		(pad "1" smd custom
			(at 0 -0.4318 270)
			(size 0.127 0.127)
			(layers "F.Cu" "F.Mask" "F.Paste")
			(net "SMBUS_PECI_SW_EN")
			(options
				(clearance outline)
				(anchor circle)
			)
			(primitives
				(gr_poly
					(pts
						(arc
							(start -0.2032 -0.2794)
							(mid -0.239121 -0.264521)
							(end -0.254 -0.2286)
						)
						(arc
							(start -0.254 0.2286)
							(mid -0.239121 0.264521)
							(end -0.2032 0.2794)
						)
						(arc
							(start 0.2032 0.2794)
							(mid 0.239121 0.264521)
							(end 0.254 0.2286)
						)
						(arc
							(start 0.254 -0.2286)
							(mid 0.239121 -0.264521)
							(end 0.2032 -0.2794)
						)
					)
					(width 0)
					(fill yes)
				)
			)
		)
		(pad "2" smd custom
			(at 0 0.4318 270)
			(size 0.127 0.127)
			(layers "F.Cu" "F.Mask" "F.Paste")
			(net "SMBUS_SW_INV_D")
			(options
				(clearance outline)
				(anchor circle)
			)
			(primitives
				(gr_poly
					(pts
						(arc
							(start -0.2032 -0.2794)
							(mid -0.239121 -0.264521)
							(end -0.254 -0.2286)
						)
						(arc
							(start -0.254 0.2286)
							(mid -0.239121 0.264521)
							(end -0.2032 0.2794)
						)
						(arc
							(start 0.2032 0.2794)
							(mid 0.239121 0.264521)
							(end 0.254 0.2286)
						)
						(arc
							(start 0.254 -0.2286)
							(mid 0.239121 -0.264521)
							(end 0.2032 -0.2794)
						)
					)
					(width 0)
					(fill yes)
				)
			)
		)
	)
	(footprint ""
		(layer "F.Cu")
		(at 12.954 -29.464 -90)
		(property "Reference" "PC76"
			(at 0 0 270)
			(layer "F.SilkS")
			(hide yes)
			(effects
				(font
					(size 1.27 1.27)
				)
			)
		)
		(property "Value" "SC470P50V2KX-3GP"
			(at 1.8923 -1.2065 270)
			(unlocked yes)
			(layer "F.Fab")
			(hide yes)
			(effects
				(font
					(size 1.016 1.016)
					(thickness 0.1524)
				)
			)
		)
		(property "Device Type" "C402H22"
			(at 1.8923 -2.7305 270)
			(unlocked yes)
			(layer "F.Fab")
			(hide yes)
			(effects
				(font
					(size 1.016 1.016)
					(thickness 0.1524)
				)
			)
		)
		(duplicate_pad_numbers_are_jumpers no)
		(fp_rect
			(start -0.381 0.7366)
			(end 0.381 -0.7366)
			(stroke
				(width 0)
				(type default)
			)
			(fill no)
			(layer "F.CrtYd")
		)
		(fp_rect
			(start -0.381 0.7366)
			(end 0.381 -0.7366)
			(stroke
				(width 0)
				(type default)
			)
			(fill no)
			(layer "F.Fab")
		)
		(pad "1" smd custom
			(at 0 -0.4572 270)
			(size 0.1143 0.1143)
			(layers "F.Cu" "F.Mask" "F.Paste")
			(net "P1V0_SNB")
			(options
				(clearance outline)
				(anchor circle)
			)
			(primitives
				(gr_poly
					(pts
						(arc
							(start -0.254 -0.1778)
							(mid -0.239121 -0.213721)
							(end -0.2032 -0.2286)
						)
						(arc
							(start 0.2032 -0.2286)
							(mid 0.239121 -0.213721)
							(end 0.254 -0.1778)
						)
						(arc
							(start 0.254 0.1778)
							(mid 0.239121 0.213721)
							(end 0.2032 0.2286)
						)
						(arc
							(start -0.2032 0.2286)
							(mid -0.239121 0.213721)
							(end -0.254 0.1778)
						)
					)
					(width 0)
					(fill yes)
				)
			)
		)
		(pad "2" smd custom
			(at 0 0.4572 270)
			(size 0.1143 0.1143)
			(layers "F.Cu" "F.Mask" "F.Paste")
			(net "GND")
			(options
				(clearance outline)
				(anchor circle)
			)
			(primitives
				(gr_poly
					(pts
						(arc
							(start -0.254 -0.1778)
							(mid -0.239121 -0.213721)
							(end -0.2032 -0.2286)
						)
						(arc
							(start 0.2032 -0.2286)
							(mid 0.239121 -0.213721)
							(end 0.254 -0.1778)
						)
						(arc
							(start 0.254 0.1778)
							(mid 0.239121 0.213721)
							(end 0.2032 0.2286)
						)
						(arc
							(start -0.2032 0.2286)
							(mid -0.239121 0.213721)
							(end -0.254 0.1778)
						)
					)
					(width 0)
					(fill yes)
				)
			)
		)
	)
	(footprint ""
		(layer "F.Cu")
		(at 29.2608 -55.3212 -90)
		(property "Reference" "PR50"
			(at 0 0 270)
			(layer "F.SilkS")
			(hide yes)
			(effects
				(font
					(size 1.27 1.27)
				)
			)
		)
		(property "Value" "10KR2F-2-GP"
			(at 1.7907 -1.1176 270)
			(unlocked yes)
			(layer "F.Fab")
			(hide yes)
			(effects
				(font
					(size 1.016 1.016)
					(thickness 0.1524)
				)
			)
		)
		(property "Device Type" "R402H16"
			(at 1.7907 -2.6416 270)
			(unlocked yes)
			(layer "F.Fab")
			(hide yes)
			(effects
				(font
					(size 1.016 1.016)
					(thickness 0.1524)
				)
			)
		)
		(duplicate_pad_numbers_are_jumpers no)
		(fp_rect
			(start -0.381 0.8382)
			(end 0.381 -0.8382)
			(stroke
				(width 0)
				(type default)
			)
			(fill no)
			(layer "F.CrtYd")
		)
		(fp_rect
			(start -0.381 0.8382)
			(end 0.381 -0.8382)
			(stroke
				(width 0)
				(type default)
			)
			(fill no)
			(layer "F.Fab")
		)
		(pad "1" smd custom
			(at 0 -0.4318 270)
			(size 0.127 0.127)
			(layers "F.Cu" "F.Mask" "F.Paste")
			(net "VR_PVCCP_PHASE")
			(options
				(clearance outline)
				(anchor circle)
			)
			(primitives
				(gr_poly
					(pts
						(arc
							(start -0.2032 -0.2794)
							(mid -0.239121 -0.264521)
							(end -0.254 -0.2286)
						)
						(arc
							(start -0.254 0.2286)
							(mid -0.239121 0.264521)
							(end -0.2032 0.2794)
						)
						(arc
							(start 0.2032 0.2794)
							(mid 0.239121 0.264521)
							(end 0.254 0.2286)
						)
						(arc
							(start 0.254 -0.2286)
							(mid 0.239121 -0.264521)
							(end 0.2032 -0.2794)
						)
					)
					(width 0)
					(fill yes)
				)
			)
		)
		(pad "2" smd custom
			(at 0 0.4318 270)
			(size 0.127 0.127)
			(layers "F.Cu" "F.Mask" "F.Paste")
			(net "VR_PVCCP_GH_R")
			(options
				(clearance outline)
				(anchor circle)
			)
			(primitives
				(gr_poly
					(pts
						(arc
							(start -0.2032 -0.2794)
							(mid -0.239121 -0.264521)
							(end -0.254 -0.2286)
						)
						(arc
							(start -0.254 0.2286)
							(mid -0.239121 0.264521)
							(end -0.2032 0.2794)
						)
						(arc
							(start 0.2032 0.2794)
							(mid 0.239121 0.264521)
							(end 0.254 0.2286)
						)
						(arc
							(start 0.254 -0.2286)
							(mid 0.239121 -0.264521)
							(end 0.2032 -0.2794)
						)
					)
					(width 0)
					(fill yes)
				)
			)
		)
	)
	(footprint ""
		(layer "F.Cu")
		(at 56.515 -42.037 180)
		(property "Reference" "U11"
			(at 0 0 180)
			(layer "F.SilkS")
			(hide yes)
			(effects
				(font
					(size 1.27 1.27)
				)
			)
		)
		(property "Value" "2N7002DW-7F-GP"
			(at -2.5654 1.1049 180)
			(unlocked yes)
			(layer "F.Fab")
			(hide yes)
			(effects
				(font
					(size 1.016 1.016)
					(thickness 0.1524)
				)
			)
		)
		(property "Device Type" "SOT-363H44"
			(at -2.5654 -0.4191 180)
			(unlocked yes)
			(layer "F.Fab")
			(hide yes)
			(effects
				(font
					(size 1.016 1.016)
					(thickness 0.1524)
				)
			)
		)
		(duplicate_pad_numbers_are_jumpers no)
		(fp_poly
			(pts
				(xy -0.6477 1.4351) (xy -0.9525 1.7399) (xy -0.3556 1.7399) (xy -0.3429 1.7399) (xy -0.3556 1.7272)
			)
			(stroke
				(width 0)
				(type default)
			)
			(fill yes)
			(layer "F.SilkS")
		)
		(fp_poly
			(pts
				(xy 1.2573 0.8763) (xy 1.2573 -0.8763) (xy 0.9525 -0.8763) (xy 0.9525 -1.4351) (xy -0.9525 -1.4351)
				(xy -0.9525 -0.8763) (xy -1.2573 -0.8763) (xy -1.2573 0.8763) (xy -0.9525 0.8763) (xy -0.9525 1.4351)
				(xy 0.9525 1.4351) (xy 0.9525 0.8763)
			)
			(stroke
				(width 0)
				(type default)
			)
			(fill no)
			(layer "F.CrtYd")
		)
		(fp_poly
			(pts
				(xy 1.2573 0.8763) (xy 1.2573 -0.8763) (xy 0.9525 -0.8763) (xy 0.9525 -1.4351) (xy -0.9525 -1.4351)
				(xy -0.9525 -0.8763) (xy -1.2573 -0.8763) (xy -1.2573 0.8763) (xy -0.9525 0.8763) (xy -0.9525 1.4351)
				(xy 0.9525 1.4351) (xy 0.9525 0.8763)
			)
			(stroke
				(width 0)
				(type default)
			)
			(fill no)
			(layer "F.Fab")
		)
		(pad "1" smd rect
			(at -0.65024 0.8255 180)
			(size 0.3556 0.9652)
			(layers "F.Cu" "F.Mask" "F.Paste")
			(net "GND")
		)
		(pad "2" smd rect
			(at 0 0.8255 180)
			(size 0.3556 0.9652)
			(layers "F.Cu" "F.Mask" "F.Paste")
			(net "SW_P3V3_EN_G2")
		)
		(pad "3" smd rect
			(at 0.65024 0.8255 180)
			(size 0.3556 0.9652)
			(layers "F.Cu" "F.Mask" "F.Paste")
			(net "SW_P3V3_EN_LV_D")
		)
		(pad "4" smd rect
			(at 0.65024 -0.8255 180)
			(size 0.3556 0.9652)
			(layers "F.Cu" "F.Mask" "F.Paste")
			(net "GND")
		)
		(pad "5" smd rect
			(at 0 -0.8255 180)
			(size 0.3556 0.9652)
			(layers "F.Cu" "F.Mask" "F.Paste")
			(net "SW_P3V3_LV_G5")
		)
		(pad "6" smd rect
			(at -0.65024 -0.8255 180)
			(size 0.3556 0.9652)
			(layers "F.Cu" "F.Mask" "F.Paste")
			(net "SW_P3V3_LV_G5")
		)
	)
	(footprint ""
		(layer "F.Cu")
		(at 137.541 -18.415 -90)
		(property "Reference" "R470"
			(at 0 0 270)
			(layer "F.SilkS")
			(hide yes)
			(effects
				(font
					(size 1.27 1.27)
				)
			)
		)
		(property "Value" "4K7R2F-GP"
			(at 1.7907 -1.1176 270)
			(unlocked yes)
			(layer "F.Fab")
			(hide yes)
			(effects
				(font
					(size 1.016 1.016)
					(thickness 0.1524)
				)
			)
		)
		(property "Device Type" "R402H16"
			(at 1.7907 -2.6416 270)
			(unlocked yes)
			(layer "F.Fab")
			(hide yes)
			(effects
				(font
					(size 1.016 1.016)
					(thickness 0.1524)
				)
			)
		)
		(duplicate_pad_numbers_are_jumpers no)
		(fp_rect
			(start -0.381 0.8382)
			(end 0.381 -0.8382)
			(stroke
				(width 0)
				(type default)
			)
			(fill no)
			(layer "F.CrtYd")
		)
		(fp_rect
			(start -0.381 0.8382)
			(end 0.381 -0.8382)
			(stroke
				(width 0)
				(type default)
			)
			(fill no)
			(layer "F.Fab")
		)
		(pad "1" smd custom
			(at 0 -0.4318 270)
			(size 0.127 0.127)
			(layers "F.Cu" "F.Mask" "F.Paste")
			(net "P3V3_STBY")
			(options
				(clearance outline)
				(anchor circle)
			)
			(primitives
				(gr_poly
					(pts
						(arc
							(start -0.2032 -0.2794)
							(mid -0.239121 -0.264521)
							(end -0.254 -0.2286)
						)
						(arc
							(start -0.254 0.2286)
							(mid -0.239121 0.264521)
							(end -0.2032 0.2794)
						)
						(arc
							(start 0.2032 0.2794)
							(mid 0.239121 0.264521)
							(end 0.254 0.2286)
						)
						(arc
							(start 0.254 -0.2286)
							(mid 0.239121 -0.264521)
							(end 0.2032 -0.2794)
						)
					)
					(width 0)
					(fill yes)
				)
			)
		)
		(pad "2" smd custom
			(at 0 0.4318 270)
			(size 0.127 0.127)
			(layers "F.Cu" "F.Mask" "F.Paste")
			(net "HOST_LV_D_RSTBTN#")
			(options
				(clearance outline)
				(anchor circle)
			)
			(primitives
				(gr_poly
					(pts
						(arc
							(start -0.2032 -0.2794)
							(mid -0.239121 -0.264521)
							(end -0.254 -0.2286)
						)
						(arc
							(start -0.254 0.2286)
							(mid -0.239121 0.264521)
							(end -0.2032 0.2794)
						)
						(arc
							(start 0.2032 0.2794)
							(mid 0.239121 0.264521)
							(end 0.254 0.2286)
						)
						(arc
							(start 0.254 -0.2286)
							(mid 0.239121 -0.264521)
							(end 0.2032 -0.2794)
						)
					)
					(width 0)
					(fill yes)
				)
			)
		)
	)
	(footprint ""
		(layer "F.Cu")
		(at 109.1438 -19.177 90)
		(property "Reference" "R167"
			(at 0 0 90)
			(layer "F.SilkS")
			(hide yes)
			(effects
				(font
					(size 1.27 1.27)
				)
			)
		)
		(property "Value" "100R3F-1-GP"
			(at -0.0254 -2.5146 90)
			(unlocked yes)
			(layer "F.Fab")
			(hide yes)
			(effects
				(font
					(size 1.016 1.016)
					(thickness 0.1524)
				)
			)
		)
		(property "Device Type" "R603H22"
			(at -0.0254 -4.0386 90)
			(unlocked yes)
			(layer "F.Fab")
			(hide yes)
			(effects
				(font
					(size 1.016 1.016)
					(thickness 0.1524)
				)
			)
		)
		(duplicate_pad_numbers_are_jumpers no)
		(fp_line
			(start 0.4318 0)
			(end 0.2032 0)
			(stroke
				(width 0.2032)
				(type default)
			)
			(layer "F.SilkS")
		)
		(fp_line
			(start -0.2032 0)
			(end -0.4191 0)
			(stroke
				(width 0.2032)
				(type default)
			)
			(layer "F.SilkS")
		)
		(fp_rect
			(start -0.635 1.1811)
			(end 0.635 -1.1811)
			(stroke
				(width 0)
				(type default)
			)
			(fill no)
			(layer "F.CrtYd")
		)
		(fp_rect
			(start -0.635 1.1811)
			(end 0.635 -1.1811)
			(stroke
				(width 0)
				(type default)
			)
			(fill no)
			(layer "F.Fab")
		)
		(pad "1" smd custom
			(at 0 -0.6604 90)
			(size 0.19685 0.19685)
			(layers "F.Cu" "F.Mask" "F.Paste")
			(net "M_B_MON2_P")
			(options
				(clearance outline)
				(anchor circle)
			)
			(primitives
				(gr_poly
					(pts
						(arc
							(start 0.508 -0.2921)
							(mid 0.478242 -0.363942)
							(end 0.4064 -0.3937)
						)
						(arc
							(start -0.4064 -0.3937)
							(mid -0.478242 -0.363942)
							(end -0.508 -0.2921)
						)
						(arc
							(start -0.508 0.2921)
							(mid -0.478242 0.363942)
							(end -0.4064 0.3937)
						)
						(arc
							(start 0.4064 0.3937)
							(mid 0.478242 0.363942)
							(end 0.508 0.2921)
						)
					)
					(width 0)
					(fill yes)
				)
			)
		)
		(pad "2" smd custom
			(at 0 0.6604 90)
			(size 0.19685 0.19685)
			(layers "F.Cu" "F.Mask" "F.Paste")
			(net "M_B_MON2_N")
			(options
				(clearance outline)
				(anchor circle)
			)
			(primitives
				(gr_poly
					(pts
						(arc
							(start 0.508 -0.2921)
							(mid 0.478242 -0.363942)
							(end 0.4064 -0.3937)
						)
						(arc
							(start -0.4064 -0.3937)
							(mid -0.478242 -0.363942)
							(end -0.508 -0.2921)
						)
						(arc
							(start -0.508 0.2921)
							(mid -0.478242 0.363942)
							(end -0.4064 0.3937)
						)
						(arc
							(start 0.4064 0.3937)
							(mid 0.478242 0.363942)
							(end 0.508 0.2921)
						)
					)
					(width 0)
					(fill yes)
				)
			)
		)
	)
	(footprint ""
		(layer "F.Cu")
		(at 16.0528 -51.2572 90)
		(property "Reference" "PC147"
			(at 0 0 90)
			(layer "F.SilkS")
			(hide yes)
			(effects
				(font
					(size 1.27 1.27)
				)
			)
		)
		(property "Value" "SC100P50V2JN-3GP"
			(at 1.8923 -1.2065 90)
			(unlocked yes)
			(layer "F.Fab")
			(hide yes)
			(effects
				(font
					(size 1.016 1.016)
					(thickness 0.1524)
				)
			)
		)
		(property "Device Type" "C402H22"
			(at 1.8923 -2.7305 90)
			(unlocked yes)
			(layer "F.Fab")
			(hide yes)
			(effects
				(font
					(size 1.016 1.016)
					(thickness 0.1524)
				)
			)
		)
		(duplicate_pad_numbers_are_jumpers no)
		(fp_rect
			(start -0.381 0.7366)
			(end 0.381 -0.7366)
			(stroke
				(width 0)
				(type default)
			)
			(fill no)
			(layer "F.CrtYd")
		)
		(fp_rect
			(start -0.381 0.7366)
			(end 0.381 -0.7366)
			(stroke
				(width 0)
				(type default)
			)
			(fill no)
			(layer "F.Fab")
		)
		(pad "1" smd custom
			(at 0 -0.4572 90)
			(size 0.1143 0.1143)
			(layers "F.Cu" "F.Mask" "F.Paste")
			(net "VR_PVCCP_COMP")
			(options
				(clearance outline)
				(anchor circle)
			)
			(primitives
				(gr_poly
					(pts
						(arc
							(start -0.254 -0.1778)
							(mid -0.239121 -0.213721)
							(end -0.2032 -0.2286)
						)
						(arc
							(start 0.2032 -0.2286)
							(mid 0.239121 -0.213721)
							(end 0.254 -0.1778)
						)
						(arc
							(start 0.254 0.1778)
							(mid 0.239121 0.213721)
							(end 0.2032 0.2286)
						)
						(arc
							(start -0.2032 0.2286)
							(mid -0.239121 0.213721)
							(end -0.254 0.1778)
						)
					)
					(width 0)
					(fill yes)
				)
			)
		)
		(pad "2" smd custom
			(at 0 0.4572 90)
			(size 0.1143 0.1143)
			(layers "F.Cu" "F.Mask" "F.Paste")
			(net "VR_PVCCP_FB")
			(options
				(clearance outline)
				(anchor circle)
			)
			(primitives
				(gr_poly
					(pts
						(arc
							(start -0.254 -0.1778)
							(mid -0.239121 -0.213721)
							(end -0.2032 -0.2286)
						)
						(arc
							(start 0.2032 -0.2286)
							(mid 0.239121 -0.213721)
							(end 0.254 -0.1778)
						)
						(arc
							(start 0.254 0.1778)
							(mid 0.239121 0.213721)
							(end 0.2032 0.2286)
						)
						(arc
							(start -0.2032 0.2286)
							(mid -0.239121 0.213721)
							(end -0.254 0.1778)
						)
					)
					(width 0)
					(fill yes)
				)
			)
		)
	)
	(footprint ""
		(layer "F.Cu")
		(at 5.08 -25.527)
		(property "Reference" "PC91"
			(at 0 0 0)
			(layer "F.SilkS")
			(hide yes)
			(effects
				(font
					(size 1.27 1.27)
				)
			)
		)
		(property "Value" "SC22U25V5MX-GP"
			(at 0 -4.9022 0)
			(unlocked yes)
			(layer "F.Fab")
			(hide yes)
			(effects
				(font
					(size 1.016 1.016)
					(thickness 0.1524)
				)
			)
		)
		(property "Device Type" "C805H58"
			(at 0 -6.8072 0)
			(unlocked yes)
			(layer "F.Fab")
			(hide yes)
			(effects
				(font
					(size 1.016 1.016)
					(thickness 0.1524)
				)
			)
		)
		(duplicate_pad_numbers_are_jumpers no)
		(fp_line
			(start 0.6096 0)
			(end -0.6096 0)
			(stroke
				(width 0.3048)
				(type default)
			)
			(layer "F.SilkS")
		)
		(fp_poly
			(pts
				(xy -0.9017 1.4351) (xy 0.9017 1.4351) (xy 0.9017 -1.4351) (xy -0.9017 -1.4351)
			)
			(stroke
				(width 0)
				(type default)
			)
			(fill no)
			(layer "F.CrtYd")
		)
		(fp_poly
			(pts
				(xy 0.9017 1.4351) (xy 0.9017 -1.4351) (xy -0.9017 -1.4351) (xy -0.9017 1.4351)
			)
			(stroke
				(width 0)
				(type default)
			)
			(fill no)
			(layer "F.Fab")
		)
		(pad "1" smd rect
			(at 0 -0.8382)
			(size 1.5494 0.9398)
			(layers "F.Cu" "F.Mask" "F.Paste")
			(net "P1V0_VIN")
		)
		(pad "2" smd rect
			(at 0 0.8382)
			(size 1.5494 0.9398)
			(layers "F.Cu" "F.Mask" "F.Paste")
			(net "GND")
		)
	)
	(footprint ""
		(layer "F.Cu")
		(at 28.829 -13.335)
		(property "Reference" "R462"
			(at 0 0 0)
			(layer "F.SilkS")
			(hide yes)
			(effects
				(font
					(size 1.27 1.27)
				)
			)
		)
		(property "Value" "4K7R2F-GP"
			(at 1.7907 -1.1176 0)
			(unlocked yes)
			(layer "F.Fab")
			(hide yes)
			(effects
				(font
					(size 1.016 1.016)
					(thickness 0.1524)
				)
			)
		)
		(property "Device Type" "R402H16"
			(at 1.7907 -2.6416 0)
			(unlocked yes)
			(layer "F.Fab")
			(hide yes)
			(effects
				(font
					(size 1.016 1.016)
					(thickness 0.1524)
				)
			)
		)
		(duplicate_pad_numbers_are_jumpers no)
		(fp_rect
			(start -0.381 0.8382)
			(end 0.381 -0.8382)
			(stroke
				(width 0)
				(type default)
			)
			(fill no)
			(layer "F.CrtYd")
		)
		(fp_rect
			(start -0.381 0.8382)
			(end 0.381 -0.8382)
			(stroke
				(width 0)
				(type default)
			)
			(fill no)
			(layer "F.Fab")
		)
		(pad "1" smd custom
			(at 0 -0.4318)
			(size 0.127 0.127)
			(layers "F.Cu" "F.Mask" "F.Paste")
			(net "P3V3_STBY")
			(options
				(clearance outline)
				(anchor circle)
			)
			(primitives
				(gr_poly
					(pts
						(arc
							(start -0.2032 -0.2794)
							(mid -0.239121 -0.264521)
							(end -0.254 -0.2286)
						)
						(arc
							(start -0.254 0.2286)
							(mid -0.239121 0.264521)
							(end -0.2032 0.2794)
						)
						(arc
							(start 0.2032 0.2794)
							(mid 0.239121 0.264521)
							(end 0.254 0.2286)
						)
						(arc
							(start 0.254 -0.2286)
							(mid 0.239121 -0.264521)
							(end 0.2032 -0.2794)
						)
					)
					(width 0)
					(fill yes)
				)
			)
		)
		(pad "2" smd custom
			(at 0 0.4318)
			(size 0.127 0.127)
			(layers "F.Cu" "F.Mask" "F.Paste")
			(net "PCIE_GF_I2C_CLK")
			(options
				(clearance outline)
				(anchor circle)
			)
			(primitives
				(gr_poly
					(pts
						(arc
							(start -0.2032 -0.2794)
							(mid -0.239121 -0.264521)
							(end -0.254 -0.2286)
						)
						(arc
							(start -0.254 0.2286)
							(mid -0.239121 0.264521)
							(end -0.2032 0.2794)
						)
						(arc
							(start 0.2032 0.2794)
							(mid 0.239121 0.264521)
							(end 0.254 0.2286)
						)
						(arc
							(start 0.254 -0.2286)
							(mid 0.239121 -0.264521)
							(end 0.2032 -0.2794)
						)
					)
					(width 0)
					(fill yes)
				)
			)
		)
	)
	(footprint ""
		(layer "F.Cu")
		(at 204.7748 -27.686 90)
		(property "Reference" "TP17"
			(at 0 0 90)
			(layer "F.SilkS")
			(hide yes)
			(effects
				(font
					(size 1.27 1.27)
				)
			)
		)
		(property "Value" "TPAD32-GP"
			(at 0 -3.166364 90)
			(unlocked yes)
			(layer "F.Fab")
			(hide yes)
			(effects
				(font
					(size 1.016 1.016)
					(thickness 0.1524)
				)
			)
		)
		(property "Device Type" "TPAD32"
			(at 0 -4.690618 90)
			(unlocked yes)
			(layer "F.Fab")
			(hide yes)
			(effects
				(font
					(size 1.016 1.016)
					(thickness 0.1524)
				)
			)
		)
		(duplicate_pad_numbers_are_jumpers no)
		(fp_poly
			(pts
				(arc
					(start 0 0.7112)
					(mid 0 -0.7112)
					(end 0 0.7112)
				)
			)
			(stroke
				(width 0)
				(type default)
			)
			(fill no)
			(layer "F.CrtYd")
		)
		(fp_poly
			(pts
				(arc
					(start 0 0.7112)
					(mid 0 -0.7112)
					(end 0 0.7112)
				)
			)
			(stroke
				(width 0)
				(type default)
			)
			(fill no)
			(layer "F.Fab")
		)
		(pad "1" smd circle
			(at 0 0 90)
			(size 0.8128 0.8128)
			(layers "F.Cu" "F.Mask" "F.Paste")
			(net "JTAG_PLD_TDI")
		)
	)
	(footprint ""
		(layer "B.Cu")
		(at 138.303 -24.384 90)
		(property "Reference" "C165"
			(at 0 0 90)
			(layer "B.SilkS")
			(hide yes)
			(effects
				(font
					(size 1.27 1.27)
				)
				(justify mirror)
			)
		)
		(property "Value" "SCD1U10V2KX-5GP"
			(at -1.1811 -2.7051 90)
			(unlocked yes)
			(layer "B.Fab")
			(hide yes)
			(effects
				(font
					(size 1.016 1.016)
					(thickness 0.1524)
				)
				(justify mirror)
			)
		)
		(property "Device Type" "C402H22"
			(at -1.1811 -4.2291 90)
			(unlocked yes)
			(layer "B.Fab")
			(hide yes)
			(effects
				(font
					(size 1.016 1.016)
					(thickness 0.1524)
				)
				(justify mirror)
			)
		)
		(duplicate_pad_numbers_are_jumpers no)
		(fp_rect
			(start 0.381 0.7366)
			(end -0.381 -0.7366)
			(stroke
				(width 0)
				(type default)
			)
			(fill no)
			(layer "B.CrtYd")
		)
		(fp_rect
			(start 0.381 0.7366)
			(end -0.381 -0.7366)
			(stroke
				(width 0)
				(type default)
			)
			(fill no)
			(layer "B.Fab")
		)
		(pad "1" smd custom
			(at 0 -0.4572 270)
			(size 0.1143 0.1143)
			(layers "B.Cu" "B.Mask" "B.Paste")
			(net "P3V3_STBY")
			(options
				(clearance outline)
				(anchor circle)
			)
			(primitives
				(gr_poly
					(pts
						(arc
							(start -0.254 0.1778)
							(mid -0.239121 0.213721)
							(end -0.2032 0.2286)
						)
						(arc
							(start 0.2032 0.2286)
							(mid 0.239121 0.213721)
							(end 0.254 0.1778)
						)
						(arc
							(start 0.254 -0.1778)
							(mid 0.239121 -0.213721)
							(end 0.2032 -0.2286)
						)
						(arc
							(start -0.2032 -0.2286)
							(mid -0.239121 -0.213721)
							(end -0.254 -0.1778)
						)
					)
					(width 0)
					(fill yes)
				)
			)
		)
		(pad "2" smd custom
			(at 0 0.4572 270)
			(size 0.1143 0.1143)
			(layers "B.Cu" "B.Mask" "B.Paste")
			(net "GND")
			(options
				(clearance outline)
				(anchor circle)
			)
			(primitives
				(gr_poly
					(pts
						(arc
							(start -0.254 0.1778)
							(mid -0.239121 0.213721)
							(end -0.2032 0.2286)
						)
						(arc
							(start 0.2032 0.2286)
							(mid 0.239121 0.213721)
							(end 0.254 0.1778)
						)
						(arc
							(start 0.254 -0.1778)
							(mid 0.239121 -0.213721)
							(end 0.2032 -0.2286)
						)
						(arc
							(start -0.2032 -0.2286)
							(mid -0.239121 -0.213721)
							(end -0.254 -0.1778)
						)
					)
					(width 0)
					(fill yes)
				)
			)
		)
	)
	(footprint ""
		(layer "B.Cu")
		(at 101.727 -51.451002 180)
		(property "Reference" "C130"
			(at 0 0 0)
			(layer "B.SilkS")
			(hide yes)
			(effects
				(font
					(size 1.27 1.27)
				)
				(justify mirror)
			)
		)
		(property "Value" "SC1U10V2KX-1GP"
			(at -1.1811 -2.7051 180)
			(unlocked yes)
			(layer "B.Fab")
			(hide yes)
			(effects
				(font
					(size 1.016 1.016)
					(thickness 0.1524)
				)
				(justify mirror)
			)
		)
		(property "Device Type" "C402H22"
			(at -1.1811 -4.2291 180)
			(unlocked yes)
			(layer "B.Fab")
			(hide yes)
			(effects
				(font
					(size 1.016 1.016)
					(thickness 0.1524)
				)
				(justify mirror)
			)
		)
		(duplicate_pad_numbers_are_jumpers no)
		(fp_rect
			(start 0.381 0.7366)
			(end -0.381 -0.7366)
			(stroke
				(width 0)
				(type default)
			)
			(fill no)
			(layer "B.CrtYd")
		)
		(fp_rect
			(start 0.381 0.7366)
			(end -0.381 -0.7366)
			(stroke
				(width 0)
				(type default)
			)
			(fill no)
			(layer "B.Fab")
		)
		(pad "1" smd custom
			(at 0 -0.4572)
			(size 0.1143 0.1143)
			(layers "B.Cu" "B.Mask" "B.Paste")
			(net "PV_VDDR")
			(options
				(clearance outline)
				(anchor circle)
			)
			(primitives
				(gr_poly
					(pts
						(arc
							(start -0.254 0.1778)
							(mid -0.239121 0.213721)
							(end -0.2032 0.2286)
						)
						(arc
							(start 0.2032 0.2286)
							(mid 0.239121 0.213721)
							(end 0.254 0.1778)
						)
						(arc
							(start 0.254 -0.1778)
							(mid 0.239121 -0.213721)
							(end 0.2032 -0.2286)
						)
						(arc
							(start -0.2032 -0.2286)
							(mid -0.239121 -0.213721)
							(end -0.254 -0.1778)
						)
					)
					(width 0)
					(fill yes)
				)
			)
		)
		(pad "2" smd custom
			(at 0 0.4572)
			(size 0.1143 0.1143)
			(layers "B.Cu" "B.Mask" "B.Paste")
			(net "GND")
			(options
				(clearance outline)
				(anchor circle)
			)
			(primitives
				(gr_poly
					(pts
						(arc
							(start -0.254 0.1778)
							(mid -0.239121 0.213721)
							(end -0.2032 0.2286)
						)
						(arc
							(start 0.2032 0.2286)
							(mid 0.239121 0.213721)
							(end 0.254 0.1778)
						)
						(arc
							(start 0.254 -0.1778)
							(mid 0.239121 -0.213721)
							(end 0.2032 -0.2286)
						)
						(arc
							(start -0.2032 -0.2286)
							(mid -0.239121 -0.213721)
							(end -0.254 -0.1778)
						)
					)
					(width 0)
					(fill yes)
				)
			)
		)
	)
	(footprint ""
		(layer "B.Cu")
		(at 144.399 -23.495 90)
		(property "Reference" "C197"
			(at 0 0 90)
			(layer "B.SilkS")
			(hide yes)
			(effects
				(font
					(size 1.27 1.27)
				)
				(justify mirror)
			)
		)
		(property "Value" "SCD1U10V2KX-5GP"
			(at -1.1811 -2.7051 90)
			(unlocked yes)
			(layer "B.Fab")
			(hide yes)
			(effects
				(font
					(size 1.016 1.016)
					(thickness 0.1524)
				)
				(justify mirror)
			)
		)
		(property "Device Type" "C402H22"
			(at -1.1811 -4.2291 90)
			(unlocked yes)
			(layer "B.Fab")
			(hide yes)
			(effects
				(font
					(size 1.016 1.016)
					(thickness 0.1524)
				)
				(justify mirror)
			)
		)
		(duplicate_pad_numbers_are_jumpers no)
		(fp_rect
			(start 0.381 0.7366)
			(end -0.381 -0.7366)
			(stroke
				(width 0)
				(type default)
			)
			(fill no)
			(layer "B.CrtYd")
		)
		(fp_rect
			(start 0.381 0.7366)
			(end -0.381 -0.7366)
			(stroke
				(width 0)
				(type default)
			)
			(fill no)
			(layer "B.Fab")
		)
		(pad "1" smd custom
			(at 0 -0.4572 270)
			(size 0.1143 0.1143)
			(layers "B.Cu" "B.Mask" "B.Paste")
			(net "P3V3_STBY")
			(options
				(clearance outline)
				(anchor circle)
			)
			(primitives
				(gr_poly
					(pts
						(arc
							(start -0.254 0.1778)
							(mid -0.239121 0.213721)
							(end -0.2032 0.2286)
						)
						(arc
							(start 0.2032 0.2286)
							(mid 0.239121 0.213721)
							(end 0.254 0.1778)
						)
						(arc
							(start 0.254 -0.1778)
							(mid 0.239121 -0.213721)
							(end 0.2032 -0.2286)
						)
						(arc
							(start -0.2032 -0.2286)
							(mid -0.239121 -0.213721)
							(end -0.254 -0.1778)
						)
					)
					(width 0)
					(fill yes)
				)
			)
		)
		(pad "2" smd custom
			(at 0 0.4572 270)
			(size 0.1143 0.1143)
			(layers "B.Cu" "B.Mask" "B.Paste")
			(net "GND")
			(options
				(clearance outline)
				(anchor circle)
			)
			(primitives
				(gr_poly
					(pts
						(arc
							(start -0.254 0.1778)
							(mid -0.239121 0.213721)
							(end -0.2032 0.2286)
						)
						(arc
							(start 0.2032 0.2286)
							(mid 0.239121 0.213721)
							(end 0.254 0.1778)
						)
						(arc
							(start 0.254 -0.1778)
							(mid 0.239121 -0.213721)
							(end 0.2032 -0.2286)
						)
						(arc
							(start -0.2032 -0.2286)
							(mid -0.239121 -0.213721)
							(end -0.254 -0.1778)
						)
					)
					(width 0)
					(fill yes)
				)
			)
		)
	)
	(footprint ""
		(layer "B.Cu")
		(at 190.4746 -11.812778 90)
		(property "Reference" "R197"
			(at 0 0 90)
			(layer "B.SilkS")
			(hide yes)
			(effects
				(font
					(size 1.27 1.27)
				)
				(justify mirror)
			)
		)
		(property "Value" "4K7R2F-GP"
			(at -0.064008 -3.993896 90)
			(unlocked yes)
			(layer "B.Fab")
			(hide yes)
			(effects
				(font
					(size 1.016 1.016)
					(thickness 0.1524)
				)
				(justify mirror)
			)
		)
		(property "Device Type" "R402H16"
			(at -0.064008 -5.517896 90)
			(unlocked yes)
			(layer "B.Fab")
			(hide yes)
			(effects
				(font
					(size 1.016 1.016)
					(thickness 0.1524)
				)
				(justify mirror)
			)
		)
		(duplicate_pad_numbers_are_jumpers no)
		(fp_rect
			(start 0.381 0.8382)
			(end -0.381 -0.8382)
			(stroke
				(width 0)
				(type default)
			)
			(fill no)
			(layer "B.CrtYd")
		)
		(fp_rect
			(start 0.381 0.8382)
			(end -0.381 -0.8382)
			(stroke
				(width 0)
				(type default)
			)
			(fill no)
			(layer "B.Fab")
		)
		(pad "1" smd custom
			(at 0 -0.4318 270)
			(size 0.127 0.127)
			(layers "B.Cu" "B.Mask" "B.Paste")
			(net "CHB_0_SA1")
			(options
				(clearance outline)
				(anchor circle)
			)
			(primitives
				(gr_poly
					(pts
						(arc
							(start -0.2032 0.2794)
							(mid -0.239121 0.264521)
							(end -0.254 0.2286)
						)
						(arc
							(start -0.254 -0.2286)
							(mid -0.239121 -0.264521)
							(end -0.2032 -0.2794)
						)
						(arc
							(start 0.2032 -0.2794)
							(mid 0.239121 -0.264521)
							(end 0.254 -0.2286)
						)
						(arc
							(start 0.254 0.2286)
							(mid 0.239121 0.264521)
							(end 0.2032 0.2794)
						)
					)
					(width 0)
					(fill yes)
				)
			)
		)
		(pad "2" smd custom
			(at 0 0.4318 270)
			(size 0.127 0.127)
			(layers "B.Cu" "B.Mask" "B.Paste")
			(net "GND")
			(options
				(clearance outline)
				(anchor circle)
			)
			(primitives
				(gr_poly
					(pts
						(arc
							(start -0.2032 0.2794)
							(mid -0.239121 0.264521)
							(end -0.254 0.2286)
						)
						(arc
							(start -0.254 -0.2286)
							(mid -0.239121 -0.264521)
							(end -0.2032 -0.2794)
						)
						(arc
							(start 0.2032 -0.2794)
							(mid 0.239121 -0.264521)
							(end 0.254 -0.2286)
						)
						(arc
							(start 0.254 0.2286)
							(mid 0.239121 0.264521)
							(end 0.2032 0.2794)
						)
					)
					(width 0)
					(fill yes)
				)
			)
		)
	)
	(footprint ""
		(layer "B.Cu")
		(at 109.982 -43.18 -90)
		(property "Reference" "C193"
			(at 0 0 90)
			(layer "B.SilkS")
			(hide yes)
			(effects
				(font
					(size 1.27 1.27)
				)
				(justify mirror)
			)
		)
		(property "Value" "SC1U10V2KX-1GP"
			(at -1.1811 -2.7051 270)
			(unlocked yes)
			(layer "B.Fab")
			(hide yes)
			(effects
				(font
					(size 1.016 1.016)
					(thickness 0.1524)
				)
				(justify mirror)
			)
		)
		(property "Device Type" "C402H22"
			(at -1.1811 -4.2291 270)
			(unlocked yes)
			(layer "B.Fab")
			(hide yes)
			(effects
				(font
					(size 1.016 1.016)
					(thickness 0.1524)
				)
				(justify mirror)
			)
		)
		(duplicate_pad_numbers_are_jumpers no)
		(fp_rect
			(start 0.381 0.7366)
			(end -0.381 -0.7366)
			(stroke
				(width 0)
				(type default)
			)
			(fill no)
			(layer "B.CrtYd")
		)
		(fp_rect
			(start 0.381 0.7366)
			(end -0.381 -0.7366)
			(stroke
				(width 0)
				(type default)
			)
			(fill no)
			(layer "B.Fab")
		)
		(pad "1" smd custom
			(at 0 -0.4572 90)
			(size 0.1143 0.1143)
			(layers "B.Cu" "B.Mask" "B.Paste")
			(net "PVCCP")
			(options
				(clearance outline)
				(anchor circle)
			)
			(primitives
				(gr_poly
					(pts
						(arc
							(start -0.254 0.1778)
							(mid -0.239121 0.213721)
							(end -0.2032 0.2286)
						)
						(arc
							(start 0.2032 0.2286)
							(mid 0.239121 0.213721)
							(end 0.254 0.1778)
						)
						(arc
							(start 0.254 -0.1778)
							(mid 0.239121 -0.213721)
							(end 0.2032 -0.2286)
						)
						(arc
							(start -0.2032 -0.2286)
							(mid -0.239121 -0.213721)
							(end -0.254 -0.1778)
						)
					)
					(width 0)
					(fill yes)
				)
			)
		)
		(pad "2" smd custom
			(at 0 0.4572 90)
			(size 0.1143 0.1143)
			(layers "B.Cu" "B.Mask" "B.Paste")
			(net "GND")
			(options
				(clearance outline)
				(anchor circle)
			)
			(primitives
				(gr_poly
					(pts
						(arc
							(start -0.254 0.1778)
							(mid -0.239121 0.213721)
							(end -0.2032 0.2286)
						)
						(arc
							(start 0.2032 0.2286)
							(mid 0.239121 0.213721)
							(end 0.254 0.1778)
						)
						(arc
							(start 0.254 -0.1778)
							(mid 0.239121 -0.213721)
							(end 0.2032 -0.2286)
						)
						(arc
							(start -0.2032 -0.2286)
							(mid -0.239121 -0.213721)
							(end -0.254 -0.1778)
						)
					)
					(width 0)
					(fill yes)
				)
			)
		)
	)
	(footprint ""
		(layer "B.Cu")
		(at 67.183 -28.321 -90)
		(property "Reference" "C45"
			(at 0 0 90)
			(layer "B.SilkS")
			(hide yes)
			(effects
				(font
					(size 1.27 1.27)
				)
				(justify mirror)
			)
		)
		(property "Value" "SCD01U16V2KX-3GP"
			(at -1.1811 -2.7051 270)
			(unlocked yes)
			(layer "B.Fab")
			(hide yes)
			(effects
				(font
					(size 1.016 1.016)
					(thickness 0.1524)
				)
				(justify mirror)
			)
		)
		(property "Device Type" "C402H22"
			(at -1.1811 -4.2291 270)
			(unlocked yes)
			(layer "B.Fab")
			(hide yes)
			(effects
				(font
					(size 1.016 1.016)
					(thickness 0.1524)
				)
				(justify mirror)
			)
		)
		(duplicate_pad_numbers_are_jumpers no)
		(fp_rect
			(start 0.381 0.7366)
			(end -0.381 -0.7366)
			(stroke
				(width 0)
				(type default)
			)
			(fill no)
			(layer "B.CrtYd")
		)
		(fp_rect
			(start 0.381 0.7366)
			(end -0.381 -0.7366)
			(stroke
				(width 0)
				(type default)
			)
			(fill no)
			(layer "B.Fab")
		)
		(pad "1" smd custom
			(at 0 -0.4572 90)
			(size 0.1143 0.1143)
			(layers "B.Cu" "B.Mask" "B.Paste")
			(net "SATA3_TX_DN0")
			(options
				(clearance outline)
				(anchor circle)
			)
			(primitives
				(gr_poly
					(pts
						(arc
							(start -0.254 0.1778)
							(mid -0.239121 0.213721)
							(end -0.2032 0.2286)
						)
						(arc
							(start 0.2032 0.2286)
							(mid 0.239121 0.213721)
							(end 0.254 0.1778)
						)
						(arc
							(start 0.254 -0.1778)
							(mid 0.239121 -0.213721)
							(end 0.2032 -0.2286)
						)
						(arc
							(start -0.2032 -0.2286)
							(mid -0.239121 -0.213721)
							(end -0.254 -0.1778)
						)
					)
					(width 0)
					(fill yes)
				)
			)
		)
		(pad "2" smd custom
			(at 0 0.4572 90)
			(size 0.1143 0.1143)
			(layers "B.Cu" "B.Mask" "B.Paste")
			(net "SATA3_TX_C_DN0")
			(options
				(clearance outline)
				(anchor circle)
			)
			(primitives
				(gr_poly
					(pts
						(arc
							(start -0.254 0.1778)
							(mid -0.239121 0.213721)
							(end -0.2032 0.2286)
						)
						(arc
							(start 0.2032 0.2286)
							(mid 0.239121 0.213721)
							(end 0.254 0.1778)
						)
						(arc
							(start 0.254 -0.1778)
							(mid 0.239121 -0.213721)
							(end 0.2032 -0.2286)
						)
						(arc
							(start -0.2032 -0.2286)
							(mid -0.239121 -0.213721)
							(end -0.254 -0.1778)
						)
					)
					(width 0)
					(fill yes)
				)
			)
		)
	)
	(footprint ""
		(layer "B.Cu")
		(at 161.163 -59.309)
		(property "Reference" "C361"
			(at 0 0 0)
			(layer "B.SilkS")
			(hide yes)
			(effects
				(font
					(size 1.27 1.27)
				)
				(justify mirror)
			)
		)
		(property "Value" "SC47U6D3V5MX-1-GP"
			(at 0 -4.9022 0)
			(unlocked yes)
			(layer "B.Fab")
			(hide yes)
			(effects
				(font
					(size 1.016 1.016)
					(thickness 0.1524)
				)
				(justify mirror)
			)
		)
		(property "Device Type" "C805H54"
			(at 0 -6.8072 0)
			(unlocked yes)
			(layer "B.Fab")
			(hide yes)
			(effects
				(font
					(size 1.016 1.016)
					(thickness 0.1524)
				)
				(justify mirror)
			)
		)
		(duplicate_pad_numbers_are_jumpers no)
		(fp_line
			(start -0.6096 0)
			(end 0.6096 0)
			(stroke
				(width 0.3048)
				(type default)
			)
			(layer "B.SilkS")
		)
		(fp_poly
			(pts
				(xy 0.9017 1.4351) (xy -0.9017 1.4351) (xy -0.9017 -1.4351) (xy 0.9017 -1.4351)
			)
			(stroke
				(width 0)
				(type default)
			)
			(fill no)
			(layer "B.CrtYd")
		)
		(fp_poly
			(pts
				(xy -0.9017 1.4351) (xy -0.9017 -1.4351) (xy 0.9017 -1.4351) (xy 0.9017 1.4351)
			)
			(stroke
				(width 0)
				(type default)
			)
			(fill no)
			(layer "B.Fab")
		)
		(pad "1" smd rect
			(at 0 -0.8382 180)
			(size 1.5494 0.9398)
			(layers "B.Cu" "B.Mask" "B.Paste")
			(net "PV_VDDR")
		)
		(pad "2" smd rect
			(at 0 0.8382 180)
			(size 1.5494 0.9398)
			(layers "B.Cu" "B.Mask" "B.Paste")
			(net "GND")
		)
	)
	(footprint ""
		(layer "B.Cu")
		(at 163.9062 -13.235178 180)
		(property "Reference" "C293"
			(at 0 0 0)
			(layer "B.SilkS")
			(hide yes)
			(effects
				(font
					(size 1.27 1.27)
				)
				(justify mirror)
			)
		)
		(property "Value" "SC10U6D3V3MX-GP"
			(at 0.0254 -2.0193 180)
			(unlocked yes)
			(layer "B.Fab")
			(hide yes)
			(effects
				(font
					(size 1.016 1.016)
					(thickness 0.1524)
				)
				(justify mirror)
			)
		)
		(property "Device Type" "C603H38"
			(at 0.0254 -3.5433 180)
			(unlocked yes)
			(layer "B.Fab")
			(hide yes)
			(effects
				(font
					(size 1.016 1.016)
					(thickness 0.1524)
				)
				(justify mirror)
			)
		)
		(duplicate_pad_numbers_are_jumpers no)
		(fp_line
			(start 0.4064 0)
			(end -0.4064 0)
			(stroke
				(width 0.2286)
				(type default)
			)
			(layer "B.SilkS")
		)
		(fp_rect
			(start 0.635 1.1811)
			(end -0.635 -1.1811)
			(stroke
				(width 0)
				(type default)
			)
			(fill no)
			(layer "B.CrtYd")
		)
		(fp_rect
			(start 0.635 1.1811)
			(end -0.635 -1.1811)
			(stroke
				(width 0)
				(type default)
			)
			(fill no)
			(layer "B.Fab")
		)
		(pad "1" smd custom
			(at 0 -0.6604)
			(size 0.19685 0.19685)
			(layers "B.Cu" "B.Mask" "B.Paste")
			(net "PV_VDDR")
			(options
				(clearance outline)
				(anchor circle)
			)
			(primitives
				(gr_poly
					(pts
						(arc
							(start 0.508 0.2921)
							(mid 0.478242 0.363942)
							(end 0.4064 0.3937)
						)
						(arc
							(start -0.4064 0.3937)
							(mid -0.478242 0.363942)
							(end -0.508 0.2921)
						)
						(arc
							(start -0.508 -0.2921)
							(mid -0.478242 -0.363942)
							(end -0.4064 -0.3937)
						)
						(arc
							(start 0.4064 -0.3937)
							(mid 0.478242 -0.363942)
							(end 0.508 -0.2921)
						)
					)
					(width 0)
					(fill yes)
				)
			)
		)
		(pad "2" smd custom
			(at 0 0.6604)
			(size 0.19685 0.19685)
			(layers "B.Cu" "B.Mask" "B.Paste")
			(net "GND")
			(options
				(clearance outline)
				(anchor circle)
			)
			(primitives
				(gr_poly
					(pts
						(arc
							(start 0.508 0.2921)
							(mid 0.478242 0.363942)
							(end 0.4064 0.3937)
						)
						(arc
							(start -0.4064 0.3937)
							(mid -0.478242 0.363942)
							(end -0.508 0.2921)
						)
						(arc
							(start -0.508 -0.2921)
							(mid -0.478242 -0.363942)
							(end -0.4064 -0.3937)
						)
						(arc
							(start 0.4064 -0.3937)
							(mid 0.478242 -0.363942)
							(end 0.508 -0.2921)
						)
					)
					(width 0)
					(fill yes)
				)
			)
		)
	)
	(footprint ""
		(layer "B.Cu")
		(at 197.485 -32.004 -90)
		(property "Reference" "R150"
			(at 0 0 90)
			(layer "B.SilkS")
			(hide yes)
			(effects
				(font
					(size 1.27 1.27)
				)
				(justify mirror)
			)
		)
		(property "Value" "300R2F-GP"
			(at -1.7907 -1.1176 270)
			(unlocked yes)
			(layer "B.Fab")
			(hide yes)
			(effects
				(font
					(size 1.016 1.016)
					(thickness 0.1524)
				)
				(justify mirror)
			)
		)
		(property "Device Type" "R402H16"
			(at -1.7907 -2.6416 270)
			(unlocked yes)
			(layer "B.Fab")
			(hide yes)
			(effects
				(font
					(size 1.016 1.016)
					(thickness 0.1524)
				)
				(justify mirror)
			)
		)
		(duplicate_pad_numbers_are_jumpers no)
		(fp_rect
			(start 0.381 0.8382)
			(end -0.381 -0.8382)
			(stroke
				(width 0)
				(type default)
			)
			(fill no)
			(layer "B.CrtYd")
		)
		(fp_rect
			(start 0.381 0.8382)
			(end -0.381 -0.8382)
			(stroke
				(width 0)
				(type default)
			)
			(fill no)
			(layer "B.Fab")
		)
		(pad "1" smd custom
			(at 0 -0.4318 90)
			(size 0.127 0.127)
			(layers "B.Cu" "B.Mask" "B.Paste")
			(net "PORT80_R_BIT1")
			(options
				(clearance outline)
				(anchor circle)
			)
			(primitives
				(gr_poly
					(pts
						(arc
							(start -0.2032 0.2794)
							(mid -0.239121 0.264521)
							(end -0.254 0.2286)
						)
						(arc
							(start -0.254 -0.2286)
							(mid -0.239121 -0.264521)
							(end -0.2032 -0.2794)
						)
						(arc
							(start 0.2032 -0.2794)
							(mid 0.239121 -0.264521)
							(end 0.254 -0.2286)
						)
						(arc
							(start 0.254 0.2286)
							(mid 0.239121 0.264521)
							(end 0.2032 0.2794)
						)
					)
					(width 0)
					(fill yes)
				)
			)
		)
		(pad "2" smd custom
			(at 0 0.4318 90)
			(size 0.127 0.127)
			(layers "B.Cu" "B.Mask" "B.Paste")
			(net "P3V3_STBY")
			(options
				(clearance outline)
				(anchor circle)
			)
			(primitives
				(gr_poly
					(pts
						(arc
							(start -0.2032 0.2794)
							(mid -0.239121 0.264521)
							(end -0.254 0.2286)
						)
						(arc
							(start -0.254 -0.2286)
							(mid -0.239121 -0.264521)
							(end -0.2032 -0.2794)
						)
						(arc
							(start 0.2032 -0.2794)
							(mid 0.239121 -0.264521)
							(end 0.254 -0.2286)
						)
						(arc
							(start 0.254 0.2286)
							(mid 0.239121 0.264521)
							(end 0.2032 0.2794)
						)
					)
					(width 0)
					(fill yes)
				)
			)
		)
	)
	(footprint ""
		(layer "B.Cu")
		(at 157.6832 -59.6646)
		(property "Reference" "C330"
			(at 0 0 0)
			(layer "B.SilkS")
			(hide yes)
			(effects
				(font
					(size 1.27 1.27)
				)
				(justify mirror)
			)
		)
		(property "Value" "SCD1U16V2KX-3GP"
			(at -1.8923 -1.2065 0)
			(unlocked yes)
			(layer "B.Fab")
			(hide yes)
			(effects
				(font
					(size 1.016 1.016)
					(thickness 0.1524)
				)
				(justify mirror)
			)
		)
		(property "Device Type" "C402H22"
			(at -1.8923 -2.7305 0)
			(unlocked yes)
			(layer "B.Fab")
			(hide yes)
			(effects
				(font
					(size 1.016 1.016)
					(thickness 0.1524)
				)
				(justify mirror)
			)
		)
		(duplicate_pad_numbers_are_jumpers no)
		(fp_rect
			(start 0.381 0.7366)
			(end -0.381 -0.7366)
			(stroke
				(width 0)
				(type default)
			)
			(fill no)
			(layer "B.CrtYd")
		)
		(fp_rect
			(start 0.381 0.7366)
			(end -0.381 -0.7366)
			(stroke
				(width 0)
				(type default)
			)
			(fill no)
			(layer "B.Fab")
		)
		(pad "1" smd custom
			(at 0 -0.4572 180)
			(size 0.1143 0.1143)
			(layers "B.Cu" "B.Mask" "B.Paste")
			(net "PV_VDDR")
			(options
				(clearance outline)
				(anchor circle)
			)
			(primitives
				(gr_poly
					(pts
						(arc
							(start -0.254 0.1778)
							(mid -0.239121 0.213721)
							(end -0.2032 0.2286)
						)
						(arc
							(start 0.2032 0.2286)
							(mid 0.239121 0.213721)
							(end 0.254 0.1778)
						)
						(arc
							(start 0.254 -0.1778)
							(mid 0.239121 -0.213721)
							(end 0.2032 -0.2286)
						)
						(arc
							(start -0.2032 -0.2286)
							(mid -0.239121 -0.213721)
							(end -0.254 -0.1778)
						)
					)
					(width 0)
					(fill yes)
				)
			)
		)
		(pad "2" smd custom
			(at 0 0.4572 180)
			(size 0.1143 0.1143)
			(layers "B.Cu" "B.Mask" "B.Paste")
			(net "GND")
			(options
				(clearance outline)
				(anchor circle)
			)
			(primitives
				(gr_poly
					(pts
						(arc
							(start -0.254 0.1778)
							(mid -0.239121 0.213721)
							(end -0.2032 0.2286)
						)
						(arc
							(start 0.2032 0.2286)
							(mid 0.239121 0.213721)
							(end 0.254 0.1778)
						)
						(arc
							(start 0.254 -0.1778)
							(mid 0.239121 -0.213721)
							(end 0.2032 -0.2286)
						)
						(arc
							(start -0.2032 -0.2286)
							(mid -0.239121 -0.213721)
							(end -0.254 -0.1778)
						)
					)
					(width 0)
					(fill yes)
				)
			)
		)
	)
	(footprint ""
		(layer "B.Cu")
		(at 80.518 -35.4584 -90)
		(property "Reference" "TP36"
			(at 0 0 90)
			(layer "B.SilkS")
			(hide yes)
			(effects
				(font
					(size 1.27 1.27)
				)
				(justify mirror)
			)
		)
		(property "Value" "TPAD24"
			(at 0 -2.9972 270)
			(unlocked yes)
			(layer "B.Fab")
			(hide yes)
			(effects
				(font
					(size 1.016 1.016)
					(thickness 0.1524)
				)
				(justify mirror)
			)
		)
		(property "Device Type" "TPAD24"
			(at 0 -4.5212 270)
			(unlocked yes)
			(layer "B.Fab")
			(hide yes)
			(effects
				(font
					(size 1.016 1.016)
					(thickness 0.1524)
				)
				(justify mirror)
			)
		)
		(duplicate_pad_numbers_are_jumpers no)
		(fp_poly
			(pts
				(arc
					(start 0 -0.3048)
					(mid 0 0.3048)
					(end 0 -0.3048)
				)
			)
			(stroke
				(width 0)
				(type default)
			)
			(fill no)
			(layer "B.CrtYd")
		)
		(fp_poly
			(pts
				(arc
					(start 0 -0.6096)
					(mid 0 0.6096)
					(end 0 -0.6096)
				)
			)
			(stroke
				(width 0)
				(type default)
			)
			(fill no)
			(layer "B.Fab")
		)
		(pad "1" smd circle
			(at 0 0 90)
			(size 0.6096 0.6096)
			(layers "B.Cu" "B.Mask" "B.Paste")
			(net "TP_CPU_RSVD13")
		)
	)
	(footprint ""
		(layer "B.Cu")
		(at 67.0306 -37.1602 90)
		(property "Reference" "PR128"
			(at 0 0 90)
			(layer "B.SilkS")
			(hide yes)
			(effects
				(font
					(size 1.27 1.27)
				)
				(justify mirror)
			)
		)
		(property "Value" "0R2J-2-GP"
			(at -0.064008 -3.993896 90)
			(unlocked yes)
			(layer "B.Fab")
			(hide yes)
			(effects
				(font
					(size 1.016 1.016)
					(thickness 0.1524)
				)
				(justify mirror)
			)
		)
		(property "Device Type" "R402H16"
			(at -0.064008 -5.517896 90)
			(unlocked yes)
			(layer "B.Fab")
			(hide yes)
			(effects
				(font
					(size 1.016 1.016)
					(thickness 0.1524)
				)
				(justify mirror)
			)
		)
		(duplicate_pad_numbers_are_jumpers no)
		(fp_rect
			(start 0.381 0.8382)
			(end -0.381 -0.8382)
			(stroke
				(width 0)
				(type default)
			)
			(fill no)
			(layer "B.CrtYd")
		)
		(fp_rect
			(start 0.381 0.8382)
			(end -0.381 -0.8382)
			(stroke
				(width 0)
				(type default)
			)
			(fill no)
			(layer "B.Fab")
		)
		(pad "1" smd custom
			(at 0 -0.4318 270)
			(size 0.127 0.127)
			(layers "B.Cu" "B.Mask" "B.Paste")
			(net "PMU_SLP_DDRVTT#")
			(options
				(clearance outline)
				(anchor circle)
			)
			(primitives
				(gr_poly
					(pts
						(arc
							(start -0.2032 0.2794)
							(mid -0.239121 0.264521)
							(end -0.254 0.2286)
						)
						(arc
							(start -0.254 -0.2286)
							(mid -0.239121 -0.264521)
							(end -0.2032 -0.2794)
						)
						(arc
							(start 0.2032 -0.2794)
							(mid 0.239121 -0.264521)
							(end 0.254 -0.2286)
						)
						(arc
							(start 0.254 0.2286)
							(mid 0.239121 0.264521)
							(end 0.2032 0.2794)
						)
					)
					(width 0)
					(fill yes)
				)
			)
		)
		(pad "2" smd custom
			(at 0 0.4318 270)
			(size 0.127 0.127)
			(layers "B.Cu" "B.Mask" "B.Paste")
			(net "PMU_SLP_INA_DDRVTT#")
			(options
				(clearance outline)
				(anchor circle)
			)
			(primitives
				(gr_poly
					(pts
						(arc
							(start -0.2032 0.2794)
							(mid -0.239121 0.264521)
							(end -0.254 0.2286)
						)
						(arc
							(start -0.254 -0.2286)
							(mid -0.239121 -0.264521)
							(end -0.2032 -0.2794)
						)
						(arc
							(start 0.2032 -0.2794)
							(mid 0.239121 -0.264521)
							(end 0.254 -0.2286)
						)
						(arc
							(start 0.254 0.2286)
							(mid 0.239121 0.264521)
							(end 0.2032 0.2794)
						)
					)
					(width 0)
					(fill yes)
				)
			)
		)
	)
	(footprint ""
		(layer "B.Cu")
		(at 31.369 -42.545 180)
		(property "Reference" "PR187"
			(at 0 0 0)
			(layer "B.SilkS")
			(hide yes)
			(effects
				(font
					(size 1.27 1.27)
				)
				(justify mirror)
			)
		)
		(property "Value" "0R3J-6-GP"
			(at 0.0254 -2.0193 180)
			(unlocked yes)
			(layer "B.Fab")
			(hide yes)
			(effects
				(font
					(size 1.016 1.016)
					(thickness 0.1524)
				)
				(justify mirror)
			)
		)
		(property "Device Type" "R603H22"
			(at 0.0254 -3.5433 180)
			(unlocked yes)
			(layer "B.Fab")
			(hide yes)
			(effects
				(font
					(size 1.016 1.016)
					(thickness 0.1524)
				)
				(justify mirror)
			)
		)
		(duplicate_pad_numbers_are_jumpers no)
		(fp_line
			(start 0.2032 0)
			(end 0.4191 0)
			(stroke
				(width 0.2032)
				(type default)
			)
			(layer "B.SilkS")
		)
		(fp_line
			(start -0.4318 0)
			(end -0.2032 0)
			(stroke
				(width 0.2032)
				(type default)
			)
			(layer "B.SilkS")
		)
		(fp_rect
			(start 0.635 1.1811)
			(end -0.635 -1.1811)
			(stroke
				(width 0)
				(type default)
			)
			(fill no)
			(layer "B.CrtYd")
		)
		(fp_rect
			(start 0.635 1.1811)
			(end -0.635 -1.1811)
			(stroke
				(width 0)
				(type default)
			)
			(fill no)
			(layer "B.Fab")
		)
		(pad "1" smd custom
			(at 0 -0.6604)
			(size 0.19685 0.19685)
			(layers "B.Cu" "B.Mask" "B.Paste")
			(net "P1V5_STBY")
			(options
				(clearance outline)
				(anchor circle)
			)
			(primitives
				(gr_poly
					(pts
						(arc
							(start 0.508 0.2921)
							(mid 0.478242 0.363942)
							(end 0.4064 0.3937)
						)
						(arc
							(start -0.4064 0.3937)
							(mid -0.478242 0.363942)
							(end -0.508 0.2921)
						)
						(arc
							(start -0.508 -0.2921)
							(mid -0.478242 -0.363942)
							(end -0.4064 -0.3937)
						)
						(arc
							(start 0.4064 -0.3937)
							(mid 0.478242 -0.363942)
							(end 0.508 -0.2921)
						)
					)
					(width 0)
					(fill yes)
				)
			)
		)
		(pad "2" smd custom
			(at 0 0.6604)
			(size 0.19685 0.19685)
			(layers "B.Cu" "B.Mask" "B.Paste")
			(net "P1V5_STBY_OUT")
			(options
				(clearance outline)
				(anchor circle)
			)
			(primitives
				(gr_poly
					(pts
						(arc
							(start 0.508 0.2921)
							(mid 0.478242 0.363942)
							(end 0.4064 0.3937)
						)
						(arc
							(start -0.4064 0.3937)
							(mid -0.478242 0.363942)
							(end -0.508 0.2921)
						)
						(arc
							(start -0.508 -0.2921)
							(mid -0.478242 -0.363942)
							(end -0.4064 -0.3937)
						)
						(arc
							(start 0.4064 -0.3937)
							(mid 0.478242 -0.363942)
							(end 0.508 -0.2921)
						)
					)
					(width 0)
					(fill yes)
				)
			)
		)
	)
	(footprint ""
		(layer "B.Cu")
		(at 40.894 -51.943 180)
		(property "Reference" "C62"
			(at 0 0 0)
			(layer "B.SilkS")
			(hide yes)
			(effects
				(font
					(size 1.27 1.27)
				)
				(justify mirror)
			)
		)
		(property "Value" "SCD1U10V2KX-5GP"
			(at -1.8923 -1.2065 180)
			(unlocked yes)
			(layer "B.Fab")
			(hide yes)
			(effects
				(font
					(size 1.016 1.016)
					(thickness 0.1524)
				)
				(justify mirror)
			)
		)
		(property "Device Type" "C402H22"
			(at -1.8923 -2.7305 180)
			(unlocked yes)
			(layer "B.Fab")
			(hide yes)
			(effects
				(font
					(size 1.016 1.016)
					(thickness 0.1524)
				)
				(justify mirror)
			)
		)
		(duplicate_pad_numbers_are_jumpers no)
		(fp_rect
			(start 0.381 0.7366)
			(end -0.381 -0.7366)
			(stroke
				(width 0)
				(type default)
			)
			(fill no)
			(layer "B.CrtYd")
		)
		(fp_rect
			(start 0.381 0.7366)
			(end -0.381 -0.7366)
			(stroke
				(width 0)
				(type default)
			)
			(fill no)
			(layer "B.Fab")
		)
		(pad "1" smd custom
			(at 0 -0.4572)
			(size 0.1143 0.1143)
			(layers "B.Cu" "B.Mask" "B.Paste")
			(net "P3V3_CLK_PCI")
			(options
				(clearance outline)
				(anchor circle)
			)
			(primitives
				(gr_poly
					(pts
						(arc
							(start -0.254 0.1778)
							(mid -0.239121 0.213721)
							(end -0.2032 0.2286)
						)
						(arc
							(start 0.2032 0.2286)
							(mid 0.239121 0.213721)
							(end 0.254 0.1778)
						)
						(arc
							(start 0.254 -0.1778)
							(mid 0.239121 -0.213721)
							(end 0.2032 -0.2286)
						)
						(arc
							(start -0.2032 -0.2286)
							(mid -0.239121 -0.213721)
							(end -0.254 -0.1778)
						)
					)
					(width 0)
					(fill yes)
				)
			)
		)
		(pad "2" smd custom
			(at 0 0.4572)
			(size 0.1143 0.1143)
			(layers "B.Cu" "B.Mask" "B.Paste")
			(net "GND")
			(options
				(clearance outline)
				(anchor circle)
			)
			(primitives
				(gr_poly
					(pts
						(arc
							(start -0.254 0.1778)
							(mid -0.239121 0.213721)
							(end -0.2032 0.2286)
						)
						(arc
							(start 0.2032 0.2286)
							(mid 0.239121 0.213721)
							(end 0.254 0.1778)
						)
						(arc
							(start 0.254 -0.1778)
							(mid 0.239121 -0.213721)
							(end 0.2032 -0.2286)
						)
						(arc
							(start -0.2032 -0.2286)
							(mid -0.239121 -0.213721)
							(end -0.254 -0.1778)
						)
					)
					(width 0)
					(fill yes)
				)
			)
		)
	)
	(footprint ""
		(layer "B.Cu")
		(at 39.878 -65.278 90)
		(property "Reference" "PR11"
			(at 0 0 90)
			(layer "B.SilkS")
			(hide yes)
			(effects
				(font
					(size 1.27 1.27)
				)
				(justify mirror)
			)
		)
		(property "Value" "0R2J-2-GP"
			(at -1.7907 -1.1176 90)
			(unlocked yes)
			(layer "B.Fab")
			(hide yes)
			(effects
				(font
					(size 1.016 1.016)
					(thickness 0.1524)
				)
				(justify mirror)
			)
		)
		(property "Device Type" "R402H16"
			(at -1.7907 -2.6416 90)
			(unlocked yes)
			(layer "B.Fab")
			(hide yes)
			(effects
				(font
					(size 1.016 1.016)
					(thickness 0.1524)
				)
				(justify mirror)
			)
		)
		(duplicate_pad_numbers_are_jumpers no)
		(fp_rect
			(start 0.381 0.8382)
			(end -0.381 -0.8382)
			(stroke
				(width 0)
				(type default)
			)
			(fill no)
			(layer "B.CrtYd")
		)
		(fp_rect
			(start 0.381 0.8382)
			(end -0.381 -0.8382)
			(stroke
				(width 0)
				(type default)
			)
			(fill no)
			(layer "B.Fab")
		)
		(pad "1" smd custom
			(at 0 -0.4318 270)
			(size 0.127 0.127)
			(layers "B.Cu" "B.Mask" "B.Paste")
			(net "VR_PVNN_PHASE")
			(options
				(clearance outline)
				(anchor circle)
			)
			(primitives
				(gr_poly
					(pts
						(arc
							(start -0.2032 0.2794)
							(mid -0.239121 0.264521)
							(end -0.254 0.2286)
						)
						(arc
							(start -0.254 -0.2286)
							(mid -0.239121 -0.264521)
							(end -0.2032 -0.2794)
						)
						(arc
							(start 0.2032 -0.2794)
							(mid 0.239121 -0.264521)
							(end 0.254 -0.2286)
						)
						(arc
							(start 0.254 0.2286)
							(mid 0.239121 0.264521)
							(end 0.2032 0.2794)
						)
					)
					(width 0)
					(fill yes)
				)
			)
		)
		(pad "2" smd custom
			(at 0 0.4318 270)
			(size 0.127 0.127)
			(layers "B.Cu" "B.Mask" "B.Paste")
			(net "VR_PVNN_ISUMP_R2")
			(options
				(clearance outline)
				(anchor circle)
			)
			(primitives
				(gr_poly
					(pts
						(arc
							(start -0.2032 0.2794)
							(mid -0.239121 0.264521)
							(end -0.254 0.2286)
						)
						(arc
							(start -0.254 -0.2286)
							(mid -0.239121 -0.264521)
							(end -0.2032 -0.2794)
						)
						(arc
							(start 0.2032 -0.2794)
							(mid 0.239121 -0.264521)
							(end 0.254 -0.2286)
						)
						(arc
							(start 0.254 0.2286)
							(mid 0.239121 0.264521)
							(end 0.2032 0.2794)
						)
					)
					(width 0)
					(fill yes)
				)
			)
		)
	)
	(footprint ""
		(layer "B.Cu")
		(at 110.109 -5.715 180)
		(property "Reference" "R468"
			(at 0 0 0)
			(layer "B.SilkS")
			(hide yes)
			(effects
				(font
					(size 1.27 1.27)
				)
				(justify mirror)
			)
		)
		(property "Value" "8K2R2F-1-GP"
			(at -1.7907 -1.1176 180)
			(unlocked yes)
			(layer "B.Fab")
			(hide yes)
			(effects
				(font
					(size 1.016 1.016)
					(thickness 0.1524)
				)
				(justify mirror)
			)
		)
		(property "Device Type" "R402H16"
			(at -1.7907 -2.6416 180)
			(unlocked yes)
			(layer "B.Fab")
			(hide yes)
			(effects
				(font
					(size 1.016 1.016)
					(thickness 0.1524)
				)
				(justify mirror)
			)
		)
		(duplicate_pad_numbers_are_jumpers no)
		(fp_rect
			(start 0.381 0.8382)
			(end -0.381 -0.8382)
			(stroke
				(width 0)
				(type default)
			)
			(fill no)
			(layer "B.CrtYd")
		)
		(fp_rect
			(start 0.381 0.8382)
			(end -0.381 -0.8382)
			(stroke
				(width 0)
				(type default)
			)
			(fill no)
			(layer "B.Fab")
		)
		(pad "1" smd custom
			(at 0 -0.4318)
			(size 0.127 0.127)
			(layers "B.Cu" "B.Mask" "B.Paste")
			(net "P3V3_STBY")
			(options
				(clearance outline)
				(anchor circle)
			)
			(primitives
				(gr_poly
					(pts
						(arc
							(start -0.2032 0.2794)
							(mid -0.239121 0.264521)
							(end -0.254 0.2286)
						)
						(arc
							(start -0.254 -0.2286)
							(mid -0.239121 -0.264521)
							(end -0.2032 -0.2794)
						)
						(arc
							(start 0.2032 -0.2794)
							(mid 0.239121 -0.264521)
							(end 0.254 -0.2286)
						)
						(arc
							(start 0.254 0.2286)
							(mid 0.239121 0.264521)
							(end 0.2032 0.2794)
						)
					)
					(width 0)
					(fill yes)
				)
			)
		)
		(pad "2" smd custom
			(at 0 0.4318)
			(size 0.127 0.127)
			(layers "B.Cu" "B.Mask" "B.Paste")
			(net "IRQ_LV_MCERR#")
			(options
				(clearance outline)
				(anchor circle)
			)
			(primitives
				(gr_poly
					(pts
						(arc
							(start -0.2032 0.2794)
							(mid -0.239121 0.264521)
							(end -0.254 0.2286)
						)
						(arc
							(start -0.254 -0.2286)
							(mid -0.239121 -0.264521)
							(end -0.2032 -0.2794)
						)
						(arc
							(start 0.2032 -0.2794)
							(mid 0.239121 -0.264521)
							(end 0.254 -0.2286)
						)
						(arc
							(start 0.254 0.2286)
							(mid 0.239121 0.264521)
							(end 0.2032 0.2794)
						)
					)
					(width 0)
					(fill yes)
				)
			)
		)
	)
	(footprint ""
		(layer "B.Cu")
		(at 153.289 -36.068 -90)
		(property "Reference" "C234"
			(at 0 0 90)
			(layer "B.SilkS")
			(hide yes)
			(effects
				(font
					(size 1.27 1.27)
				)
				(justify mirror)
			)
		)
		(property "Value" "SCD1U10V2KX-5GP"
			(at -1.1811 -2.7051 270)
			(unlocked yes)
			(layer "B.Fab")
			(hide yes)
			(effects
				(font
					(size 1.016 1.016)
					(thickness 0.1524)
				)
				(justify mirror)
			)
		)
		(property "Device Type" "C402H22"
			(at -1.1811 -4.2291 270)
			(unlocked yes)
			(layer "B.Fab")
			(hide yes)
			(effects
				(font
					(size 1.016 1.016)
					(thickness 0.1524)
				)
				(justify mirror)
			)
		)
		(duplicate_pad_numbers_are_jumpers no)
		(fp_rect
			(start 0.381 0.7366)
			(end -0.381 -0.7366)
			(stroke
				(width 0)
				(type default)
			)
			(fill no)
			(layer "B.CrtYd")
		)
		(fp_rect
			(start 0.381 0.7366)
			(end -0.381 -0.7366)
			(stroke
				(width 0)
				(type default)
			)
			(fill no)
			(layer "B.Fab")
		)
		(pad "1" smd custom
			(at 0 -0.4572 90)
			(size 0.1143 0.1143)
			(layers "B.Cu" "B.Mask" "B.Paste")
			(net "P3V3_STBY")
			(options
				(clearance outline)
				(anchor circle)
			)
			(primitives
				(gr_poly
					(pts
						(arc
							(start -0.254 0.1778)
							(mid -0.239121 0.213721)
							(end -0.2032 0.2286)
						)
						(arc
							(start 0.2032 0.2286)
							(mid 0.239121 0.213721)
							(end 0.254 0.1778)
						)
						(arc
							(start 0.254 -0.1778)
							(mid 0.239121 -0.213721)
							(end 0.2032 -0.2286)
						)
						(arc
							(start -0.2032 -0.2286)
							(mid -0.239121 -0.213721)
							(end -0.254 -0.1778)
						)
					)
					(width 0)
					(fill yes)
				)
			)
		)
		(pad "2" smd custom
			(at 0 0.4572 90)
			(size 0.1143 0.1143)
			(layers "B.Cu" "B.Mask" "B.Paste")
			(net "GND")
			(options
				(clearance outline)
				(anchor circle)
			)
			(primitives
				(gr_poly
					(pts
						(arc
							(start -0.254 0.1778)
							(mid -0.239121 0.213721)
							(end -0.2032 0.2286)
						)
						(arc
							(start 0.2032 0.2286)
							(mid 0.239121 0.213721)
							(end 0.254 0.1778)
						)
						(arc
							(start 0.254 -0.1778)
							(mid 0.239121 -0.213721)
							(end 0.2032 -0.2286)
						)
						(arc
							(start -0.2032 -0.2286)
							(mid -0.239121 -0.213721)
							(end -0.254 -0.1778)
						)
					)
					(width 0)
					(fill yes)
				)
			)
		)
	)
	(footprint ""
		(layer "B.Cu")
		(at 72.6694 -20.1168)
		(property "Reference" "PC121"
			(at 0 0 0)
			(layer "B.SilkS")
			(hide yes)
			(effects
				(font
					(size 1.27 1.27)
				)
				(justify mirror)
			)
		)
		(property "Value" "SC680P50V2KX-2GP"
			(at -1.8923 -1.2065 0)
			(unlocked yes)
			(layer "B.Fab")
			(hide yes)
			(effects
				(font
					(size 1.016 1.016)
					(thickness 0.1524)
				)
				(justify mirror)
			)
		)
		(property "Device Type" "C402H22"
			(at -1.8923 -2.7305 0)
			(unlocked yes)
			(layer "B.Fab")
			(hide yes)
			(effects
				(font
					(size 1.016 1.016)
					(thickness 0.1524)
				)
				(justify mirror)
			)
		)
		(duplicate_pad_numbers_are_jumpers no)
		(fp_rect
			(start 0.381 0.7366)
			(end -0.381 -0.7366)
			(stroke
				(width 0)
				(type default)
			)
			(fill no)
			(layer "B.CrtYd")
		)
		(fp_rect
			(start 0.381 0.7366)
			(end -0.381 -0.7366)
			(stroke
				(width 0)
				(type default)
			)
			(fill no)
			(layer "B.Fab")
		)
		(pad "1" smd custom
			(at 0 -0.4572 180)
			(size 0.1143 0.1143)
			(layers "B.Cu" "B.Mask" "B.Paste")
			(net "VR_PVIN_P1V8_STBY")
			(options
				(clearance outline)
				(anchor circle)
			)
			(primitives
				(gr_poly
					(pts
						(arc
							(start -0.254 0.1778)
							(mid -0.239121 0.213721)
							(end -0.2032 0.2286)
						)
						(arc
							(start 0.2032 0.2286)
							(mid 0.239121 0.213721)
							(end 0.254 0.1778)
						)
						(arc
							(start 0.254 -0.1778)
							(mid 0.239121 -0.213721)
							(end 0.2032 -0.2286)
						)
						(arc
							(start -0.2032 -0.2286)
							(mid -0.239121 -0.213721)
							(end -0.254 -0.1778)
						)
					)
					(width 0)
					(fill yes)
				)
			)
		)
		(pad "2" smd custom
			(at 0 0.4572 180)
			(size 0.1143 0.1143)
			(layers "B.Cu" "B.Mask" "B.Paste")
			(net "GND")
			(options
				(clearance outline)
				(anchor circle)
			)
			(primitives
				(gr_poly
					(pts
						(arc
							(start -0.254 0.1778)
							(mid -0.239121 0.213721)
							(end -0.2032 0.2286)
						)
						(arc
							(start 0.2032 0.2286)
							(mid 0.239121 0.213721)
							(end 0.254 0.1778)
						)
						(arc
							(start 0.254 -0.1778)
							(mid 0.239121 -0.213721)
							(end 0.2032 -0.2286)
						)
						(arc
							(start -0.2032 -0.2286)
							(mid -0.239121 -0.213721)
							(end -0.254 -0.1778)
						)
					)
					(width 0)
					(fill yes)
				)
			)
		)
	)
	(footprint ""
		(layer "B.Cu")
		(at 36.957 -48.387 90)
		(property "Reference" "L2"
			(at 0 0 90)
			(layer "B.SilkS")
			(hide yes)
			(effects
				(font
					(size 1.27 1.27)
				)
				(justify mirror)
			)
		)
		(property "Value" "BLM18PG330SN1D-GP"
			(at 0.0254 -2.0193 90)
			(unlocked yes)
			(layer "B.Fab")
			(hide yes)
			(effects
				(font
					(size 1.016 1.016)
					(thickness 0.1524)
				)
				(justify mirror)
			)
		)
		(property "Device Type" "L1608-UH38"
			(at 0.0254 -3.5433 90)
			(unlocked yes)
			(layer "B.Fab")
			(hide yes)
			(effects
				(font
					(size 1.016 1.016)
					(thickness 0.1524)
				)
				(justify mirror)
			)
		)
		(duplicate_pad_numbers_are_jumpers no)
		(fp_line
			(start 0.4064 0)
			(end -0.4064 0)
			(stroke
				(width 0.2032)
				(type default)
			)
			(layer "B.SilkS")
		)
		(fp_rect
			(start 0.635 1.1811)
			(end -0.635 -1.1811)
			(stroke
				(width 0)
				(type default)
			)
			(fill no)
			(layer "B.CrtYd")
		)
		(fp_rect
			(start 0.635 1.1811)
			(end -0.635 -1.1811)
			(stroke
				(width 0)
				(type default)
			)
			(fill no)
			(layer "B.Fab")
		)
		(pad "1" smd custom
			(at 0 -0.6604 270)
			(size 0.19685 0.19685)
			(layers "B.Cu" "B.Mask" "B.Paste")
			(net "P3V3_STBY")
			(options
				(clearance outline)
				(anchor circle)
			)
			(primitives
				(gr_poly
					(pts
						(arc
							(start 0.508 0.2921)
							(mid 0.478242 0.363942)
							(end 0.4064 0.3937)
						)
						(arc
							(start -0.4064 0.3937)
							(mid -0.478242 0.363942)
							(end -0.508 0.2921)
						)
						(arc
							(start -0.508 -0.2921)
							(mid -0.478242 -0.363942)
							(end -0.4064 -0.3937)
						)
						(arc
							(start 0.4064 -0.3937)
							(mid 0.478242 -0.363942)
							(end 0.508 -0.2921)
						)
					)
					(width 0)
					(fill yes)
				)
			)
		)
		(pad "2" smd custom
			(at 0 0.6604 270)
			(size 0.19685 0.19685)
			(layers "B.Cu" "B.Mask" "B.Paste")
			(net "P3V3_CLK_XTAL")
			(options
				(clearance outline)
				(anchor circle)
			)
			(primitives
				(gr_poly
					(pts
						(arc
							(start 0.508 0.2921)
							(mid 0.478242 0.363942)
							(end 0.4064 0.3937)
						)
						(arc
							(start -0.4064 0.3937)
							(mid -0.478242 0.363942)
							(end -0.508 0.2921)
						)
						(arc
							(start -0.508 -0.2921)
							(mid -0.478242 -0.363942)
							(end -0.4064 -0.3937)
						)
						(arc
							(start 0.4064 -0.3937)
							(mid 0.478242 -0.363942)
							(end 0.508 -0.2921)
						)
					)
					(width 0)
					(fill yes)
				)
			)
		)
	)
	(footprint ""
		(layer "B.Cu")
		(at 44.6024 -15.5702 90)
		(property "Reference" "R427"
			(at 0 0 90)
			(layer "B.SilkS")
			(hide yes)
			(effects
				(font
					(size 1.27 1.27)
				)
				(justify mirror)
			)
		)
		(property "Value" "43D2R2F-GP"
			(at -1.7907 -1.1176 90)
			(unlocked yes)
			(layer "B.Fab")
			(hide yes)
			(effects
				(font
					(size 1.016 1.016)
					(thickness 0.1524)
				)
				(justify mirror)
			)
		)
		(property "Device Type" "R402H16"
			(at -1.7907 -2.6416 90)
			(unlocked yes)
			(layer "B.Fab")
			(hide yes)
			(effects
				(font
					(size 1.016 1.016)
					(thickness 0.1524)
				)
				(justify mirror)
			)
		)
		(duplicate_pad_numbers_are_jumpers no)
		(fp_rect
			(start 0.381 0.8382)
			(end -0.381 -0.8382)
			(stroke
				(width 0)
				(type default)
			)
			(fill no)
			(layer "B.CrtYd")
		)
		(fp_rect
			(start 0.381 0.8382)
			(end -0.381 -0.8382)
			(stroke
				(width 0)
				(type default)
			)
			(fill no)
			(layer "B.Fab")
		)
		(pad "1" smd custom
			(at 0 -0.4318 270)
			(size 0.127 0.127)
			(layers "B.Cu" "B.Mask" "B.Paste")
			(net "CLK_100M_CLKBUFF_ENET_DP")
			(options
				(clearance outline)
				(anchor circle)
			)
			(primitives
				(gr_poly
					(pts
						(arc
							(start -0.2032 0.2794)
							(mid -0.239121 0.264521)
							(end -0.254 0.2286)
						)
						(arc
							(start -0.254 -0.2286)
							(mid -0.239121 -0.264521)
							(end -0.2032 -0.2794)
						)
						(arc
							(start 0.2032 -0.2794)
							(mid 0.239121 -0.264521)
							(end 0.254 -0.2286)
						)
						(arc
							(start 0.254 0.2286)
							(mid 0.239121 0.264521)
							(end 0.2032 0.2794)
						)
					)
					(width 0)
					(fill yes)
				)
			)
		)
		(pad "2" smd custom
			(at 0 0.4318 270)
			(size 0.127 0.127)
			(layers "B.Cu" "B.Mask" "B.Paste")
			(net "GND")
			(options
				(clearance outline)
				(anchor circle)
			)
			(primitives
				(gr_poly
					(pts
						(arc
							(start -0.2032 0.2794)
							(mid -0.239121 0.264521)
							(end -0.254 0.2286)
						)
						(arc
							(start -0.254 -0.2286)
							(mid -0.239121 -0.264521)
							(end -0.2032 -0.2794)
						)
						(arc
							(start 0.2032 -0.2794)
							(mid 0.239121 -0.264521)
							(end 0.254 -0.2286)
						)
						(arc
							(start 0.254 0.2286)
							(mid 0.239121 0.264521)
							(end 0.2032 0.2794)
						)
					)
					(width 0)
					(fill yes)
				)
			)
		)
	)
	(footprint ""
		(layer "B.Cu")
		(at 176.276 -42.291)
		(property "Reference" "C357"
			(at 0 0 0)
			(layer "B.SilkS")
			(hide yes)
			(effects
				(font
					(size 1.27 1.27)
				)
				(justify mirror)
			)
		)
		(property "Value" "SC1U6D3V3KX-2GP"
			(at 0.0254 -2.0193 0)
			(unlocked yes)
			(layer "B.Fab")
			(hide yes)
			(effects
				(font
					(size 1.016 1.016)
					(thickness 0.1524)
				)
				(justify mirror)
			)
		)
		(property "Device Type" "C603H36"
			(at 0.0254 -3.5433 0)
			(unlocked yes)
			(layer "B.Fab")
			(hide yes)
			(effects
				(font
					(size 1.016 1.016)
					(thickness 0.1524)
				)
				(justify mirror)
			)
		)
		(duplicate_pad_numbers_are_jumpers no)
		(fp_line
			(start 0.4064 0)
			(end -0.4064 0)
			(stroke
				(width 0.2286)
				(type default)
			)
			(layer "B.SilkS")
		)
		(fp_rect
			(start 0.635 1.1811)
			(end -0.635 -1.1811)
			(stroke
				(width 0)
				(type default)
			)
			(fill no)
			(layer "B.CrtYd")
		)
		(fp_rect
			(start 0.635 1.1811)
			(end -0.635 -1.1811)
			(stroke
				(width 0)
				(type default)
			)
			(fill no)
			(layer "B.Fab")
		)
		(pad "1" smd custom
			(at 0 -0.6604 180)
			(size 0.19685 0.19685)
			(layers "B.Cu" "B.Mask" "B.Paste")
			(net "SPI_SW_RST#")
			(options
				(clearance outline)
				(anchor circle)
			)
			(primitives
				(gr_poly
					(pts
						(arc
							(start 0.508 0.2921)
							(mid 0.478242 0.363942)
							(end 0.4064 0.3937)
						)
						(arc
							(start -0.4064 0.3937)
							(mid -0.478242 0.363942)
							(end -0.508 0.2921)
						)
						(arc
							(start -0.508 -0.2921)
							(mid -0.478242 -0.363942)
							(end -0.4064 -0.3937)
						)
						(arc
							(start 0.4064 -0.3937)
							(mid 0.478242 -0.363942)
							(end 0.508 -0.2921)
						)
					)
					(width 0)
					(fill yes)
				)
			)
		)
		(pad "2" smd custom
			(at 0 0.6604 180)
			(size 0.19685 0.19685)
			(layers "B.Cu" "B.Mask" "B.Paste")
			(net "GND")
			(options
				(clearance outline)
				(anchor circle)
			)
			(primitives
				(gr_poly
					(pts
						(arc
							(start 0.508 0.2921)
							(mid 0.478242 0.363942)
							(end 0.4064 0.3937)
						)
						(arc
							(start -0.4064 0.3937)
							(mid -0.478242 0.363942)
							(end -0.508 0.2921)
						)
						(arc
							(start -0.508 -0.2921)
							(mid -0.478242 -0.363942)
							(end -0.4064 -0.3937)
						)
						(arc
							(start 0.4064 -0.3937)
							(mid 0.478242 -0.363942)
							(end 0.508 -0.2921)
						)
					)
					(width 0)
					(fill yes)
				)
			)
		)
	)
	(footprint ""
		(layer "B.Cu")
		(at 97.917 -51.3588 180)
		(property "Reference" "C118"
			(at 0 0 0)
			(layer "B.SilkS")
			(hide yes)
			(effects
				(font
					(size 1.27 1.27)
				)
				(justify mirror)
			)
		)
		(property "Value" "SC1U10V2KX-1GP"
			(at -1.1811 -2.7051 180)
			(unlocked yes)
			(layer "B.Fab")
			(hide yes)
			(effects
				(font
					(size 1.016 1.016)
					(thickness 0.1524)
				)
				(justify mirror)
			)
		)
		(property "Device Type" "C402H22"
			(at -1.1811 -4.2291 180)
			(unlocked yes)
			(layer "B.Fab")
			(hide yes)
			(effects
				(font
					(size 1.016 1.016)
					(thickness 0.1524)
				)
				(justify mirror)
			)
		)
		(duplicate_pad_numbers_are_jumpers no)
		(fp_rect
			(start 0.381 0.7366)
			(end -0.381 -0.7366)
			(stroke
				(width 0)
				(type default)
			)
			(fill no)
			(layer "B.CrtYd")
		)
		(fp_rect
			(start 0.381 0.7366)
			(end -0.381 -0.7366)
			(stroke
				(width 0)
				(type default)
			)
			(fill no)
			(layer "B.Fab")
		)
		(pad "1" smd custom
			(at 0 -0.4572)
			(size 0.1143 0.1143)
			(layers "B.Cu" "B.Mask" "B.Paste")
			(net "VCCCLKDDR0")
			(options
				(clearance outline)
				(anchor circle)
			)
			(primitives
				(gr_poly
					(pts
						(arc
							(start -0.254 0.1778)
							(mid -0.239121 0.213721)
							(end -0.2032 0.2286)
						)
						(arc
							(start 0.2032 0.2286)
							(mid 0.239121 0.213721)
							(end 0.254 0.1778)
						)
						(arc
							(start 0.254 -0.1778)
							(mid 0.239121 -0.213721)
							(end 0.2032 -0.2286)
						)
						(arc
							(start -0.2032 -0.2286)
							(mid -0.239121 -0.213721)
							(end -0.254 -0.1778)
						)
					)
					(width 0)
					(fill yes)
				)
			)
		)
		(pad "2" smd custom
			(at 0 0.4572)
			(size 0.1143 0.1143)
			(layers "B.Cu" "B.Mask" "B.Paste")
			(net "GND")
			(options
				(clearance outline)
				(anchor circle)
			)
			(primitives
				(gr_poly
					(pts
						(arc
							(start -0.254 0.1778)
							(mid -0.239121 0.213721)
							(end -0.2032 0.2286)
						)
						(arc
							(start 0.2032 0.2286)
							(mid 0.239121 0.213721)
							(end 0.254 0.1778)
						)
						(arc
							(start 0.254 -0.1778)
							(mid 0.239121 -0.213721)
							(end 0.2032 -0.2286)
						)
						(arc
							(start -0.2032 -0.2286)
							(mid -0.239121 -0.213721)
							(end -0.254 -0.1778)
						)
					)
					(width 0)
					(fill yes)
				)
			)
		)
	)
	(footprint ""
		(layer "B.Cu")
		(at 197.485 -33.782 -90)
		(property "Reference" "R152"
			(at 0 0 90)
			(layer "B.SilkS")
			(hide yes)
			(effects
				(font
					(size 1.27 1.27)
				)
				(justify mirror)
			)
		)
		(property "Value" "300R2F-GP"
			(at -1.7907 -1.1176 270)
			(unlocked yes)
			(layer "B.Fab")
			(hide yes)
			(effects
				(font
					(size 1.016 1.016)
					(thickness 0.1524)
				)
				(justify mirror)
			)
		)
		(property "Device Type" "R402H16"
			(at -1.7907 -2.6416 270)
			(unlocked yes)
			(layer "B.Fab")
			(hide yes)
			(effects
				(font
					(size 1.016 1.016)
					(thickness 0.1524)
				)
				(justify mirror)
			)
		)
		(duplicate_pad_numbers_are_jumpers no)
		(fp_rect
			(start 0.381 0.8382)
			(end -0.381 -0.8382)
			(stroke
				(width 0)
				(type default)
			)
			(fill no)
			(layer "B.CrtYd")
		)
		(fp_rect
			(start 0.381 0.8382)
			(end -0.381 -0.8382)
			(stroke
				(width 0)
				(type default)
			)
			(fill no)
			(layer "B.Fab")
		)
		(pad "1" smd custom
			(at 0 -0.4318 90)
			(size 0.127 0.127)
			(layers "B.Cu" "B.Mask" "B.Paste")
			(net "PORT80_R_BIT3")
			(options
				(clearance outline)
				(anchor circle)
			)
			(primitives
				(gr_poly
					(pts
						(arc
							(start -0.2032 0.2794)
							(mid -0.239121 0.264521)
							(end -0.254 0.2286)
						)
						(arc
							(start -0.254 -0.2286)
							(mid -0.239121 -0.264521)
							(end -0.2032 -0.2794)
						)
						(arc
							(start 0.2032 -0.2794)
							(mid 0.239121 -0.264521)
							(end 0.254 -0.2286)
						)
						(arc
							(start 0.254 0.2286)
							(mid 0.239121 0.264521)
							(end 0.2032 0.2794)
						)
					)
					(width 0)
					(fill yes)
				)
			)
		)
		(pad "2" smd custom
			(at 0 0.4318 90)
			(size 0.127 0.127)
			(layers "B.Cu" "B.Mask" "B.Paste")
			(net "P3V3_STBY")
			(options
				(clearance outline)
				(anchor circle)
			)
			(primitives
				(gr_poly
					(pts
						(arc
							(start -0.2032 0.2794)
							(mid -0.239121 0.264521)
							(end -0.254 0.2286)
						)
						(arc
							(start -0.254 -0.2286)
							(mid -0.239121 -0.264521)
							(end -0.2032 -0.2794)
						)
						(arc
							(start 0.2032 -0.2794)
							(mid 0.239121 -0.264521)
							(end 0.254 -0.2286)
						)
						(arc
							(start 0.254 0.2286)
							(mid 0.239121 0.264521)
							(end 0.2032 0.2794)
						)
					)
					(width 0)
					(fill yes)
				)
			)
		)
	)
	(footprint ""
		(layer "B.Cu")
		(at 33.147 -44.45 -90)
		(property "Reference" "PR185"
			(at 0 0 90)
			(layer "B.SilkS")
			(hide yes)
			(effects
				(font
					(size 1.27 1.27)
				)
				(justify mirror)
			)
		)
		(property "Value" "4K75R2F-1-GP"
			(at -1.7907 -1.1176 270)
			(unlocked yes)
			(layer "B.Fab")
			(hide yes)
			(effects
				(font
					(size 1.016 1.016)
					(thickness 0.1524)
				)
				(justify mirror)
			)
		)
		(property "Device Type" "R402H16"
			(at -1.7907 -2.6416 270)
			(unlocked yes)
			(layer "B.Fab")
			(hide yes)
			(effects
				(font
					(size 1.016 1.016)
					(thickness 0.1524)
				)
				(justify mirror)
			)
		)
		(duplicate_pad_numbers_are_jumpers no)
		(fp_rect
			(start 0.381 0.8382)
			(end -0.381 -0.8382)
			(stroke
				(width 0)
				(type default)
			)
			(fill no)
			(layer "B.CrtYd")
		)
		(fp_rect
			(start 0.381 0.8382)
			(end -0.381 -0.8382)
			(stroke
				(width 0)
				(type default)
			)
			(fill no)
			(layer "B.Fab")
		)
		(pad "1" smd custom
			(at 0 -0.4318 90)
			(size 0.127 0.127)
			(layers "B.Cu" "B.Mask" "B.Paste")
			(net "P1V5_STBY_FB")
			(options
				(clearance outline)
				(anchor circle)
			)
			(primitives
				(gr_poly
					(pts
						(arc
							(start -0.2032 0.2794)
							(mid -0.239121 0.264521)
							(end -0.254 0.2286)
						)
						(arc
							(start -0.254 -0.2286)
							(mid -0.239121 -0.264521)
							(end -0.2032 -0.2794)
						)
						(arc
							(start 0.2032 -0.2794)
							(mid 0.239121 -0.264521)
							(end 0.254 -0.2286)
						)
						(arc
							(start 0.254 0.2286)
							(mid 0.239121 0.264521)
							(end 0.2032 0.2794)
						)
					)
					(width 0)
					(fill yes)
				)
			)
		)
		(pad "2" smd custom
			(at 0 0.4318 90)
			(size 0.127 0.127)
			(layers "B.Cu" "B.Mask" "B.Paste")
			(net "GND")
			(options
				(clearance outline)
				(anchor circle)
			)
			(primitives
				(gr_poly
					(pts
						(arc
							(start -0.2032 0.2794)
							(mid -0.239121 0.264521)
							(end -0.254 0.2286)
						)
						(arc
							(start -0.254 -0.2286)
							(mid -0.239121 -0.264521)
							(end -0.2032 -0.2794)
						)
						(arc
							(start 0.2032 -0.2794)
							(mid 0.239121 -0.264521)
							(end 0.254 -0.2286)
						)
						(arc
							(start 0.254 0.2286)
							(mid 0.239121 0.264521)
							(end 0.2032 0.2794)
						)
					)
					(width 0)
					(fill yes)
				)
			)
		)
	)
	(footprint ""
		(layer "B.Cu")
		(at 110.363 -52.197 90)
		(property "Reference" "C126"
			(at 0 0 90)
			(layer "B.SilkS")
			(hide yes)
			(effects
				(font
					(size 1.27 1.27)
				)
				(justify mirror)
			)
		)
		(property "Value" "SC22U6D3V5MX-2GP"
			(at 0.0762 -6.1214 90)
			(unlocked yes)
			(layer "B.Fab")
			(hide yes)
			(effects
				(font
					(size 1.016 1.016)
					(thickness 0.1524)
				)
				(justify mirror)
			)
		)
		(property "Device Type" "C805H58"
			(at 0.0762 -8.1534 90)
			(unlocked yes)
			(layer "B.Fab")
			(hide yes)
			(effects
				(font
					(size 1.016 1.016)
					(thickness 0.1524)
				)
				(justify mirror)
			)
		)
		(duplicate_pad_numbers_are_jumpers no)
		(fp_line
			(start -0.6096 0)
			(end 0.6096 0)
			(stroke
				(width 0.3048)
				(type default)
			)
			(layer "B.SilkS")
		)
		(fp_poly
			(pts
				(xy 0.9017 1.4351) (xy -0.9017 1.4351) (xy -0.9017 -1.4351) (xy 0.9017 -1.4351)
			)
			(stroke
				(width 0)
				(type default)
			)
			(fill no)
			(layer "B.CrtYd")
		)
		(fp_poly
			(pts
				(xy -0.9017 1.4351) (xy -0.9017 -1.4351) (xy 0.9017 -1.4351) (xy 0.9017 1.4351)
			)
			(stroke
				(width 0)
				(type default)
			)
			(fill no)
			(layer "B.Fab")
		)
		(pad "1" smd rect
			(at 0 -0.8382 270)
			(size 1.5494 0.9398)
			(layers "B.Cu" "B.Mask" "B.Paste")
			(net "PV_VDDR")
		)
		(pad "2" smd rect
			(at 0 0.8382 270)
			(size 1.5494 0.9398)
			(layers "B.Cu" "B.Mask" "B.Paste")
			(net "GND")
		)
	)
	(footprint ""
		(layer "B.Cu")
		(at 121.666 -68.7578)
		(property "Reference" "R238"
			(at 0 0 0)
			(layer "B.SilkS")
			(hide yes)
			(effects
				(font
					(size 1.27 1.27)
				)
				(justify mirror)
			)
		)
		(property "Value" "0R2J-2-GP"
			(at -0.064008 -3.993896 0)
			(unlocked yes)
			(layer "B.Fab")
			(hide yes)
			(effects
				(font
					(size 1.016 1.016)
					(thickness 0.1524)
				)
				(justify mirror)
			)
		)
		(property "Device Type" "R402H16"
			(at -0.064008 -5.517896 0)
			(unlocked yes)
			(layer "B.Fab")
			(hide yes)
			(effects
				(font
					(size 1.016 1.016)
					(thickness 0.1524)
				)
				(justify mirror)
			)
		)
		(duplicate_pad_numbers_are_jumpers no)
		(fp_rect
			(start 0.381 0.8382)
			(end -0.381 -0.8382)
			(stroke
				(width 0)
				(type default)
			)
			(fill no)
			(layer "B.CrtYd")
		)
		(fp_rect
			(start 0.381 0.8382)
			(end -0.381 -0.8382)
			(stroke
				(width 0)
				(type default)
			)
			(fill no)
			(layer "B.Fab")
		)
		(pad "1" smd custom
			(at 0 -0.4318 180)
			(size 0.127 0.127)
			(layers "B.Cu" "B.Mask" "B.Paste")
			(net "SMB_M_A0_R_DATA")
			(options
				(clearance outline)
				(anchor circle)
			)
			(primitives
				(gr_poly
					(pts
						(arc
							(start -0.2032 0.2794)
							(mid -0.239121 0.264521)
							(end -0.254 0.2286)
						)
						(arc
							(start -0.254 -0.2286)
							(mid -0.239121 -0.264521)
							(end -0.2032 -0.2794)
						)
						(arc
							(start 0.2032 -0.2794)
							(mid 0.239121 -0.264521)
							(end 0.254 -0.2286)
						)
						(arc
							(start 0.254 0.2286)
							(mid 0.239121 0.264521)
							(end 0.2032 0.2794)
						)
					)
					(width 0)
					(fill yes)
				)
			)
		)
		(pad "2" smd custom
			(at 0 0.4318 180)
			(size 0.127 0.127)
			(layers "B.Cu" "B.Mask" "B.Paste")
			(net "SMB_HOST_LV_DATA")
			(options
				(clearance outline)
				(anchor circle)
			)
			(primitives
				(gr_poly
					(pts
						(arc
							(start -0.2032 0.2794)
							(mid -0.239121 0.264521)
							(end -0.254 0.2286)
						)
						(arc
							(start -0.254 -0.2286)
							(mid -0.239121 -0.264521)
							(end -0.2032 -0.2794)
						)
						(arc
							(start 0.2032 -0.2794)
							(mid 0.239121 -0.264521)
							(end 0.254 -0.2286)
						)
						(arc
							(start 0.254 0.2286)
							(mid 0.239121 0.264521)
							(end 0.2032 0.2794)
						)
					)
					(width 0)
					(fill yes)
				)
			)
		)
	)
	(footprint ""
		(layer "B.Cu")
		(at 91.4146 -38.5826 90)
		(property "Reference" "C183"
			(at 0 0 90)
			(layer "B.SilkS")
			(hide yes)
			(effects
				(font
					(size 1.27 1.27)
				)
				(justify mirror)
			)
		)
		(property "Value" "SCD1U16V2KX-3GP"
			(at -1.1811 -2.7051 90)
			(unlocked yes)
			(layer "B.Fab")
			(hide yes)
			(effects
				(font
					(size 1.016 1.016)
					(thickness 0.1524)
				)
				(justify mirror)
			)
		)
		(property "Device Type" "C402H22"
			(at -1.1811 -4.2291 90)
			(unlocked yes)
			(layer "B.Fab")
			(hide yes)
			(effects
				(font
					(size 1.016 1.016)
					(thickness 0.1524)
				)
				(justify mirror)
			)
		)
		(duplicate_pad_numbers_are_jumpers no)
		(fp_rect
			(start 0.381 0.7366)
			(end -0.381 -0.7366)
			(stroke
				(width 0)
				(type default)
			)
			(fill no)
			(layer "B.CrtYd")
		)
		(fp_rect
			(start 0.381 0.7366)
			(end -0.381 -0.7366)
			(stroke
				(width 0)
				(type default)
			)
			(fill no)
			(layer "B.Fab")
		)
		(pad "1" smd custom
			(at 0 -0.4572 270)
			(size 0.1143 0.1143)
			(layers "B.Cu" "B.Mask" "B.Paste")
			(net "P3V3_RTC")
			(options
				(clearance outline)
				(anchor circle)
			)
			(primitives
				(gr_poly
					(pts
						(arc
							(start -0.254 0.1778)
							(mid -0.239121 0.213721)
							(end -0.2032 0.2286)
						)
						(arc
							(start 0.2032 0.2286)
							(mid 0.239121 0.213721)
							(end 0.254 0.1778)
						)
						(arc
							(start 0.254 -0.1778)
							(mid 0.239121 -0.213721)
							(end 0.2032 -0.2286)
						)
						(arc
							(start -0.2032 -0.2286)
							(mid -0.239121 -0.213721)
							(end -0.254 -0.1778)
						)
					)
					(width 0)
					(fill yes)
				)
			)
		)
		(pad "2" smd custom
			(at 0 0.4572 270)
			(size 0.1143 0.1143)
			(layers "B.Cu" "B.Mask" "B.Paste")
			(net "GND")
			(options
				(clearance outline)
				(anchor circle)
			)
			(primitives
				(gr_poly
					(pts
						(arc
							(start -0.254 0.1778)
							(mid -0.239121 0.213721)
							(end -0.2032 0.2286)
						)
						(arc
							(start 0.2032 0.2286)
							(mid 0.239121 0.213721)
							(end 0.254 0.1778)
						)
						(arc
							(start 0.254 -0.1778)
							(mid 0.239121 -0.213721)
							(end 0.2032 -0.2286)
						)
						(arc
							(start -0.2032 -0.2286)
							(mid -0.239121 -0.213721)
							(end -0.254 -0.1778)
						)
					)
					(width 0)
					(fill yes)
				)
			)
		)
	)
	(footprint ""
		(layer "B.Cu")
		(at 98.933 -38.598602 180)
		(property "Reference" "C185"
			(at 0 0 0)
			(layer "B.SilkS")
			(hide yes)
			(effects
				(font
					(size 1.27 1.27)
				)
				(justify mirror)
			)
		)
		(property "Value" "SC2D2U10V2KX-GP"
			(at -1.1811 -2.7051 180)
			(unlocked yes)
			(layer "B.Fab")
			(hide yes)
			(effects
				(font
					(size 1.016 1.016)
					(thickness 0.1524)
				)
				(justify mirror)
			)
		)
		(property "Device Type" "C402H22"
			(at -1.1811 -4.2291 180)
			(unlocked yes)
			(layer "B.Fab")
			(hide yes)
			(effects
				(font
					(size 1.016 1.016)
					(thickness 0.1524)
				)
				(justify mirror)
			)
		)
		(duplicate_pad_numbers_are_jumpers no)
		(fp_rect
			(start 0.381 0.7366)
			(end -0.381 -0.7366)
			(stroke
				(width 0)
				(type default)
			)
			(fill no)
			(layer "B.CrtYd")
		)
		(fp_rect
			(start 0.381 0.7366)
			(end -0.381 -0.7366)
			(stroke
				(width 0)
				(type default)
			)
			(fill no)
			(layer "B.Fab")
		)
		(pad "1" smd custom
			(at 0 -0.4572)
			(size 0.1143 0.1143)
			(layers "B.Cu" "B.Mask" "B.Paste")
			(net "P1V0")
			(options
				(clearance outline)
				(anchor circle)
			)
			(primitives
				(gr_poly
					(pts
						(arc
							(start -0.254 0.1778)
							(mid -0.239121 0.213721)
							(end -0.2032 0.2286)
						)
						(arc
							(start 0.2032 0.2286)
							(mid 0.239121 0.213721)
							(end 0.254 0.1778)
						)
						(arc
							(start 0.254 -0.1778)
							(mid 0.239121 -0.213721)
							(end 0.2032 -0.2286)
						)
						(arc
							(start -0.2032 -0.2286)
							(mid -0.239121 -0.213721)
							(end -0.254 -0.1778)
						)
					)
					(width 0)
					(fill yes)
				)
			)
		)
		(pad "2" smd custom
			(at 0 0.4572)
			(size 0.1143 0.1143)
			(layers "B.Cu" "B.Mask" "B.Paste")
			(net "GND")
			(options
				(clearance outline)
				(anchor circle)
			)
			(primitives
				(gr_poly
					(pts
						(arc
							(start -0.254 0.1778)
							(mid -0.239121 0.213721)
							(end -0.2032 0.2286)
						)
						(arc
							(start 0.2032 0.2286)
							(mid 0.239121 0.213721)
							(end 0.254 0.1778)
						)
						(arc
							(start 0.254 -0.1778)
							(mid 0.239121 -0.213721)
							(end 0.2032 -0.2286)
						)
						(arc
							(start -0.2032 -0.2286)
							(mid -0.239121 -0.213721)
							(end -0.254 -0.1778)
						)
					)
					(width 0)
					(fill yes)
				)
			)
		)
	)
	(footprint ""
		(layer "B.Cu")
		(at 71.501 -34.417 -90)
		(property "Reference" "R335"
			(at 0 0 90)
			(layer "B.SilkS")
			(hide yes)
			(effects
				(font
					(size 1.27 1.27)
				)
				(justify mirror)
			)
		)
		(property "Value" "11KR2F-L-GP"
			(at -0.064008 -3.993896 270)
			(unlocked yes)
			(layer "B.Fab")
			(hide yes)
			(effects
				(font
					(size 1.016 1.016)
					(thickness 0.1524)
				)
				(justify mirror)
			)
		)
		(property "Device Type" "R402H16"
			(at -0.064008 -5.517896 270)
			(unlocked yes)
			(layer "B.Fab")
			(hide yes)
			(effects
				(font
					(size 1.016 1.016)
					(thickness 0.1524)
				)
				(justify mirror)
			)
		)
		(duplicate_pad_numbers_are_jumpers no)
		(fp_rect
			(start 0.381 0.8382)
			(end -0.381 -0.8382)
			(stroke
				(width 0)
				(type default)
			)
			(fill no)
			(layer "B.CrtYd")
		)
		(fp_rect
			(start 0.381 0.8382)
			(end -0.381 -0.8382)
			(stroke
				(width 0)
				(type default)
			)
			(fill no)
			(layer "B.Fab")
		)
		(pad "1" smd custom
			(at 0 -0.4318 90)
			(size 0.127 0.127)
			(layers "B.Cu" "B.Mask" "B.Paste")
			(net "P3V3_RTC")
			(options
				(clearance outline)
				(anchor circle)
			)
			(primitives
				(gr_poly
					(pts
						(arc
							(start -0.2032 0.2794)
							(mid -0.239121 0.264521)
							(end -0.254 0.2286)
						)
						(arc
							(start -0.254 -0.2286)
							(mid -0.239121 -0.264521)
							(end -0.2032 -0.2794)
						)
						(arc
							(start 0.2032 -0.2794)
							(mid 0.239121 -0.264521)
							(end 0.254 -0.2286)
						)
						(arc
							(start 0.254 0.2286)
							(mid 0.239121 0.264521)
							(end 0.2032 0.2794)
						)
					)
					(width 0)
					(fill yes)
				)
			)
		)
		(pad "2" smd custom
			(at 0 0.4318 90)
			(size 0.127 0.127)
			(layers "B.Cu" "B.Mask" "B.Paste")
			(net "SRTCRST_BUF_IN#")
			(options
				(clearance outline)
				(anchor circle)
			)
			(primitives
				(gr_poly
					(pts
						(arc
							(start -0.2032 0.2794)
							(mid -0.239121 0.264521)
							(end -0.254 0.2286)
						)
						(arc
							(start -0.254 -0.2286)
							(mid -0.239121 -0.264521)
							(end -0.2032 -0.2794)
						)
						(arc
							(start 0.2032 -0.2794)
							(mid 0.239121 -0.264521)
							(end 0.254 -0.2286)
						)
						(arc
							(start 0.254 0.2286)
							(mid 0.239121 0.264521)
							(end 0.2032 0.2794)
						)
					)
					(width 0)
					(fill yes)
				)
			)
		)
	)
	(footprint ""
		(layer "B.Cu")
		(at 93.599 -26.924 90)
		(property "Reference" "C226"
			(at 0 0 90)
			(layer "B.SilkS")
			(hide yes)
			(effects
				(font
					(size 1.27 1.27)
				)
				(justify mirror)
			)
		)
		(property "Value" "SC1U10V2KX-1GP"
			(at -1.1811 -2.7051 90)
			(unlocked yes)
			(layer "B.Fab")
			(hide yes)
			(effects
				(font
					(size 1.016 1.016)
					(thickness 0.1524)
				)
				(justify mirror)
			)
		)
		(property "Device Type" "C402H22"
			(at -1.1811 -4.2291 90)
			(unlocked yes)
			(layer "B.Fab")
			(hide yes)
			(effects
				(font
					(size 1.016 1.016)
					(thickness 0.1524)
				)
				(justify mirror)
			)
		)
		(duplicate_pad_numbers_are_jumpers no)
		(fp_rect
			(start 0.381 0.7366)
			(end -0.381 -0.7366)
			(stroke
				(width 0)
				(type default)
			)
			(fill no)
			(layer "B.CrtYd")
		)
		(fp_rect
			(start 0.381 0.7366)
			(end -0.381 -0.7366)
			(stroke
				(width 0)
				(type default)
			)
			(fill no)
			(layer "B.Fab")
		)
		(pad "1" smd custom
			(at 0 -0.4572 270)
			(size 0.1143 0.1143)
			(layers "B.Cu" "B.Mask" "B.Paste")
			(net "P1V0")
			(options
				(clearance outline)
				(anchor circle)
			)
			(primitives
				(gr_poly
					(pts
						(arc
							(start -0.254 0.1778)
							(mid -0.239121 0.213721)
							(end -0.2032 0.2286)
						)
						(arc
							(start 0.2032 0.2286)
							(mid 0.239121 0.213721)
							(end 0.254 0.1778)
						)
						(arc
							(start 0.254 -0.1778)
							(mid 0.239121 -0.213721)
							(end 0.2032 -0.2286)
						)
						(arc
							(start -0.2032 -0.2286)
							(mid -0.239121 -0.213721)
							(end -0.254 -0.1778)
						)
					)
					(width 0)
					(fill yes)
				)
			)
		)
		(pad "2" smd custom
			(at 0 0.4572 270)
			(size 0.1143 0.1143)
			(layers "B.Cu" "B.Mask" "B.Paste")
			(net "GND")
			(options
				(clearance outline)
				(anchor circle)
			)
			(primitives
				(gr_poly
					(pts
						(arc
							(start -0.254 0.1778)
							(mid -0.239121 0.213721)
							(end -0.2032 0.2286)
						)
						(arc
							(start 0.2032 0.2286)
							(mid 0.239121 0.213721)
							(end 0.254 0.1778)
						)
						(arc
							(start 0.254 -0.1778)
							(mid 0.239121 -0.213721)
							(end 0.2032 -0.2286)
						)
						(arc
							(start -0.2032 -0.2286)
							(mid -0.239121 -0.213721)
							(end -0.254 -0.1778)
						)
					)
					(width 0)
					(fill yes)
				)
			)
		)
	)
	(footprint ""
		(layer "B.Cu")
		(at 101.981 -33.290002 90)
		(property "Reference" "C218"
			(at 0 0 90)
			(layer "B.SilkS")
			(hide yes)
			(effects
				(font
					(size 1.27 1.27)
				)
				(justify mirror)
			)
		)
		(property "Value" "SC1U10V2KX-1GP"
			(at -1.1811 -2.7051 90)
			(unlocked yes)
			(layer "B.Fab")
			(hide yes)
			(effects
				(font
					(size 1.016 1.016)
					(thickness 0.1524)
				)
				(justify mirror)
			)
		)
		(property "Device Type" "C402H22"
			(at -1.1811 -4.2291 90)
			(unlocked yes)
			(layer "B.Fab")
			(hide yes)
			(effects
				(font
					(size 1.016 1.016)
					(thickness 0.1524)
				)
				(justify mirror)
			)
		)
		(duplicate_pad_numbers_are_jumpers no)
		(fp_rect
			(start 0.381 0.7366)
			(end -0.381 -0.7366)
			(stroke
				(width 0)
				(type default)
			)
			(fill no)
			(layer "B.CrtYd")
		)
		(fp_rect
			(start 0.381 0.7366)
			(end -0.381 -0.7366)
			(stroke
				(width 0)
				(type default)
			)
			(fill no)
			(layer "B.Fab")
		)
		(pad "1" smd custom
			(at 0 -0.4572 270)
			(size 0.1143 0.1143)
			(layers "B.Cu" "B.Mask" "B.Paste")
			(net "P1V0")
			(options
				(clearance outline)
				(anchor circle)
			)
			(primitives
				(gr_poly
					(pts
						(arc
							(start -0.254 0.1778)
							(mid -0.239121 0.213721)
							(end -0.2032 0.2286)
						)
						(arc
							(start 0.2032 0.2286)
							(mid 0.239121 0.213721)
							(end 0.254 0.1778)
						)
						(arc
							(start 0.254 -0.1778)
							(mid 0.239121 -0.213721)
							(end 0.2032 -0.2286)
						)
						(arc
							(start -0.2032 -0.2286)
							(mid -0.239121 -0.213721)
							(end -0.254 -0.1778)
						)
					)
					(width 0)
					(fill yes)
				)
			)
		)
		(pad "2" smd custom
			(at 0 0.4572 270)
			(size 0.1143 0.1143)
			(layers "B.Cu" "B.Mask" "B.Paste")
			(net "GND")
			(options
				(clearance outline)
				(anchor circle)
			)
			(primitives
				(gr_poly
					(pts
						(arc
							(start -0.254 0.1778)
							(mid -0.239121 0.213721)
							(end -0.2032 0.2286)
						)
						(arc
							(start 0.2032 0.2286)
							(mid 0.239121 0.213721)
							(end 0.254 0.1778)
						)
						(arc
							(start 0.254 -0.1778)
							(mid 0.239121 -0.213721)
							(end 0.2032 -0.2286)
						)
						(arc
							(start -0.2032 -0.2286)
							(mid -0.239121 -0.213721)
							(end -0.254 -0.1778)
						)
					)
					(width 0)
					(fill yes)
				)
			)
		)
	)
	(footprint ""
		(layer "B.Cu")
		(at 106.0831 -44.608242 90)
		(property "Reference" "R303"
			(at 0 0 90)
			(layer "B.SilkS")
			(hide yes)
			(effects
				(font
					(size 1.27 1.27)
				)
				(justify mirror)
			)
		)
		(property "Value" "162R2F-GP"
			(at -0.064008 -3.993896 90)
			(unlocked yes)
			(layer "B.Fab")
			(hide yes)
			(effects
				(font
					(size 1.016 1.016)
					(thickness 0.1524)
				)
				(justify mirror)
			)
		)
		(property "Device Type" "R402H16"
			(at -0.064008 -5.517896 90)
			(unlocked yes)
			(layer "B.Fab")
			(hide yes)
			(effects
				(font
					(size 1.016 1.016)
					(thickness 0.1524)
				)
				(justify mirror)
			)
		)
		(duplicate_pad_numbers_are_jumpers no)
		(fp_rect
			(start 0.381 0.8382)
			(end -0.381 -0.8382)
			(stroke
				(width 0)
				(type default)
			)
			(fill no)
			(layer "B.CrtYd")
		)
		(fp_rect
			(start 0.381 0.8382)
			(end -0.381 -0.8382)
			(stroke
				(width 0)
				(type default)
			)
			(fill no)
			(layer "B.Fab")
		)
		(pad "1" smd custom
			(at 0 -0.4318 270)
			(size 0.127 0.127)
			(layers "B.Cu" "B.Mask" "B.Paste")
			(net "M_A_ODTPU")
			(options
				(clearance outline)
				(anchor circle)
			)
			(primitives
				(gr_poly
					(pts
						(arc
							(start -0.2032 0.2794)
							(mid -0.239121 0.264521)
							(end -0.254 0.2286)
						)
						(arc
							(start -0.254 -0.2286)
							(mid -0.239121 -0.264521)
							(end -0.2032 -0.2794)
						)
						(arc
							(start 0.2032 -0.2794)
							(mid 0.239121 -0.264521)
							(end 0.254 -0.2286)
						)
						(arc
							(start 0.254 0.2286)
							(mid 0.239121 0.264521)
							(end 0.2032 0.2794)
						)
					)
					(width 0)
					(fill yes)
				)
			)
		)
		(pad "2" smd custom
			(at 0 0.4318 270)
			(size 0.127 0.127)
			(layers "B.Cu" "B.Mask" "B.Paste")
			(net "GND")
			(options
				(clearance outline)
				(anchor circle)
			)
			(primitives
				(gr_poly
					(pts
						(arc
							(start -0.2032 0.2794)
							(mid -0.239121 0.264521)
							(end -0.254 0.2286)
						)
						(arc
							(start -0.254 -0.2286)
							(mid -0.239121 -0.264521)
							(end -0.2032 -0.2794)
						)
						(arc
							(start 0.2032 -0.2794)
							(mid 0.239121 -0.264521)
							(end 0.254 -0.2286)
						)
						(arc
							(start 0.254 0.2286)
							(mid 0.239121 0.264521)
							(end 0.2032 0.2794)
						)
					)
					(width 0)
					(fill yes)
				)
			)
		)
	)
	(footprint ""
		(layer "B.Cu")
		(at 130.175 -14.987778 180)
		(property "Reference" "C355"
			(at 0 0 0)
			(layer "B.SilkS")
			(hide yes)
			(effects
				(font
					(size 1.27 1.27)
				)
				(justify mirror)
			)
		)
		(property "Value" "SC1U6D3V3KX-2GP"
			(at 0.0254 -2.0193 180)
			(unlocked yes)
			(layer "B.Fab")
			(hide yes)
			(effects
				(font
					(size 1.016 1.016)
					(thickness 0.1524)
				)
				(justify mirror)
			)
		)
		(property "Device Type" "C603H36"
			(at 0.0254 -3.5433 180)
			(unlocked yes)
			(layer "B.Fab")
			(hide yes)
			(effects
				(font
					(size 1.016 1.016)
					(thickness 0.1524)
				)
				(justify mirror)
			)
		)
		(duplicate_pad_numbers_are_jumpers no)
		(fp_line
			(start 0.4064 0)
			(end -0.4064 0)
			(stroke
				(width 0.2286)
				(type default)
			)
			(layer "B.SilkS")
		)
		(fp_rect
			(start 0.635 1.1811)
			(end -0.635 -1.1811)
			(stroke
				(width 0)
				(type default)
			)
			(fill no)
			(layer "B.CrtYd")
		)
		(fp_rect
			(start 0.635 1.1811)
			(end -0.635 -1.1811)
			(stroke
				(width 0)
				(type default)
			)
			(fill no)
			(layer "B.Fab")
		)
		(pad "1" smd custom
			(at 0 -0.6604)
			(size 0.19685 0.19685)
			(layers "B.Cu" "B.Mask" "B.Paste")
			(net "DDR3_M_B_VREF_DQ1")
			(options
				(clearance outline)
				(anchor circle)
			)
			(primitives
				(gr_poly
					(pts
						(arc
							(start 0.508 0.2921)
							(mid 0.478242 0.363942)
							(end 0.4064 0.3937)
						)
						(arc
							(start -0.4064 0.3937)
							(mid -0.478242 0.363942)
							(end -0.508 0.2921)
						)
						(arc
							(start -0.508 -0.2921)
							(mid -0.478242 -0.363942)
							(end -0.4064 -0.3937)
						)
						(arc
							(start 0.4064 -0.3937)
							(mid 0.478242 -0.363942)
							(end 0.508 -0.2921)
						)
					)
					(width 0)
					(fill yes)
				)
			)
		)
		(pad "2" smd custom
			(at 0 0.6604)
			(size 0.19685 0.19685)
			(layers "B.Cu" "B.Mask" "B.Paste")
			(net "GND")
			(options
				(clearance outline)
				(anchor circle)
			)
			(primitives
				(gr_poly
					(pts
						(arc
							(start 0.508 0.2921)
							(mid 0.478242 0.363942)
							(end 0.4064 0.3937)
						)
						(arc
							(start -0.4064 0.3937)
							(mid -0.478242 0.363942)
							(end -0.508 0.2921)
						)
						(arc
							(start -0.508 -0.2921)
							(mid -0.478242 -0.363942)
							(end -0.4064 -0.3937)
						)
						(arc
							(start 0.4064 -0.3937)
							(mid 0.478242 -0.363942)
							(end 0.508 -0.2921)
						)
					)
					(width 0)
					(fill yes)
				)
			)
		)
	)
	(footprint ""
		(layer "B.Cu")
		(at 14.859 -48.133)
		(property "Reference" "C250"
			(at 0 0 0)
			(layer "B.SilkS")
			(hide yes)
			(effects
				(font
					(size 1.27 1.27)
				)
				(justify mirror)
			)
		)
		(property "Value" "SC1U6D3V2KX-GP"
			(at -1.8923 -1.2065 0)
			(unlocked yes)
			(layer "B.Fab")
			(hide yes)
			(effects
				(font
					(size 1.016 1.016)
					(thickness 0.1524)
				)
				(justify mirror)
			)
		)
		(property "Device Type" "C402H22"
			(at -1.8923 -2.7305 0)
			(unlocked yes)
			(layer "B.Fab")
			(hide yes)
			(effects
				(font
					(size 1.016 1.016)
					(thickness 0.1524)
				)
				(justify mirror)
			)
		)
		(duplicate_pad_numbers_are_jumpers no)
		(fp_rect
			(start 0.381 0.7366)
			(end -0.381 -0.7366)
			(stroke
				(width 0)
				(type default)
			)
			(fill no)
			(layer "B.CrtYd")
		)
		(fp_rect
			(start 0.381 0.7366)
			(end -0.381 -0.7366)
			(stroke
				(width 0)
				(type default)
			)
			(fill no)
			(layer "B.Fab")
		)
		(pad "1" smd custom
			(at 0 -0.4572 180)
			(size 0.1143 0.1143)
			(layers "B.Cu" "B.Mask" "B.Paste")
			(net "P3V3")
			(options
				(clearance outline)
				(anchor circle)
			)
			(primitives
				(gr_poly
					(pts
						(arc
							(start -0.254 0.1778)
							(mid -0.239121 0.213721)
							(end -0.2032 0.2286)
						)
						(arc
							(start 0.2032 0.2286)
							(mid 0.239121 0.213721)
							(end 0.254 0.1778)
						)
						(arc
							(start 0.254 -0.1778)
							(mid 0.239121 -0.213721)
							(end 0.2032 -0.2286)
						)
						(arc
							(start -0.2032 -0.2286)
							(mid -0.239121 -0.213721)
							(end -0.254 -0.1778)
						)
					)
					(width 0)
					(fill yes)
				)
			)
		)
		(pad "2" smd custom
			(at 0 0.4572 180)
			(size 0.1143 0.1143)
			(layers "B.Cu" "B.Mask" "B.Paste")
			(net "GND")
			(options
				(clearance outline)
				(anchor circle)
			)
			(primitives
				(gr_poly
					(pts
						(arc
							(start -0.254 0.1778)
							(mid -0.239121 0.213721)
							(end -0.2032 0.2286)
						)
						(arc
							(start 0.2032 0.2286)
							(mid 0.239121 0.213721)
							(end 0.254 0.1778)
						)
						(arc
							(start 0.254 -0.1778)
							(mid 0.239121 -0.213721)
							(end 0.2032 -0.2286)
						)
						(arc
							(start -0.2032 -0.2286)
							(mid -0.239121 -0.213721)
							(end -0.254 -0.1778)
						)
					)
					(width 0)
					(fill yes)
				)
			)
		)
	)
	(footprint ""
		(layer "B.Cu")
		(at 76.962 -19.7358 90)
		(property "Reference" "PR225"
			(at 0 0 90)
			(layer "B.SilkS")
			(hide yes)
			(effects
				(font
					(size 1.27 1.27)
				)
				(justify mirror)
			)
		)
		(property "Value" "0R3J-6-GP"
			(at 0.0254 -2.5146 90)
			(unlocked yes)
			(layer "B.Fab")
			(hide yes)
			(effects
				(font
					(size 1.016 1.016)
					(thickness 0.1524)
				)
				(justify mirror)
			)
		)
		(property "Device Type" "R603H22"
			(at 0.0254 -4.0386 90)
			(unlocked yes)
			(layer "B.Fab")
			(hide yes)
			(effects
				(font
					(size 1.016 1.016)
					(thickness 0.1524)
				)
				(justify mirror)
			)
		)
		(duplicate_pad_numbers_are_jumpers no)
		(fp_line
			(start 0.2032 0)
			(end 0.4191 0)
			(stroke
				(width 0.2032)
				(type default)
			)
			(layer "B.SilkS")
		)
		(fp_line
			(start -0.4318 0)
			(end -0.2032 0)
			(stroke
				(width 0.2032)
				(type default)
			)
			(layer "B.SilkS")
		)
		(fp_rect
			(start 0.635 1.1811)
			(end -0.635 -1.1811)
			(stroke
				(width 0)
				(type default)
			)
			(fill no)
			(layer "B.CrtYd")
		)
		(fp_rect
			(start 0.635 1.1811)
			(end -0.635 -1.1811)
			(stroke
				(width 0)
				(type default)
			)
			(fill no)
			(layer "B.Fab")
		)
		(pad "1" smd custom
			(at 0 -0.6604 270)
			(size 0.19685 0.19685)
			(layers "B.Cu" "B.Mask" "B.Paste")
			(net "P1V8_STBY")
			(options
				(clearance outline)
				(anchor circle)
			)
			(primitives
				(gr_poly
					(pts
						(arc
							(start 0.508 0.2921)
							(mid 0.478242 0.363942)
							(end 0.4064 0.3937)
						)
						(arc
							(start -0.4064 0.3937)
							(mid -0.478242 0.363942)
							(end -0.508 0.2921)
						)
						(arc
							(start -0.508 -0.2921)
							(mid -0.478242 -0.363942)
							(end -0.4064 -0.3937)
						)
						(arc
							(start 0.4064 -0.3937)
							(mid 0.478242 -0.363942)
							(end 0.508 -0.2921)
						)
					)
					(width 0)
					(fill yes)
				)
			)
		)
		(pad "2" smd custom
			(at 0 0.6604 270)
			(size 0.19685 0.19685)
			(layers "B.Cu" "B.Mask" "B.Paste")
			(net "TPS74801_P1V35_IN")
			(options
				(clearance outline)
				(anchor circle)
			)
			(primitives
				(gr_poly
					(pts
						(arc
							(start 0.508 0.2921)
							(mid 0.478242 0.363942)
							(end 0.4064 0.3937)
						)
						(arc
							(start -0.4064 0.3937)
							(mid -0.478242 0.363942)
							(end -0.508 0.2921)
						)
						(arc
							(start -0.508 -0.2921)
							(mid -0.478242 -0.363942)
							(end -0.4064 -0.3937)
						)
						(arc
							(start 0.4064 -0.3937)
							(mid 0.478242 -0.363942)
							(end 0.508 -0.2921)
						)
					)
					(width 0)
					(fill yes)
				)
			)
		)
	)
	(footprint ""
		(layer "B.Cu")
		(at 20.701 -59.944 180)
		(property "Reference" "PC3"
			(at 0 0 0)
			(layer "B.SilkS")
			(hide yes)
			(effects
				(font
					(size 1.27 1.27)
				)
				(justify mirror)
			)
		)
		(property "Value" "SC1KP50V2KX-1GP"
			(at -1.8923 -1.2065 180)
			(unlocked yes)
			(layer "B.Fab")
			(hide yes)
			(effects
				(font
					(size 1.016 1.016)
					(thickness 0.1524)
				)
				(justify mirror)
			)
		)
		(property "Device Type" "C402H22"
			(at -1.8923 -2.7305 180)
			(unlocked yes)
			(layer "B.Fab")
			(hide yes)
			(effects
				(font
					(size 1.016 1.016)
					(thickness 0.1524)
				)
				(justify mirror)
			)
		)
		(duplicate_pad_numbers_are_jumpers no)
		(fp_rect
			(start 0.381 0.7366)
			(end -0.381 -0.7366)
			(stroke
				(width 0)
				(type default)
			)
			(fill no)
			(layer "B.CrtYd")
		)
		(fp_rect
			(start 0.381 0.7366)
			(end -0.381 -0.7366)
			(stroke
				(width 0)
				(type default)
			)
			(fill no)
			(layer "B.Fab")
		)
		(pad "1" smd custom
			(at 0 -0.4572)
			(size 0.1143 0.1143)
			(layers "B.Cu" "B.Mask" "B.Paste")
			(net "GND")
			(options
				(clearance outline)
				(anchor circle)
			)
			(primitives
				(gr_poly
					(pts
						(arc
							(start -0.254 0.1778)
							(mid -0.239121 0.213721)
							(end -0.2032 0.2286)
						)
						(arc
							(start 0.2032 0.2286)
							(mid 0.239121 0.213721)
							(end 0.254 0.1778)
						)
						(arc
							(start 0.254 -0.1778)
							(mid 0.239121 -0.213721)
							(end 0.2032 -0.2286)
						)
						(arc
							(start -0.2032 -0.2286)
							(mid -0.239121 -0.213721)
							(end -0.254 -0.1778)
						)
					)
					(width 0)
					(fill yes)
				)
			)
		)
		(pad "2" smd custom
			(at 0 0.4572)
			(size 0.1143 0.1143)
			(layers "B.Cu" "B.Mask" "B.Paste")
			(net "VR_PVNN_FB_RC2")
			(options
				(clearance outline)
				(anchor circle)
			)
			(primitives
				(gr_poly
					(pts
						(arc
							(start -0.254 0.1778)
							(mid -0.239121 0.213721)
							(end -0.2032 0.2286)
						)
						(arc
							(start 0.2032 0.2286)
							(mid 0.239121 0.213721)
							(end 0.254 0.1778)
						)
						(arc
							(start 0.254 -0.1778)
							(mid 0.239121 -0.213721)
							(end 0.2032 -0.2286)
						)
						(arc
							(start -0.2032 -0.2286)
							(mid -0.239121 -0.213721)
							(end -0.254 -0.1778)
						)
					)
					(width 0)
					(fill yes)
				)
			)
		)
	)
	(footprint ""
		(layer "B.Cu")
		(at 80.264 -13.462)
		(property "Reference" "C275"
			(at 0 0 0)
			(layer "B.SilkS")
			(hide yes)
			(effects
				(font
					(size 1.27 1.27)
				)
				(justify mirror)
			)
		)
		(property "Value" "SCD1U16V2KX-3GP"
			(at -1.1811 -2.7051 0)
			(unlocked yes)
			(layer "B.Fab")
			(hide yes)
			(effects
				(font
					(size 1.016 1.016)
					(thickness 0.1524)
				)
				(justify mirror)
			)
		)
		(property "Device Type" "C402H22"
			(at -1.1811 -4.2291 0)
			(unlocked yes)
			(layer "B.Fab")
			(hide yes)
			(effects
				(font
					(size 1.016 1.016)
					(thickness 0.1524)
				)
				(justify mirror)
			)
		)
		(duplicate_pad_numbers_are_jumpers no)
		(fp_rect
			(start 0.381 0.7366)
			(end -0.381 -0.7366)
			(stroke
				(width 0)
				(type default)
			)
			(fill no)
			(layer "B.CrtYd")
		)
		(fp_rect
			(start 0.381 0.7366)
			(end -0.381 -0.7366)
			(stroke
				(width 0)
				(type default)
			)
			(fill no)
			(layer "B.Fab")
		)
		(pad "1" smd custom
			(at 0 -0.4572 180)
			(size 0.1143 0.1143)
			(layers "B.Cu" "B.Mask" "B.Paste")
			(net "P2E_CPU_SAS_C_TX_DN0")
			(options
				(clearance outline)
				(anchor circle)
			)
			(primitives
				(gr_poly
					(pts
						(arc
							(start -0.254 0.1778)
							(mid -0.239121 0.213721)
							(end -0.2032 0.2286)
						)
						(arc
							(start 0.2032 0.2286)
							(mid 0.239121 0.213721)
							(end 0.254 0.1778)
						)
						(arc
							(start 0.254 -0.1778)
							(mid 0.239121 -0.213721)
							(end 0.2032 -0.2286)
						)
						(arc
							(start -0.2032 -0.2286)
							(mid -0.239121 -0.213721)
							(end -0.254 -0.1778)
						)
					)
					(width 0)
					(fill yes)
				)
			)
		)
		(pad "2" smd custom
			(at 0 0.4572 180)
			(size 0.1143 0.1143)
			(layers "B.Cu" "B.Mask" "B.Paste")
			(net "P2E_CPU_SAS_TX_DN0")
			(options
				(clearance outline)
				(anchor circle)
			)
			(primitives
				(gr_poly
					(pts
						(arc
							(start -0.254 0.1778)
							(mid -0.239121 0.213721)
							(end -0.2032 0.2286)
						)
						(arc
							(start 0.2032 0.2286)
							(mid 0.239121 0.213721)
							(end 0.254 0.1778)
						)
						(arc
							(start 0.254 -0.1778)
							(mid 0.239121 -0.213721)
							(end 0.2032 -0.2286)
						)
						(arc
							(start -0.2032 -0.2286)
							(mid -0.239121 -0.213721)
							(end -0.254 -0.1778)
						)
					)
					(width 0)
					(fill yes)
				)
			)
		)
	)
	(footprint ""
		(layer "B.Cu")
		(at 157.988 -12.574778 180)
		(property "Reference" "C298"
			(at 0 0 0)
			(layer "B.SilkS")
			(hide yes)
			(effects
				(font
					(size 1.27 1.27)
				)
				(justify mirror)
			)
		)
		(property "Value" "SC10U6D3V3MX-GP"
			(at 0.0254 -2.0193 180)
			(unlocked yes)
			(layer "B.Fab")
			(hide yes)
			(effects
				(font
					(size 1.016 1.016)
					(thickness 0.1524)
				)
				(justify mirror)
			)
		)
		(property "Device Type" "C603H38"
			(at 0.0254 -3.5433 180)
			(unlocked yes)
			(layer "B.Fab")
			(hide yes)
			(effects
				(font
					(size 1.016 1.016)
					(thickness 0.1524)
				)
				(justify mirror)
			)
		)
		(duplicate_pad_numbers_are_jumpers no)
		(fp_line
			(start 0.4064 0)
			(end -0.4064 0)
			(stroke
				(width 0.2286)
				(type default)
			)
			(layer "B.SilkS")
		)
		(fp_rect
			(start 0.635 1.1811)
			(end -0.635 -1.1811)
			(stroke
				(width 0)
				(type default)
			)
			(fill no)
			(layer "B.CrtYd")
		)
		(fp_rect
			(start 0.635 1.1811)
			(end -0.635 -1.1811)
			(stroke
				(width 0)
				(type default)
			)
			(fill no)
			(layer "B.Fab")
		)
		(pad "1" smd custom
			(at 0 -0.6604)
			(size 0.19685 0.19685)
			(layers "B.Cu" "B.Mask" "B.Paste")
			(net "PV_VDDR")
			(options
				(clearance outline)
				(anchor circle)
			)
			(primitives
				(gr_poly
					(pts
						(arc
							(start 0.508 0.2921)
							(mid 0.478242 0.363942)
							(end 0.4064 0.3937)
						)
						(arc
							(start -0.4064 0.3937)
							(mid -0.478242 0.363942)
							(end -0.508 0.2921)
						)
						(arc
							(start -0.508 -0.2921)
							(mid -0.478242 -0.363942)
							(end -0.4064 -0.3937)
						)
						(arc
							(start 0.4064 -0.3937)
							(mid 0.478242 -0.363942)
							(end 0.508 -0.2921)
						)
					)
					(width 0)
					(fill yes)
				)
			)
		)
		(pad "2" smd custom
			(at 0 0.6604)
			(size 0.19685 0.19685)
			(layers "B.Cu" "B.Mask" "B.Paste")
			(net "GND")
			(options
				(clearance outline)
				(anchor circle)
			)
			(primitives
				(gr_poly
					(pts
						(arc
							(start 0.508 0.2921)
							(mid 0.478242 0.363942)
							(end 0.4064 0.3937)
						)
						(arc
							(start -0.4064 0.3937)
							(mid -0.478242 0.363942)
							(end -0.508 0.2921)
						)
						(arc
							(start -0.508 -0.2921)
							(mid -0.478242 -0.363942)
							(end -0.4064 -0.3937)
						)
						(arc
							(start 0.4064 -0.3937)
							(mid 0.478242 -0.363942)
							(end 0.508 -0.2921)
						)
					)
					(width 0)
					(fill yes)
				)
			)
		)
	)
	(footprint ""
		(layer "B.Cu")
		(at 70.485 -53.467)
		(property "Reference" "R275"
			(at 0 0 0)
			(layer "B.SilkS")
			(hide yes)
			(effects
				(font
					(size 1.27 1.27)
				)
				(justify mirror)
			)
		)
		(property "Value" "1KR2F-3-GP"
			(at -0.064008 -3.993896 0)
			(unlocked yes)
			(layer "B.Fab")
			(hide yes)
			(effects
				(font
					(size 1.016 1.016)
					(thickness 0.1524)
				)
				(justify mirror)
			)
		)
		(property "Device Type" "R402H16"
			(at -0.064008 -5.517896 0)
			(unlocked yes)
			(layer "B.Fab")
			(hide yes)
			(effects
				(font
					(size 1.016 1.016)
					(thickness 0.1524)
				)
				(justify mirror)
			)
		)
		(duplicate_pad_numbers_are_jumpers no)
		(fp_rect
			(start 0.381 0.8382)
			(end -0.381 -0.8382)
			(stroke
				(width 0)
				(type default)
			)
			(fill no)
			(layer "B.CrtYd")
		)
		(fp_rect
			(start 0.381 0.8382)
			(end -0.381 -0.8382)
			(stroke
				(width 0)
				(type default)
			)
			(fill no)
			(layer "B.Fab")
		)
		(pad "1" smd custom
			(at 0 -0.4318 180)
			(size 0.127 0.127)
			(layers "B.Cu" "B.Mask" "B.Paste")
			(net "P3V3_STBY")
			(options
				(clearance outline)
				(anchor circle)
			)
			(primitives
				(gr_poly
					(pts
						(arc
							(start -0.2032 0.2794)
							(mid -0.239121 0.264521)
							(end -0.254 0.2286)
						)
						(arc
							(start -0.254 -0.2286)
							(mid -0.239121 -0.264521)
							(end -0.2032 -0.2794)
						)
						(arc
							(start 0.2032 -0.2794)
							(mid 0.239121 -0.264521)
							(end 0.254 -0.2286)
						)
						(arc
							(start 0.254 0.2286)
							(mid 0.239121 0.264521)
							(end 0.2032 0.2794)
						)
					)
					(width 0)
					(fill yes)
				)
			)
		)
		(pad "2" smd custom
			(at 0 0.4318 180)
			(size 0.127 0.127)
			(layers "B.Cu" "B.Mask" "B.Paste")
			(net "MEMORY_HOT_LV_R#")
			(options
				(clearance outline)
				(anchor circle)
			)
			(primitives
				(gr_poly
					(pts
						(arc
							(start -0.2032 0.2794)
							(mid -0.239121 0.264521)
							(end -0.254 0.2286)
						)
						(arc
							(start -0.254 -0.2286)
							(mid -0.239121 -0.264521)
							(end -0.2032 -0.2794)
						)
						(arc
							(start 0.2032 -0.2794)
							(mid 0.239121 -0.264521)
							(end 0.254 -0.2286)
						)
						(arc
							(start 0.254 0.2286)
							(mid 0.239121 0.264521)
							(end 0.2032 0.2794)
						)
					)
					(width 0)
					(fill yes)
				)
			)
		)
	)
	(footprint ""
		(layer "B.Cu")
		(at 74.041 -29.464 90)
		(property "Reference" "R457"
			(at 0 0 90)
			(layer "B.SilkS")
			(hide yes)
			(effects
				(font
					(size 1.27 1.27)
				)
				(justify mirror)
			)
		)
		(property "Value" "10KR2F-2-GP"
			(at -1.7907 -1.1176 90)
			(unlocked yes)
			(layer "B.Fab")
			(hide yes)
			(effects
				(font
					(size 1.016 1.016)
					(thickness 0.1524)
				)
				(justify mirror)
			)
		)
		(property "Device Type" "R402H16"
			(at -1.7907 -2.6416 90)
			(unlocked yes)
			(layer "B.Fab")
			(hide yes)
			(effects
				(font
					(size 1.016 1.016)
					(thickness 0.1524)
				)
				(justify mirror)
			)
		)
		(duplicate_pad_numbers_are_jumpers no)
		(fp_rect
			(start 0.381 0.8382)
			(end -0.381 -0.8382)
			(stroke
				(width 0)
				(type default)
			)
			(fill no)
			(layer "B.CrtYd")
		)
		(fp_rect
			(start 0.381 0.8382)
			(end -0.381 -0.8382)
			(stroke
				(width 0)
				(type default)
			)
			(fill no)
			(layer "B.Fab")
		)
		(pad "1" smd custom
			(at 0 -0.4318 270)
			(size 0.127 0.127)
			(layers "B.Cu" "B.Mask" "B.Paste")
			(net "P3V3_CPU")
			(options
				(clearance outline)
				(anchor circle)
			)
			(primitives
				(gr_poly
					(pts
						(arc
							(start -0.2032 0.2794)
							(mid -0.239121 0.264521)
							(end -0.254 0.2286)
						)
						(arc
							(start -0.254 -0.2286)
							(mid -0.239121 -0.264521)
							(end -0.2032 -0.2794)
						)
						(arc
							(start 0.2032 -0.2794)
							(mid 0.239121 -0.264521)
							(end 0.254 -0.2286)
						)
						(arc
							(start 0.254 0.2286)
							(mid 0.239121 0.264521)
							(end 0.2032 0.2794)
						)
					)
					(width 0)
					(fill yes)
				)
			)
		)
		(pad "2" smd custom
			(at 0 0.4318 270)
			(size 0.127 0.127)
			(layers "B.Cu" "B.Mask" "B.Paste")
			(net "REV_CPU_FPGA_IO0")
			(options
				(clearance outline)
				(anchor circle)
			)
			(primitives
				(gr_poly
					(pts
						(arc
							(start -0.2032 0.2794)
							(mid -0.239121 0.264521)
							(end -0.254 0.2286)
						)
						(arc
							(start -0.254 -0.2286)
							(mid -0.239121 -0.264521)
							(end -0.2032 -0.2794)
						)
						(arc
							(start 0.2032 -0.2794)
							(mid 0.239121 -0.264521)
							(end 0.254 -0.2286)
						)
						(arc
							(start 0.254 0.2286)
							(mid 0.239121 0.264521)
							(end 0.2032 0.2794)
						)
					)
					(width 0)
					(fill yes)
				)
			)
		)
	)
	(footprint ""
		(layer "B.Cu")
		(at 69.088 -43.815)
		(property "Reference" "Q14"
			(at 0 0 0)
			(layer "B.SilkS")
			(hide yes)
			(effects
				(font
					(size 1.27 1.27)
				)
				(justify mirror)
			)
		)
		(property "Value" "2N7002A-7-GP"
			(at 4.3561 -5.7912 0)
			(unlocked yes)
			(layer "B.Fab")
			(hide yes)
			(effects
				(font
					(size 1.016 1.016)
					(thickness 0.1524)
				)
				(justify mirror)
			)
		)
		(property "Device Type" "SOT23DGS2D4H48"
			(at 4.3561 -7.3152 0)
			(unlocked yes)
			(layer "B.Fab")
			(hide yes)
			(effects
				(font
					(size 1.016 1.016)
					(thickness 0.1524)
				)
				(justify mirror)
			)
		)
		(duplicate_pad_numbers_are_jumpers no)
		(fp_line
			(start -1.7145 -0.4445)
			(end 1.7145 -0.4445)
			(stroke
				(width 0.1524)
				(type default)
			)
			(layer "B.SilkS")
		)
		(fp_line
			(start -1.7145 0.4445)
			(end -1.7145 -0.4445)
			(stroke
				(width 0.1524)
				(type default)
			)
			(layer "B.SilkS")
		)
		(fp_line
			(start 1.7145 -0.4445)
			(end 1.7145 0.4445)
			(stroke
				(width 0.1524)
				(type default)
			)
			(layer "B.SilkS")
		)
		(fp_line
			(start 1.7145 0.4445)
			(end -1.7145 0.4445)
			(stroke
				(width 0.1524)
				(type default)
			)
			(layer "B.SilkS")
		)
		(fp_poly
			(pts
				(xy 1.4224 1.5621) (xy 1.4224 0.9017) (xy 1.7145 0.9017) (xy 1.7145 -0.9017) (xy 0.4699 -0.9017)
				(xy 0.4699 -1.5621) (xy -0.4699 -1.5621) (xy -0.4699 -0.9017) (xy -1.7145 -0.9017) (xy -1.7145 0.9017)
				(xy -1.4224 0.9017) (xy -1.4224 1.5621) (xy -0.4826 1.5621) (xy -0.4826 0.9017) (xy 0.4826 0.9017)
				(xy 0.4826 1.5621)
			)
			(stroke
				(width 0)
				(type default)
			)
			(fill no)
			(layer "B.CrtYd")
		)
		(fp_poly
			(pts
				(xy 1.4224 1.5621) (xy 1.4224 0.9017) (xy 1.7145 0.9017) (xy 1.7145 -0.9017) (xy 0.4699 -0.9017)
				(xy 0.4699 -1.5621) (xy -0.4699 -1.5621) (xy -0.4699 -0.9017) (xy -1.7145 -0.9017) (xy -1.7145 0.9017)
				(xy -1.4224 0.9017) (xy -1.4224 1.5621) (xy -0.4826 1.5621) (xy -0.4826 0.9017) (xy 0.4826 0.9017)
				(xy 0.4826 1.5621)
			)
			(stroke
				(width 0)
				(type default)
			)
			(fill no)
			(layer "B.Fab")
		)
		(pad "D" smd custom
			(at 0 -1.069086 180)
			(size 0.17145 0.17145)
			(layers "B.Cu" "B.Mask" "B.Paste")
			(net "CPU_DIAG_LED_D")
			(options
				(clearance outline)
				(anchor circle)
			)
			(primitives
				(gr_poly
					(pts
						(arc
							(start -0.1397 -0.3683)
							(mid -0.283384 -0.308784)
							(end -0.3429 -0.1651)
						)
						(arc
							(start -0.3429 0.1651)
							(mid -0.283384 0.308784)
							(end -0.1397 0.3683)
						)
						(arc
							(start 0.1397 0.3683)
							(mid 0.283384 0.308784)
							(end 0.3429 0.1651)
						)
						(arc
							(start 0.3429 -0.1651)
							(mid 0.283384 -0.308784)
							(end 0.1397 -0.3683)
						)
					)
					(width 0)
					(fill yes)
				)
			)
		)
		(pad "G" smd custom
			(at 0.94996 1.069086 180)
			(size 0.17145 0.17145)
			(layers "B.Cu" "B.Mask" "B.Paste")
			(net "CPU_DIAG_LED_R")
			(options
				(clearance outline)
				(anchor circle)
			)
			(primitives
				(gr_poly
					(pts
						(arc
							(start -0.1397 -0.3683)
							(mid -0.283384 -0.308784)
							(end -0.3429 -0.1651)
						)
						(arc
							(start -0.3429 0.1651)
							(mid -0.283384 0.308784)
							(end -0.1397 0.3683)
						)
						(arc
							(start 0.1397 0.3683)
							(mid 0.283384 0.308784)
							(end 0.3429 0.1651)
						)
						(arc
							(start 0.3429 -0.1651)
							(mid 0.283384 -0.308784)
							(end 0.1397 -0.3683)
						)
					)
					(width 0)
					(fill yes)
				)
			)
		)
		(pad "S" smd custom
			(at -0.94996 1.069086 180)
			(size 0.17145 0.17145)
			(layers "B.Cu" "B.Mask" "B.Paste")
			(net "GND")
			(options
				(clearance outline)
				(anchor circle)
			)
			(primitives
				(gr_poly
					(pts
						(arc
							(start -0.1397 -0.3683)
							(mid -0.283384 -0.308784)
							(end -0.3429 -0.1651)
						)
						(arc
							(start -0.3429 0.1651)
							(mid -0.283384 0.308784)
							(end -0.1397 0.3683)
						)
						(arc
							(start 0.1397 0.3683)
							(mid 0.283384 0.308784)
							(end 0.3429 0.1651)
						)
						(arc
							(start 0.3429 -0.1651)
							(mid 0.283384 -0.308784)
							(end 0.1397 -0.3683)
						)
					)
					(width 0)
					(fill yes)
				)
			)
		)
	)
	(footprint ""
		(layer "B.Cu")
		(at 45.212 -42.164)
		(property "Reference" "C41"
			(at 0 0 0)
			(layer "B.SilkS")
			(hide yes)
			(effects
				(font
					(size 1.27 1.27)
				)
				(justify mirror)
			)
		)
		(property "Value" "SCD1U10V2KX-5GP"
			(at -1.1811 -2.7051 0)
			(unlocked yes)
			(layer "B.Fab")
			(hide yes)
			(effects
				(font
					(size 1.016 1.016)
					(thickness 0.1524)
				)
				(justify mirror)
			)
		)
		(property "Device Type" "C402H22"
			(at -1.1811 -4.2291 0)
			(unlocked yes)
			(layer "B.Fab")
			(hide yes)
			(effects
				(font
					(size 1.016 1.016)
					(thickness 0.1524)
				)
				(justify mirror)
			)
		)
		(duplicate_pad_numbers_are_jumpers no)
		(fp_rect
			(start 0.381 0.7366)
			(end -0.381 -0.7366)
			(stroke
				(width 0)
				(type default)
			)
			(fill no)
			(layer "B.CrtYd")
		)
		(fp_rect
			(start 0.381 0.7366)
			(end -0.381 -0.7366)
			(stroke
				(width 0)
				(type default)
			)
			(fill no)
			(layer "B.Fab")
		)
		(pad "1" smd custom
			(at 0 -0.4572 180)
			(size 0.1143 0.1143)
			(layers "B.Cu" "B.Mask" "B.Paste")
			(net "P1V5_CLK_VDDDIF")
			(options
				(clearance outline)
				(anchor circle)
			)
			(primitives
				(gr_poly
					(pts
						(arc
							(start -0.254 0.1778)
							(mid -0.239121 0.213721)
							(end -0.2032 0.2286)
						)
						(arc
							(start 0.2032 0.2286)
							(mid 0.239121 0.213721)
							(end 0.254 0.1778)
						)
						(arc
							(start 0.254 -0.1778)
							(mid 0.239121 -0.213721)
							(end 0.2032 -0.2286)
						)
						(arc
							(start -0.2032 -0.2286)
							(mid -0.239121 -0.213721)
							(end -0.254 -0.1778)
						)
					)
					(width 0)
					(fill yes)
				)
			)
		)
		(pad "2" smd custom
			(at 0 0.4572 180)
			(size 0.1143 0.1143)
			(layers "B.Cu" "B.Mask" "B.Paste")
			(net "GND")
			(options
				(clearance outline)
				(anchor circle)
			)
			(primitives
				(gr_poly
					(pts
						(arc
							(start -0.254 0.1778)
							(mid -0.239121 0.213721)
							(end -0.2032 0.2286)
						)
						(arc
							(start 0.2032 0.2286)
							(mid 0.239121 0.213721)
							(end 0.254 0.1778)
						)
						(arc
							(start 0.254 -0.1778)
							(mid 0.239121 -0.213721)
							(end 0.2032 -0.2286)
						)
						(arc
							(start -0.2032 -0.2286)
							(mid -0.239121 -0.213721)
							(end -0.254 -0.1778)
						)
					)
					(width 0)
					(fill yes)
				)
			)
		)
	)
	(footprint ""
		(layer "B.Cu")
		(at 154.559 -53.594 -90)
		(property "Reference" "C358"
			(at 0 0 90)
			(layer "B.SilkS")
			(hide yes)
			(effects
				(font
					(size 1.27 1.27)
				)
				(justify mirror)
			)
		)
		(property "Value" "SCD1U16V2KX-3GP"
			(at -1.8923 -1.2065 270)
			(unlocked yes)
			(layer "B.Fab")
			(hide yes)
			(effects
				(font
					(size 1.016 1.016)
					(thickness 0.1524)
				)
				(justify mirror)
			)
		)
		(property "Device Type" "C402H22"
			(at -1.8923 -2.7305 270)
			(unlocked yes)
			(layer "B.Fab")
			(hide yes)
			(effects
				(font
					(size 1.016 1.016)
					(thickness 0.1524)
				)
				(justify mirror)
			)
		)
		(duplicate_pad_numbers_are_jumpers no)
		(fp_rect
			(start 0.381 0.7366)
			(end -0.381 -0.7366)
			(stroke
				(width 0)
				(type default)
			)
			(fill no)
			(layer "B.CrtYd")
		)
		(fp_rect
			(start 0.381 0.7366)
			(end -0.381 -0.7366)
			(stroke
				(width 0)
				(type default)
			)
			(fill no)
			(layer "B.Fab")
		)
		(pad "1" smd custom
			(at 0 -0.4572 90)
			(size 0.1143 0.1143)
			(layers "B.Cu" "B.Mask" "B.Paste")
			(net "P3V3_STBY")
			(options
				(clearance outline)
				(anchor circle)
			)
			(primitives
				(gr_poly
					(pts
						(arc
							(start -0.254 0.1778)
							(mid -0.239121 0.213721)
							(end -0.2032 0.2286)
						)
						(arc
							(start 0.2032 0.2286)
							(mid 0.239121 0.213721)
							(end 0.254 0.1778)
						)
						(arc
							(start 0.254 -0.1778)
							(mid 0.239121 -0.213721)
							(end 0.2032 -0.2286)
						)
						(arc
							(start -0.2032 -0.2286)
							(mid -0.239121 -0.213721)
							(end -0.254 -0.1778)
						)
					)
					(width 0)
					(fill yes)
				)
			)
		)
		(pad "2" smd custom
			(at 0 0.4572 90)
			(size 0.1143 0.1143)
			(layers "B.Cu" "B.Mask" "B.Paste")
			(net "GND")
			(options
				(clearance outline)
				(anchor circle)
			)
			(primitives
				(gr_poly
					(pts
						(arc
							(start -0.254 0.1778)
							(mid -0.239121 0.213721)
							(end -0.2032 0.2286)
						)
						(arc
							(start 0.2032 0.2286)
							(mid 0.239121 0.213721)
							(end 0.254 0.1778)
						)
						(arc
							(start 0.254 -0.1778)
							(mid 0.239121 -0.213721)
							(end 0.2032 -0.2286)
						)
						(arc
							(start -0.2032 -0.2286)
							(mid -0.239121 -0.213721)
							(end -0.254 -0.1778)
						)
					)
					(width 0)
					(fill yes)
				)
			)
		)
	)
	(footprint ""
		(layer "B.Cu")
		(at 44.196 -42.291)
		(property "Reference" "C43"
			(at 0 0 0)
			(layer "B.SilkS")
			(hide yes)
			(effects
				(font
					(size 1.27 1.27)
				)
				(justify mirror)
			)
		)
		(property "Value" "SC10U6D3V3MX-GP"
			(at 0 -2.8194 0)
			(unlocked yes)
			(layer "B.Fab")
			(hide yes)
			(effects
				(font
					(size 1.016 1.016)
					(thickness 0.1524)
				)
				(justify mirror)
			)
		)
		(property "Device Type" "C603H38"
			(at 0 -4.3434 0)
			(unlocked yes)
			(layer "B.Fab")
			(hide yes)
			(effects
				(font
					(size 1.016 1.016)
					(thickness 0.1524)
				)
				(justify mirror)
			)
		)
		(duplicate_pad_numbers_are_jumpers no)
		(fp_line
			(start 0.4064 0)
			(end -0.4064 0)
			(stroke
				(width 0.2286)
				(type default)
			)
			(layer "B.SilkS")
		)
		(fp_rect
			(start 0.635 1.1811)
			(end -0.635 -1.1811)
			(stroke
				(width 0)
				(type default)
			)
			(fill no)
			(layer "B.CrtYd")
		)
		(fp_rect
			(start 0.635 1.1811)
			(end -0.635 -1.1811)
			(stroke
				(width 0)
				(type default)
			)
			(fill no)
			(layer "B.Fab")
		)
		(pad "1" smd custom
			(at 0 -0.6604 180)
			(size 0.19685 0.19685)
			(layers "B.Cu" "B.Mask" "B.Paste")
			(net "P1V5_CLK_VDDDIF")
			(options
				(clearance outline)
				(anchor circle)
			)
			(primitives
				(gr_poly
					(pts
						(arc
							(start 0.508 0.2921)
							(mid 0.478242 0.363942)
							(end 0.4064 0.3937)
						)
						(arc
							(start -0.4064 0.3937)
							(mid -0.478242 0.363942)
							(end -0.508 0.2921)
						)
						(arc
							(start -0.508 -0.2921)
							(mid -0.478242 -0.363942)
							(end -0.4064 -0.3937)
						)
						(arc
							(start 0.4064 -0.3937)
							(mid 0.478242 -0.363942)
							(end 0.508 -0.2921)
						)
					)
					(width 0)
					(fill yes)
				)
			)
		)
		(pad "2" smd custom
			(at 0 0.6604 180)
			(size 0.19685 0.19685)
			(layers "B.Cu" "B.Mask" "B.Paste")
			(net "GND")
			(options
				(clearance outline)
				(anchor circle)
			)
			(primitives
				(gr_poly
					(pts
						(arc
							(start 0.508 0.2921)
							(mid 0.478242 0.363942)
							(end 0.4064 0.3937)
						)
						(arc
							(start -0.4064 0.3937)
							(mid -0.478242 0.363942)
							(end -0.508 0.2921)
						)
						(arc
							(start -0.508 -0.2921)
							(mid -0.478242 -0.363942)
							(end -0.4064 -0.3937)
						)
						(arc
							(start 0.4064 -0.3937)
							(mid 0.478242 -0.363942)
							(end 0.508 -0.2921)
						)
					)
					(width 0)
					(fill yes)
				)
			)
		)
	)
	(footprint ""
		(layer "B.Cu")
		(at 49.657 -29.2608 90)
		(property "Reference" "R361"
			(at 0 0 90)
			(layer "B.SilkS")
			(hide yes)
			(effects
				(font
					(size 1.27 1.27)
				)
				(justify mirror)
			)
		)
		(property "Value" "2D2R3J-2-GP"
			(at 0.0254 -2.5146 90)
			(unlocked yes)
			(layer "B.Fab")
			(hide yes)
			(effects
				(font
					(size 1.016 1.016)
					(thickness 0.1524)
				)
				(justify mirror)
			)
		)
		(property "Device Type" "R603H22"
			(at 0.0254 -4.0386 90)
			(unlocked yes)
			(layer "B.Fab")
			(hide yes)
			(effects
				(font
					(size 1.016 1.016)
					(thickness 0.1524)
				)
				(justify mirror)
			)
		)
		(duplicate_pad_numbers_are_jumpers no)
		(fp_line
			(start 0.2032 0)
			(end 0.4191 0)
			(stroke
				(width 0.2032)
				(type default)
			)
			(layer "B.SilkS")
		)
		(fp_line
			(start -0.4318 0)
			(end -0.2032 0)
			(stroke
				(width 0.2032)
				(type default)
			)
			(layer "B.SilkS")
		)
		(fp_rect
			(start 0.635 1.1811)
			(end -0.635 -1.1811)
			(stroke
				(width 0)
				(type default)
			)
			(fill no)
			(layer "B.CrtYd")
		)
		(fp_rect
			(start 0.635 1.1811)
			(end -0.635 -1.1811)
			(stroke
				(width 0)
				(type default)
			)
			(fill no)
			(layer "B.Fab")
		)
		(pad "1" smd custom
			(at 0 -0.6604 270)
			(size 0.19685 0.19685)
			(layers "B.Cu" "B.Mask" "B.Paste")
			(net "P3V3_VDDA_CLKBUFF_R")
			(options
				(clearance outline)
				(anchor circle)
			)
			(primitives
				(gr_poly
					(pts
						(arc
							(start 0.508 0.2921)
							(mid 0.478242 0.363942)
							(end 0.4064 0.3937)
						)
						(arc
							(start -0.4064 0.3937)
							(mid -0.478242 0.363942)
							(end -0.508 0.2921)
						)
						(arc
							(start -0.508 -0.2921)
							(mid -0.478242 -0.363942)
							(end -0.4064 -0.3937)
						)
						(arc
							(start 0.4064 -0.3937)
							(mid 0.478242 -0.363942)
							(end 0.508 -0.2921)
						)
					)
					(width 0)
					(fill yes)
				)
			)
		)
		(pad "2" smd custom
			(at 0 0.6604 270)
			(size 0.19685 0.19685)
			(layers "B.Cu" "B.Mask" "B.Paste")
			(net "P3V3_VDDA_CLKBUFF")
			(options
				(clearance outline)
				(anchor circle)
			)
			(primitives
				(gr_poly
					(pts
						(arc
							(start 0.508 0.2921)
							(mid 0.478242 0.363942)
							(end 0.4064 0.3937)
						)
						(arc
							(start -0.4064 0.3937)
							(mid -0.478242 0.363942)
							(end -0.508 0.2921)
						)
						(arc
							(start -0.508 -0.2921)
							(mid -0.478242 -0.363942)
							(end -0.4064 -0.3937)
						)
						(arc
							(start 0.4064 -0.3937)
							(mid 0.478242 -0.363942)
							(end 0.508 -0.2921)
						)
					)
					(width 0)
					(fill yes)
				)
			)
		)
	)
	(footprint ""
		(layer "B.Cu")
		(at 68.834 -13.589)
		(property "Reference" "C280"
			(at 0 0 0)
			(layer "B.SilkS")
			(hide yes)
			(effects
				(font
					(size 1.27 1.27)
				)
				(justify mirror)
			)
		)
		(property "Value" "SCD1U16V2KX-3GP"
			(at -1.1811 -2.7051 0)
			(unlocked yes)
			(layer "B.Fab")
			(hide yes)
			(effects
				(font
					(size 1.016 1.016)
					(thickness 0.1524)
				)
				(justify mirror)
			)
		)
		(property "Device Type" "C402H22"
			(at -1.1811 -4.2291 0)
			(unlocked yes)
			(layer "B.Fab")
			(hide yes)
			(effects
				(font
					(size 1.016 1.016)
					(thickness 0.1524)
				)
				(justify mirror)
			)
		)
		(duplicate_pad_numbers_are_jumpers no)
		(fp_rect
			(start 0.381 0.7366)
			(end -0.381 -0.7366)
			(stroke
				(width 0)
				(type default)
			)
			(fill no)
			(layer "B.CrtYd")
		)
		(fp_rect
			(start 0.381 0.7366)
			(end -0.381 -0.7366)
			(stroke
				(width 0)
				(type default)
			)
			(fill no)
			(layer "B.Fab")
		)
		(pad "1" smd custom
			(at 0 -0.4572 180)
			(size 0.1143 0.1143)
			(layers "B.Cu" "B.Mask" "B.Paste")
			(net "P2E_CPU_SAS_C_TX_DP3")
			(options
				(clearance outline)
				(anchor circle)
			)
			(primitives
				(gr_poly
					(pts
						(arc
							(start -0.254 0.1778)
							(mid -0.239121 0.213721)
							(end -0.2032 0.2286)
						)
						(arc
							(start 0.2032 0.2286)
							(mid 0.239121 0.213721)
							(end 0.254 0.1778)
						)
						(arc
							(start 0.254 -0.1778)
							(mid 0.239121 -0.213721)
							(end 0.2032 -0.2286)
						)
						(arc
							(start -0.2032 -0.2286)
							(mid -0.239121 -0.213721)
							(end -0.254 -0.1778)
						)
					)
					(width 0)
					(fill yes)
				)
			)
		)
		(pad "2" smd custom
			(at 0 0.4572 180)
			(size 0.1143 0.1143)
			(layers "B.Cu" "B.Mask" "B.Paste")
			(net "P2E_CPU_SAS_TX_DP3")
			(options
				(clearance outline)
				(anchor circle)
			)
			(primitives
				(gr_poly
					(pts
						(arc
							(start -0.254 0.1778)
							(mid -0.239121 0.213721)
							(end -0.2032 0.2286)
						)
						(arc
							(start 0.2032 0.2286)
							(mid 0.239121 0.213721)
							(end 0.254 0.1778)
						)
						(arc
							(start 0.254 -0.1778)
							(mid 0.239121 -0.213721)
							(end 0.2032 -0.2286)
						)
						(arc
							(start -0.2032 -0.2286)
							(mid -0.239121 -0.213721)
							(end -0.254 -0.1778)
						)
					)
					(width 0)
					(fill yes)
				)
			)
		)
	)
	(footprint ""
		(layer "B.Cu")
		(at 51.943 -17.018)
		(property "Reference" "C209"
			(at 0 0 0)
			(layer "B.SilkS")
			(hide yes)
			(effects
				(font
					(size 1.27 1.27)
				)
				(justify mirror)
			)
		)
		(property "Value" "SCD1U10V2KX-5GP"
			(at -1.1811 -2.7051 0)
			(unlocked yes)
			(layer "B.Fab")
			(hide yes)
			(effects
				(font
					(size 1.016 1.016)
					(thickness 0.1524)
				)
				(justify mirror)
			)
		)
		(property "Device Type" "C402H22"
			(at -1.1811 -4.2291 0)
			(unlocked yes)
			(layer "B.Fab")
			(hide yes)
			(effects
				(font
					(size 1.016 1.016)
					(thickness 0.1524)
				)
				(justify mirror)
			)
		)
		(duplicate_pad_numbers_are_jumpers no)
		(fp_rect
			(start 0.381 0.7366)
			(end -0.381 -0.7366)
			(stroke
				(width 0)
				(type default)
			)
			(fill no)
			(layer "B.CrtYd")
		)
		(fp_rect
			(start 0.381 0.7366)
			(end -0.381 -0.7366)
			(stroke
				(width 0)
				(type default)
			)
			(fill no)
			(layer "B.Fab")
		)
		(pad "1" smd custom
			(at 0 -0.4572 180)
			(size 0.1143 0.1143)
			(layers "B.Cu" "B.Mask" "B.Paste")
			(net "P3V3_VDDA_CLKBUFF")
			(options
				(clearance outline)
				(anchor circle)
			)
			(primitives
				(gr_poly
					(pts
						(arc
							(start -0.254 0.1778)
							(mid -0.239121 0.213721)
							(end -0.2032 0.2286)
						)
						(arc
							(start 0.2032 0.2286)
							(mid 0.239121 0.213721)
							(end 0.254 0.1778)
						)
						(arc
							(start 0.254 -0.1778)
							(mid 0.239121 -0.213721)
							(end 0.2032 -0.2286)
						)
						(arc
							(start -0.2032 -0.2286)
							(mid -0.239121 -0.213721)
							(end -0.254 -0.1778)
						)
					)
					(width 0)
					(fill yes)
				)
			)
		)
		(pad "2" smd custom
			(at 0 0.4572 180)
			(size 0.1143 0.1143)
			(layers "B.Cu" "B.Mask" "B.Paste")
			(net "GND")
			(options
				(clearance outline)
				(anchor circle)
			)
			(primitives
				(gr_poly
					(pts
						(arc
							(start -0.254 0.1778)
							(mid -0.239121 0.213721)
							(end -0.2032 0.2286)
						)
						(arc
							(start 0.2032 0.2286)
							(mid 0.239121 0.213721)
							(end 0.254 0.1778)
						)
						(arc
							(start 0.254 -0.1778)
							(mid 0.239121 -0.213721)
							(end 0.2032 -0.2286)
						)
						(arc
							(start -0.2032 -0.2286)
							(mid -0.239121 -0.213721)
							(end -0.254 -0.1778)
						)
					)
					(width 0)
					(fill yes)
				)
			)
		)
	)
	(footprint ""
		(layer "B.Cu")
		(at 91.948 -62.738 -90)
		(property "Reference" "PC7"
			(at 0 0 90)
			(layer "B.SilkS")
			(hide yes)
			(effects
				(font
					(size 1.27 1.27)
				)
				(justify mirror)
			)
		)
		(property "Value" "SC47U6D3V5MX-1-GP"
			(at 0 -4.9022 270)
			(unlocked yes)
			(layer "B.Fab")
			(hide yes)
			(effects
				(font
					(size 1.016 1.016)
					(thickness 0.1524)
				)
				(justify mirror)
			)
		)
		(property "Device Type" "C805H54"
			(at 0 -6.8072 270)
			(unlocked yes)
			(layer "B.Fab")
			(hide yes)
			(effects
				(font
					(size 1.016 1.016)
					(thickness 0.1524)
				)
				(justify mirror)
			)
		)
		(duplicate_pad_numbers_are_jumpers no)
		(fp_line
			(start -0.6096 0)
			(end 0.6096 0)
			(stroke
				(width 0.3048)
				(type default)
			)
			(layer "B.SilkS")
		)
		(fp_poly
			(pts
				(xy 0.9017 1.4351) (xy -0.9017 1.4351) (xy -0.9017 -1.4351) (xy 0.9017 -1.4351)
			)
			(stroke
				(width 0)
				(type default)
			)
			(fill no)
			(layer "B.CrtYd")
		)
		(fp_poly
			(pts
				(xy -0.9017 1.4351) (xy -0.9017 -1.4351) (xy 0.9017 -1.4351) (xy 0.9017 1.4351)
			)
			(stroke
				(width 0)
				(type default)
			)
			(fill no)
			(layer "B.Fab")
		)
		(pad "1" smd rect
			(at 0 -0.8382 90)
			(size 1.5494 0.9398)
			(layers "B.Cu" "B.Mask" "B.Paste")
			(net "P1V1")
		)
		(pad "2" smd rect
			(at 0 0.8382 90)
			(size 1.5494 0.9398)
			(layers "B.Cu" "B.Mask" "B.Paste")
			(net "GND")
		)
	)
	(footprint ""
		(layer "B.Cu")
		(at 20.447 -27.94 90)
		(property "Reference" "PR86"
			(at 0 0 90)
			(layer "B.SilkS")
			(hide yes)
			(effects
				(font
					(size 1.27 1.27)
				)
				(justify mirror)
			)
		)
		(property "Value" "2K21R2F-GP"
			(at -1.7907 -1.1176 90)
			(unlocked yes)
			(layer "B.Fab")
			(hide yes)
			(effects
				(font
					(size 1.016 1.016)
					(thickness 0.1524)
				)
				(justify mirror)
			)
		)
		(property "Device Type" "R402H16"
			(at -1.7907 -2.6416 90)
			(unlocked yes)
			(layer "B.Fab")
			(hide yes)
			(effects
				(font
					(size 1.016 1.016)
					(thickness 0.1524)
				)
				(justify mirror)
			)
		)
		(duplicate_pad_numbers_are_jumpers no)
		(fp_rect
			(start 0.381 0.8382)
			(end -0.381 -0.8382)
			(stroke
				(width 0)
				(type default)
			)
			(fill no)
			(layer "B.CrtYd")
		)
		(fp_rect
			(start 0.381 0.8382)
			(end -0.381 -0.8382)
			(stroke
				(width 0)
				(type default)
			)
			(fill no)
			(layer "B.Fab")
		)
		(pad "1" smd custom
			(at 0 -0.4318 270)
			(size 0.127 0.127)
			(layers "B.Cu" "B.Mask" "B.Paste")
			(net "P1V0_LX")
			(options
				(clearance outline)
				(anchor circle)
			)
			(primitives
				(gr_poly
					(pts
						(arc
							(start -0.2032 0.2794)
							(mid -0.239121 0.264521)
							(end -0.254 0.2286)
						)
						(arc
							(start -0.254 -0.2286)
							(mid -0.239121 -0.264521)
							(end -0.2032 -0.2794)
						)
						(arc
							(start 0.2032 -0.2794)
							(mid 0.239121 -0.264521)
							(end 0.254 -0.2286)
						)
						(arc
							(start 0.254 0.2286)
							(mid 0.239121 0.264521)
							(end 0.2032 0.2794)
						)
					)
					(width 0)
					(fill yes)
				)
			)
		)
		(pad "2" smd custom
			(at 0 0.4318 270)
			(size 0.127 0.127)
			(layers "B.Cu" "B.Mask" "B.Paste")
			(net "P1V0_SW_R")
			(options
				(clearance outline)
				(anchor circle)
			)
			(primitives
				(gr_poly
					(pts
						(arc
							(start -0.2032 0.2794)
							(mid -0.239121 0.264521)
							(end -0.254 0.2286)
						)
						(arc
							(start -0.254 -0.2286)
							(mid -0.239121 -0.264521)
							(end -0.2032 -0.2794)
						)
						(arc
							(start 0.2032 -0.2794)
							(mid 0.239121 -0.264521)
							(end 0.254 -0.2286)
						)
						(arc
							(start 0.254 0.2286)
							(mid 0.239121 0.264521)
							(end 0.2032 0.2794)
						)
					)
					(width 0)
					(fill yes)
				)
			)
		)
	)
	(footprint ""
		(layer "B.Cu")
		(at 187.5282 -31.7246 180)
		(property "Reference" "PR144"
			(at 0 0 0)
			(layer "B.SilkS")
			(hide yes)
			(effects
				(font
					(size 1.27 1.27)
				)
				(justify mirror)
			)
		)
		(property "Value" "20KR2F-L-GP"
			(at -1.7907 -1.1176 180)
			(unlocked yes)
			(layer "B.Fab")
			(hide yes)
			(effects
				(font
					(size 1.016 1.016)
					(thickness 0.1524)
				)
				(justify mirror)
			)
		)
		(property "Device Type" "R402H16"
			(at -1.7907 -2.6416 180)
			(unlocked yes)
			(layer "B.Fab")
			(hide yes)
			(effects
				(font
					(size 1.016 1.016)
					(thickness 0.1524)
				)
				(justify mirror)
			)
		)
		(duplicate_pad_numbers_are_jumpers no)
		(fp_rect
			(start 0.381 0.8382)
			(end -0.381 -0.8382)
			(stroke
				(width 0)
				(type default)
			)
			(fill no)
			(layer "B.CrtYd")
		)
		(fp_rect
			(start 0.381 0.8382)
			(end -0.381 -0.8382)
			(stroke
				(width 0)
				(type default)
			)
			(fill no)
			(layer "B.Fab")
		)
		(pad "1" smd custom
			(at 0 -0.4318)
			(size 0.127 0.127)
			(layers "B.Cu" "B.Mask" "B.Paste")
			(net "VR_PVDDR_A_NTC_R")
			(options
				(clearance outline)
				(anchor circle)
			)
			(primitives
				(gr_poly
					(pts
						(arc
							(start -0.2032 0.2794)
							(mid -0.239121 0.264521)
							(end -0.254 0.2286)
						)
						(arc
							(start -0.254 -0.2286)
							(mid -0.239121 -0.264521)
							(end -0.2032 -0.2794)
						)
						(arc
							(start 0.2032 -0.2794)
							(mid 0.239121 -0.264521)
							(end 0.254 -0.2286)
						)
						(arc
							(start 0.254 0.2286)
							(mid 0.239121 0.264521)
							(end 0.2032 0.2794)
						)
					)
					(width 0)
					(fill yes)
				)
			)
		)
		(pad "2" smd custom
			(at 0 0.4318)
			(size 0.127 0.127)
			(layers "B.Cu" "B.Mask" "B.Paste")
			(net "GND")
			(options
				(clearance outline)
				(anchor circle)
			)
			(primitives
				(gr_poly
					(pts
						(arc
							(start -0.2032 0.2794)
							(mid -0.239121 0.264521)
							(end -0.254 0.2286)
						)
						(arc
							(start -0.254 -0.2286)
							(mid -0.239121 -0.264521)
							(end -0.2032 -0.2794)
						)
						(arc
							(start 0.2032 -0.2794)
							(mid 0.239121 -0.264521)
							(end 0.254 -0.2286)
						)
						(arc
							(start 0.254 0.2286)
							(mid 0.239121 0.264521)
							(end 0.2032 0.2794)
						)
					)
					(width 0)
					(fill yes)
				)
			)
		)
	)
	(footprint ""
		(layer "B.Cu")
		(at 96.4438 -39.9923 -90)
		(property "Reference" "TP26"
			(at 0 0 90)
			(layer "B.SilkS")
			(hide yes)
			(effects
				(font
					(size 1.27 1.27)
				)
				(justify mirror)
			)
		)
		(property "Value" "TPAD24"
			(at 0 -2.9972 270)
			(unlocked yes)
			(layer "B.Fab")
			(hide yes)
			(effects
				(font
					(size 1.016 1.016)
					(thickness 0.1524)
				)
				(justify mirror)
			)
		)
		(property "Device Type" "TPAD24"
			(at 0 -4.5212 270)
			(unlocked yes)
			(layer "B.Fab")
			(hide yes)
			(effects
				(font
					(size 1.016 1.016)
					(thickness 0.1524)
				)
				(justify mirror)
			)
		)
		(duplicate_pad_numbers_are_jumpers no)
		(fp_poly
			(pts
				(arc
					(start 0 -0.3048)
					(mid 0 0.3048)
					(end 0 -0.3048)
				)
			)
			(stroke
				(width 0)
				(type default)
			)
			(fill no)
			(layer "B.CrtYd")
		)
		(fp_poly
			(pts
				(arc
					(start 0 -0.6096)
					(mid 0 0.6096)
					(end 0 -0.6096)
				)
			)
			(stroke
				(width 0)
				(type default)
			)
			(fill no)
			(layer "B.Fab")
		)
		(pad "1" smd circle
			(at 0 0 90)
			(size 0.6096 0.6096)
			(layers "B.Cu" "B.Mask" "B.Paste")
			(net "VCCCORE7VIDSI0GT_1P03")
		)
	)
	(footprint ""
		(layer "B.Cu")
		(at 70.739 -26.8732 180)
		(property "Reference" "R344"
			(at 0 0 0)
			(layer "B.SilkS")
			(hide yes)
			(effects
				(font
					(size 1.27 1.27)
				)
				(justify mirror)
			)
		)
		(property "Value" "10KR2F-2-GP"
			(at -0.064008 -3.993896 180)
			(unlocked yes)
			(layer "B.Fab")
			(hide yes)
			(effects
				(font
					(size 1.016 1.016)
					(thickness 0.1524)
				)
				(justify mirror)
			)
		)
		(property "Device Type" "R402H16"
			(at -0.064008 -5.517896 180)
			(unlocked yes)
			(layer "B.Fab")
			(hide yes)
			(effects
				(font
					(size 1.016 1.016)
					(thickness 0.1524)
				)
				(justify mirror)
			)
		)
		(duplicate_pad_numbers_are_jumpers no)
		(fp_rect
			(start 0.381 0.8382)
			(end -0.381 -0.8382)
			(stroke
				(width 0)
				(type default)
			)
			(fill no)
			(layer "B.CrtYd")
		)
		(fp_rect
			(start 0.381 0.8382)
			(end -0.381 -0.8382)
			(stroke
				(width 0)
				(type default)
			)
			(fill no)
			(layer "B.Fab")
		)
		(pad "1" smd custom
			(at 0 -0.4318)
			(size 0.127 0.127)
			(layers "B.Cu" "B.Mask" "B.Paste")
			(net "P3V3_CPU")
			(options
				(clearance outline)
				(anchor circle)
			)
			(primitives
				(gr_poly
					(pts
						(arc
							(start -0.2032 0.2794)
							(mid -0.239121 0.264521)
							(end -0.254 0.2286)
						)
						(arc
							(start -0.254 -0.2286)
							(mid -0.239121 -0.264521)
							(end -0.2032 -0.2794)
						)
						(arc
							(start 0.2032 -0.2794)
							(mid 0.239121 -0.264521)
							(end 0.254 -0.2286)
						)
						(arc
							(start 0.254 0.2286)
							(mid 0.239121 0.264521)
							(end 0.2032 0.2794)
						)
					)
					(width 0)
					(fill yes)
				)
			)
		)
		(pad "2" smd custom
			(at 0 0.4318)
			(size 0.127 0.127)
			(layers "B.Cu" "B.Mask" "B.Paste")
			(net "GBE_SDP0")
			(options
				(clearance outline)
				(anchor circle)
			)
			(primitives
				(gr_poly
					(pts
						(arc
							(start -0.2032 0.2794)
							(mid -0.239121 0.264521)
							(end -0.254 0.2286)
						)
						(arc
							(start -0.254 -0.2286)
							(mid -0.239121 -0.264521)
							(end -0.2032 -0.2794)
						)
						(arc
							(start 0.2032 -0.2794)
							(mid 0.239121 -0.264521)
							(end 0.254 -0.2286)
						)
						(arc
							(start 0.254 0.2286)
							(mid 0.239121 0.264521)
							(end 0.2032 0.2794)
						)
					)
					(width 0)
					(fill yes)
				)
			)
		)
	)
	(footprint ""
		(layer "B.Cu")
		(at 89.916 -16.383)
		(property "Reference" "C253"
			(at 0 0 0)
			(layer "B.SilkS")
			(hide yes)
			(effects
				(font
					(size 1.27 1.27)
				)
				(justify mirror)
			)
		)
		(property "Value" "SC1U10V2KX-1GP"
			(at -1.1811 -2.7051 0)
			(unlocked yes)
			(layer "B.Fab")
			(hide yes)
			(effects
				(font
					(size 1.016 1.016)
					(thickness 0.1524)
				)
				(justify mirror)
			)
		)
		(property "Device Type" "C402H22"
			(at -1.1811 -4.2291 0)
			(unlocked yes)
			(layer "B.Fab")
			(hide yes)
			(effects
				(font
					(size 1.016 1.016)
					(thickness 0.1524)
				)
				(justify mirror)
			)
		)
		(duplicate_pad_numbers_are_jumpers no)
		(fp_rect
			(start 0.381 0.7366)
			(end -0.381 -0.7366)
			(stroke
				(width 0)
				(type default)
			)
			(fill no)
			(layer "B.CrtYd")
		)
		(fp_rect
			(start 0.381 0.7366)
			(end -0.381 -0.7366)
			(stroke
				(width 0)
				(type default)
			)
			(fill no)
			(layer "B.Fab")
		)
		(pad "1" smd custom
			(at 0 -0.4572 180)
			(size 0.1143 0.1143)
			(layers "B.Cu" "B.Mask" "B.Paste")
			(net "P1V0")
			(options
				(clearance outline)
				(anchor circle)
			)
			(primitives
				(gr_poly
					(pts
						(arc
							(start -0.254 0.1778)
							(mid -0.239121 0.213721)
							(end -0.2032 0.2286)
						)
						(arc
							(start 0.2032 0.2286)
							(mid 0.239121 0.213721)
							(end 0.254 0.1778)
						)
						(arc
							(start 0.254 -0.1778)
							(mid 0.239121 -0.213721)
							(end 0.2032 -0.2286)
						)
						(arc
							(start -0.2032 -0.2286)
							(mid -0.239121 -0.213721)
							(end -0.254 -0.1778)
						)
					)
					(width 0)
					(fill yes)
				)
			)
		)
		(pad "2" smd custom
			(at 0 0.4572 180)
			(size 0.1143 0.1143)
			(layers "B.Cu" "B.Mask" "B.Paste")
			(net "GND")
			(options
				(clearance outline)
				(anchor circle)
			)
			(primitives
				(gr_poly
					(pts
						(arc
							(start -0.254 0.1778)
							(mid -0.239121 0.213721)
							(end -0.2032 0.2286)
						)
						(arc
							(start 0.2032 0.2286)
							(mid 0.239121 0.213721)
							(end 0.254 0.1778)
						)
						(arc
							(start 0.254 -0.1778)
							(mid 0.239121 -0.213721)
							(end 0.2032 -0.2286)
						)
						(arc
							(start -0.2032 -0.2286)
							(mid -0.239121 -0.213721)
							(end -0.254 -0.1778)
						)
					)
					(width 0)
					(fill yes)
				)
			)
		)
	)
	(footprint ""
		(layer "B.Cu")
		(at 96.012 -19.685 90)
		(property "Reference" "C252"
			(at 0 0 90)
			(layer "B.SilkS")
			(hide yes)
			(effects
				(font
					(size 1.27 1.27)
				)
				(justify mirror)
			)
		)
		(property "Value" "SC1U10V2KX-1GP"
			(at -1.1811 -2.7051 90)
			(unlocked yes)
			(layer "B.Fab")
			(hide yes)
			(effects
				(font
					(size 1.016 1.016)
					(thickness 0.1524)
				)
				(justify mirror)
			)
		)
		(property "Device Type" "C402H22"
			(at -1.1811 -4.2291 90)
			(unlocked yes)
			(layer "B.Fab")
			(hide yes)
			(effects
				(font
					(size 1.016 1.016)
					(thickness 0.1524)
				)
				(justify mirror)
			)
		)
		(duplicate_pad_numbers_are_jumpers no)
		(fp_rect
			(start 0.381 0.7366)
			(end -0.381 -0.7366)
			(stroke
				(width 0)
				(type default)
			)
			(fill no)
			(layer "B.CrtYd")
		)
		(fp_rect
			(start 0.381 0.7366)
			(end -0.381 -0.7366)
			(stroke
				(width 0)
				(type default)
			)
			(fill no)
			(layer "B.Fab")
		)
		(pad "1" smd custom
			(at 0 -0.4572 270)
			(size 0.1143 0.1143)
			(layers "B.Cu" "B.Mask" "B.Paste")
			(net "VCCA_PLLDDR1_AVN")
			(options
				(clearance outline)
				(anchor circle)
			)
			(primitives
				(gr_poly
					(pts
						(arc
							(start -0.254 0.1778)
							(mid -0.239121 0.213721)
							(end -0.2032 0.2286)
						)
						(arc
							(start 0.2032 0.2286)
							(mid 0.239121 0.213721)
							(end 0.254 0.1778)
						)
						(arc
							(start 0.254 -0.1778)
							(mid 0.239121 -0.213721)
							(end 0.2032 -0.2286)
						)
						(arc
							(start -0.2032 -0.2286)
							(mid -0.239121 -0.213721)
							(end -0.254 -0.1778)
						)
					)
					(width 0)
					(fill yes)
				)
			)
		)
		(pad "2" smd custom
			(at 0 0.4572 270)
			(size 0.1143 0.1143)
			(layers "B.Cu" "B.Mask" "B.Paste")
			(net "GND")
			(options
				(clearance outline)
				(anchor circle)
			)
			(primitives
				(gr_poly
					(pts
						(arc
							(start -0.254 0.1778)
							(mid -0.239121 0.213721)
							(end -0.2032 0.2286)
						)
						(arc
							(start 0.2032 0.2286)
							(mid 0.239121 0.213721)
							(end 0.254 0.1778)
						)
						(arc
							(start 0.254 -0.1778)
							(mid 0.239121 -0.213721)
							(end 0.2032 -0.2286)
						)
						(arc
							(start -0.2032 -0.2286)
							(mid -0.239121 -0.213721)
							(end -0.254 -0.1778)
						)
					)
					(width 0)
					(fill yes)
				)
			)
		)
	)
	(footprint ""
		(layer "B.Cu")
		(at 40.005 -40.005 90)
		(property "Reference" "L13"
			(at 0 0 90)
			(layer "B.SilkS")
			(hide yes)
			(effects
				(font
					(size 1.27 1.27)
				)
				(justify mirror)
			)
		)
		(property "Value" "BLM18PG330SN1D-GP"
			(at 0.0254 -2.0193 90)
			(unlocked yes)
			(layer "B.Fab")
			(hide yes)
			(effects
				(font
					(size 1.016 1.016)
					(thickness 0.1524)
				)
				(justify mirror)
			)
		)
		(property "Device Type" "L1608-UH38"
			(at 0.0254 -3.5433 90)
			(unlocked yes)
			(layer "B.Fab")
			(hide yes)
			(effects
				(font
					(size 1.016 1.016)
					(thickness 0.1524)
				)
				(justify mirror)
			)
		)
		(duplicate_pad_numbers_are_jumpers no)
		(fp_line
			(start 0.4064 0)
			(end -0.4064 0)
			(stroke
				(width 0.2032)
				(type default)
			)
			(layer "B.SilkS")
		)
		(fp_rect
			(start 0.635 1.1811)
			(end -0.635 -1.1811)
			(stroke
				(width 0)
				(type default)
			)
			(fill no)
			(layer "B.CrtYd")
		)
		(fp_rect
			(start 0.635 1.1811)
			(end -0.635 -1.1811)
			(stroke
				(width 0)
				(type default)
			)
			(fill no)
			(layer "B.Fab")
		)
		(pad "1" smd custom
			(at 0 -0.6604 270)
			(size 0.19685 0.19685)
			(layers "B.Cu" "B.Mask" "B.Paste")
			(net "P1V5_STBY")
			(options
				(clearance outline)
				(anchor circle)
			)
			(primitives
				(gr_poly
					(pts
						(arc
							(start 0.508 0.2921)
							(mid 0.478242 0.363942)
							(end 0.4064 0.3937)
						)
						(arc
							(start -0.4064 0.3937)
							(mid -0.478242 0.363942)
							(end -0.508 0.2921)
						)
						(arc
							(start -0.508 -0.2921)
							(mid -0.478242 -0.363942)
							(end -0.4064 -0.3937)
						)
						(arc
							(start 0.4064 -0.3937)
							(mid 0.478242 -0.363942)
							(end 0.508 -0.2921)
						)
					)
					(width 0)
					(fill yes)
				)
			)
		)
		(pad "2" smd custom
			(at 0 0.6604 270)
			(size 0.19685 0.19685)
			(layers "B.Cu" "B.Mask" "B.Paste")
			(net "P1V5_CLK_VDDDIF")
			(options
				(clearance outline)
				(anchor circle)
			)
			(primitives
				(gr_poly
					(pts
						(arc
							(start 0.508 0.2921)
							(mid 0.478242 0.363942)
							(end 0.4064 0.3937)
						)
						(arc
							(start -0.4064 0.3937)
							(mid -0.478242 0.363942)
							(end -0.508 0.2921)
						)
						(arc
							(start -0.508 -0.2921)
							(mid -0.478242 -0.363942)
							(end -0.4064 -0.3937)
						)
						(arc
							(start 0.4064 -0.3937)
							(mid 0.478242 -0.363942)
							(end 0.508 -0.2921)
						)
					)
					(width 0)
					(fill yes)
				)
			)
		)
	)
	(footprint ""
		(layer "B.Cu")
		(at 103.124 -67.31)
		(property "Reference" "PC4"
			(at 0 0 0)
			(layer "B.SilkS")
			(hide yes)
			(effects
				(font
					(size 1.27 1.27)
				)
				(justify mirror)
			)
		)
		(property "Value" "SC15P50V2GN-GP"
			(at -1.1811 -2.7051 0)
			(unlocked yes)
			(layer "B.Fab")
			(hide yes)
			(effects
				(font
					(size 1.016 1.016)
					(thickness 0.1524)
				)
				(justify mirror)
			)
		)
		(property "Device Type" "C402H22"
			(at -1.1811 -4.2291 0)
			(unlocked yes)
			(layer "B.Fab")
			(hide yes)
			(effects
				(font
					(size 1.016 1.016)
					(thickness 0.1524)
				)
				(justify mirror)
			)
		)
		(duplicate_pad_numbers_are_jumpers no)
		(fp_rect
			(start 0.381 0.7366)
			(end -0.381 -0.7366)
			(stroke
				(width 0)
				(type default)
			)
			(fill no)
			(layer "B.CrtYd")
		)
		(fp_rect
			(start 0.381 0.7366)
			(end -0.381 -0.7366)
			(stroke
				(width 0)
				(type default)
			)
			(fill no)
			(layer "B.Fab")
		)
		(pad "1" smd custom
			(at 0 -0.4572 180)
			(size 0.1143 0.1143)
			(layers "B.Cu" "B.Mask" "B.Paste")
			(net "VR_P1V1_VFBR")
			(options
				(clearance outline)
				(anchor circle)
			)
			(primitives
				(gr_poly
					(pts
						(arc
							(start -0.254 0.1778)
							(mid -0.239121 0.213721)
							(end -0.2032 0.2286)
						)
						(arc
							(start 0.2032 0.2286)
							(mid 0.239121 0.213721)
							(end 0.254 0.1778)
						)
						(arc
							(start 0.254 -0.1778)
							(mid 0.239121 -0.213721)
							(end 0.2032 -0.2286)
						)
						(arc
							(start -0.2032 -0.2286)
							(mid -0.239121 -0.213721)
							(end -0.254 -0.1778)
						)
					)
					(width 0)
					(fill yes)
				)
			)
		)
		(pad "2" smd custom
			(at 0 0.4572 180)
			(size 0.1143 0.1143)
			(layers "B.Cu" "B.Mask" "B.Paste")
			(net "VR_P1V1_VFB")
			(options
				(clearance outline)
				(anchor circle)
			)
			(primitives
				(gr_poly
					(pts
						(arc
							(start -0.254 0.1778)
							(mid -0.239121 0.213721)
							(end -0.2032 0.2286)
						)
						(arc
							(start 0.2032 0.2286)
							(mid 0.239121 0.213721)
							(end 0.254 0.1778)
						)
						(arc
							(start 0.254 -0.1778)
							(mid 0.239121 -0.213721)
							(end 0.2032 -0.2286)
						)
						(arc
							(start -0.2032 -0.2286)
							(mid -0.239121 -0.213721)
							(end -0.254 -0.1778)
						)
					)
					(width 0)
					(fill yes)
				)
			)
		)
	)
	(footprint ""
		(layer "B.Cu")
		(at 75.565 -30.1244)
		(property "Reference" "TP49"
			(at 0 0 0)
			(layer "B.SilkS")
			(hide yes)
			(effects
				(font
					(size 1.27 1.27)
				)
				(justify mirror)
			)
		)
		(property "Value" "TPAD24"
			(at 0 -2.9972 0)
			(unlocked yes)
			(layer "B.Fab")
			(hide yes)
			(effects
				(font
					(size 1.016 1.016)
					(thickness 0.1524)
				)
				(justify mirror)
			)
		)
		(property "Device Type" "TPAD24"
			(at 0 -4.5212 0)
			(unlocked yes)
			(layer "B.Fab")
			(hide yes)
			(effects
				(font
					(size 1.016 1.016)
					(thickness 0.1524)
				)
				(justify mirror)
			)
		)
		(duplicate_pad_numbers_are_jumpers no)
		(fp_poly
			(pts
				(arc
					(start 0.3048 0)
					(mid -0.3048 0)
					(end 0.3048 0)
				)
			)
			(stroke
				(width 0)
				(type default)
			)
			(fill no)
			(layer "B.CrtYd")
		)
		(fp_poly
			(pts
				(arc
					(start 0.6096 0)
					(mid -0.6096 0)
					(end 0.6096 0)
				)
			)
			(stroke
				(width 0)
				(type default)
			)
			(fill no)
			(layer "B.Fab")
		)
		(pad "1" smd circle
			(at 0 0 180)
			(size 0.6096 0.6096)
			(layers "B.Cu" "B.Mask" "B.Paste")
			(net "GBE_MDIO_CLK0")
		)
	)
	(footprint ""
		(layer "B.Cu")
		(at 80.01 -26.289 -90)
		(property "Reference" "R408"
			(at 0 0 90)
			(layer "B.SilkS")
			(hide yes)
			(effects
				(font
					(size 1.27 1.27)
				)
				(justify mirror)
			)
		)
		(property "Value" "4K7R2F-GP"
			(at -1.7907 -1.1176 270)
			(unlocked yes)
			(layer "B.Fab")
			(hide yes)
			(effects
				(font
					(size 1.016 1.016)
					(thickness 0.1524)
				)
				(justify mirror)
			)
		)
		(property "Device Type" "R402H16"
			(at -1.7907 -2.6416 270)
			(unlocked yes)
			(layer "B.Fab")
			(hide yes)
			(effects
				(font
					(size 1.016 1.016)
					(thickness 0.1524)
				)
				(justify mirror)
			)
		)
		(duplicate_pad_numbers_are_jumpers no)
		(fp_rect
			(start 0.381 0.8382)
			(end -0.381 -0.8382)
			(stroke
				(width 0)
				(type default)
			)
			(fill no)
			(layer "B.CrtYd")
		)
		(fp_rect
			(start 0.381 0.8382)
			(end -0.381 -0.8382)
			(stroke
				(width 0)
				(type default)
			)
			(fill no)
			(layer "B.Fab")
		)
		(pad "1" smd custom
			(at 0 -0.4318 90)
			(size 0.127 0.127)
			(layers "B.Cu" "B.Mask" "B.Paste")
			(net "P3V3_CPU")
			(options
				(clearance outline)
				(anchor circle)
			)
			(primitives
				(gr_poly
					(pts
						(arc
							(start -0.2032 0.2794)
							(mid -0.239121 0.264521)
							(end -0.254 0.2286)
						)
						(arc
							(start -0.254 -0.2286)
							(mid -0.239121 -0.264521)
							(end -0.2032 -0.2794)
						)
						(arc
							(start 0.2032 -0.2794)
							(mid 0.239121 -0.264521)
							(end 0.254 -0.2286)
						)
						(arc
							(start 0.254 0.2286)
							(mid 0.239121 0.264521)
							(end 0.2032 0.2794)
						)
					)
					(width 0)
					(fill yes)
				)
			)
		)
		(pad "2" smd custom
			(at 0 0.4318 90)
			(size 0.127 0.127)
			(layers "B.Cu" "B.Mask" "B.Paste")
			(net "NGFF_PRESENT_R#")
			(options
				(clearance outline)
				(anchor circle)
			)
			(primitives
				(gr_poly
					(pts
						(arc
							(start -0.2032 0.2794)
							(mid -0.239121 0.264521)
							(end -0.254 0.2286)
						)
						(arc
							(start -0.254 -0.2286)
							(mid -0.239121 -0.264521)
							(end -0.2032 -0.2794)
						)
						(arc
							(start 0.2032 -0.2794)
							(mid 0.239121 -0.264521)
							(end 0.254 -0.2286)
						)
						(arc
							(start 0.254 0.2286)
							(mid 0.239121 0.264521)
							(end 0.2032 0.2794)
						)
					)
					(width 0)
					(fill yes)
				)
			)
		)
	)
	(footprint ""
		(layer "B.Cu")
		(at 89.154 -25.527 -90)
		(property "Reference" "C151"
			(at 0 0 90)
			(layer "B.SilkS")
			(hide yes)
			(effects
				(font
					(size 1.27 1.27)
				)
				(justify mirror)
			)
		)
		(property "Value" "SC1U10V2KX-1GP"
			(at -1.1811 -2.7051 270)
			(unlocked yes)
			(layer "B.Fab")
			(hide yes)
			(effects
				(font
					(size 1.016 1.016)
					(thickness 0.1524)
				)
				(justify mirror)
			)
		)
		(property "Device Type" "C402H22"
			(at -1.1811 -4.2291 270)
			(unlocked yes)
			(layer "B.Fab")
			(hide yes)
			(effects
				(font
					(size 1.016 1.016)
					(thickness 0.1524)
				)
				(justify mirror)
			)
		)
		(duplicate_pad_numbers_are_jumpers no)
		(fp_rect
			(start 0.381 0.7366)
			(end -0.381 -0.7366)
			(stroke
				(width 0)
				(type default)
			)
			(fill no)
			(layer "B.CrtYd")
		)
		(fp_rect
			(start 0.381 0.7366)
			(end -0.381 -0.7366)
			(stroke
				(width 0)
				(type default)
			)
			(fill no)
			(layer "B.Fab")
		)
		(pad "1" smd custom
			(at 0 -0.4572 90)
			(size 0.1143 0.1143)
			(layers "B.Cu" "B.Mask" "B.Paste")
			(net "P1V0")
			(options
				(clearance outline)
				(anchor circle)
			)
			(primitives
				(gr_poly
					(pts
						(arc
							(start -0.254 0.1778)
							(mid -0.239121 0.213721)
							(end -0.2032 0.2286)
						)
						(arc
							(start 0.2032 0.2286)
							(mid 0.239121 0.213721)
							(end 0.254 0.1778)
						)
						(arc
							(start 0.254 -0.1778)
							(mid 0.239121 -0.213721)
							(end 0.2032 -0.2286)
						)
						(arc
							(start -0.2032 -0.2286)
							(mid -0.239121 -0.213721)
							(end -0.254 -0.1778)
						)
					)
					(width 0)
					(fill yes)
				)
			)
		)
		(pad "2" smd custom
			(at 0 0.4572 90)
			(size 0.1143 0.1143)
			(layers "B.Cu" "B.Mask" "B.Paste")
			(net "GND")
			(options
				(clearance outline)
				(anchor circle)
			)
			(primitives
				(gr_poly
					(pts
						(arc
							(start -0.254 0.1778)
							(mid -0.239121 0.213721)
							(end -0.2032 0.2286)
						)
						(arc
							(start 0.2032 0.2286)
							(mid 0.239121 0.213721)
							(end 0.254 0.1778)
						)
						(arc
							(start 0.254 -0.1778)
							(mid 0.239121 -0.213721)
							(end 0.2032 -0.2286)
						)
						(arc
							(start -0.2032 -0.2286)
							(mid -0.239121 -0.213721)
							(end -0.254 -0.1778)
						)
					)
					(width 0)
					(fill yes)
				)
			)
		)
	)
	(footprint ""
		(layer "B.Cu")
		(at 80.518 -22.4282 90)
		(property "Reference" "PC193"
			(at 0 0 90)
			(layer "B.SilkS")
			(hide yes)
			(effects
				(font
					(size 1.27 1.27)
				)
				(justify mirror)
			)
		)
		(property "Value" "SCD1U16V2KX-3GP"
			(at -1.1811 -2.7051 90)
			(unlocked yes)
			(layer "B.Fab")
			(hide yes)
			(effects
				(font
					(size 1.016 1.016)
					(thickness 0.1524)
				)
				(justify mirror)
			)
		)
		(property "Device Type" "C402H22"
			(at -1.1811 -4.2291 90)
			(unlocked yes)
			(layer "B.Fab")
			(hide yes)
			(effects
				(font
					(size 1.016 1.016)
					(thickness 0.1524)
				)
				(justify mirror)
			)
		)
		(duplicate_pad_numbers_are_jumpers no)
		(fp_rect
			(start 0.381 0.7366)
			(end -0.381 -0.7366)
			(stroke
				(width 0)
				(type default)
			)
			(fill no)
			(layer "B.CrtYd")
		)
		(fp_rect
			(start 0.381 0.7366)
			(end -0.381 -0.7366)
			(stroke
				(width 0)
				(type default)
			)
			(fill no)
			(layer "B.Fab")
		)
		(pad "1" smd custom
			(at 0 -0.4572 270)
			(size 0.1143 0.1143)
			(layers "B.Cu" "B.Mask" "B.Paste")
			(net "TPS74801_1V35_EN")
			(options
				(clearance outline)
				(anchor circle)
			)
			(primitives
				(gr_poly
					(pts
						(arc
							(start -0.254 0.1778)
							(mid -0.239121 0.213721)
							(end -0.2032 0.2286)
						)
						(arc
							(start 0.2032 0.2286)
							(mid 0.239121 0.213721)
							(end 0.254 0.1778)
						)
						(arc
							(start 0.254 -0.1778)
							(mid 0.239121 -0.213721)
							(end 0.2032 -0.2286)
						)
						(arc
							(start -0.2032 -0.2286)
							(mid -0.239121 -0.213721)
							(end -0.254 -0.1778)
						)
					)
					(width 0)
					(fill yes)
				)
			)
		)
		(pad "2" smd custom
			(at 0 0.4572 270)
			(size 0.1143 0.1143)
			(layers "B.Cu" "B.Mask" "B.Paste")
			(net "GND")
			(options
				(clearance outline)
				(anchor circle)
			)
			(primitives
				(gr_poly
					(pts
						(arc
							(start -0.254 0.1778)
							(mid -0.239121 0.213721)
							(end -0.2032 0.2286)
						)
						(arc
							(start 0.2032 0.2286)
							(mid 0.239121 0.213721)
							(end 0.254 0.1778)
						)
						(arc
							(start 0.254 -0.1778)
							(mid 0.239121 -0.213721)
							(end 0.2032 -0.2286)
						)
						(arc
							(start -0.2032 -0.2286)
							(mid -0.239121 -0.213721)
							(end -0.254 -0.1778)
						)
					)
					(width 0)
					(fill yes)
				)
			)
		)
	)
	(footprint ""
		(layer "B.Cu")
		(at 60.071 -13.335 180)
		(property "Reference" "R396"
			(at 0 0 0)
			(layer "B.SilkS")
			(hide yes)
			(effects
				(font
					(size 1.27 1.27)
				)
				(justify mirror)
			)
		)
		(property "Value" "0R2J-2-GP"
			(at -1.7907 -1.1176 180)
			(unlocked yes)
			(layer "B.Fab")
			(hide yes)
			(effects
				(font
					(size 1.016 1.016)
					(thickness 0.1524)
				)
				(justify mirror)
			)
		)
		(property "Device Type" "R402H16"
			(at -1.7907 -2.6416 180)
			(unlocked yes)
			(layer "B.Fab")
			(hide yes)
			(effects
				(font
					(size 1.016 1.016)
					(thickness 0.1524)
				)
				(justify mirror)
			)
		)
		(duplicate_pad_numbers_are_jumpers no)
		(fp_rect
			(start 0.381 0.8382)
			(end -0.381 -0.8382)
			(stroke
				(width 0)
				(type default)
			)
			(fill no)
			(layer "B.CrtYd")
		)
		(fp_rect
			(start 0.381 0.8382)
			(end -0.381 -0.8382)
			(stroke
				(width 0)
				(type default)
			)
			(fill no)
			(layer "B.Fab")
		)
		(pad "1" smd custom
			(at 0 -0.4318)
			(size 0.127 0.127)
			(layers "B.Cu" "B.Mask" "B.Paste")
			(net "PCIE2_RESET#")
			(options
				(clearance outline)
				(anchor circle)
			)
			(primitives
				(gr_poly
					(pts
						(arc
							(start -0.2032 0.2794)
							(mid -0.239121 0.264521)
							(end -0.254 0.2286)
						)
						(arc
							(start -0.254 -0.2286)
							(mid -0.239121 -0.264521)
							(end -0.2032 -0.2794)
						)
						(arc
							(start 0.2032 -0.2794)
							(mid 0.239121 -0.264521)
							(end 0.254 -0.2286)
						)
						(arc
							(start 0.254 0.2286)
							(mid 0.239121 0.264521)
							(end 0.2032 0.2794)
						)
					)
					(width 0)
					(fill yes)
				)
			)
		)
		(pad "2" smd custom
			(at 0 0.4318)
			(size 0.127 0.127)
			(layers "B.Cu" "B.Mask" "B.Paste")
			(net "PMU_BUF_PLTRST#")
			(options
				(clearance outline)
				(anchor circle)
			)
			(primitives
				(gr_poly
					(pts
						(arc
							(start -0.2032 0.2794)
							(mid -0.239121 0.264521)
							(end -0.254 0.2286)
						)
						(arc
							(start -0.254 -0.2286)
							(mid -0.239121 -0.264521)
							(end -0.2032 -0.2794)
						)
						(arc
							(start 0.2032 -0.2794)
							(mid 0.239121 -0.264521)
							(end 0.254 -0.2286)
						)
						(arc
							(start 0.254 0.2286)
							(mid 0.239121 0.264521)
							(end 0.2032 0.2794)
						)
					)
					(width 0)
					(fill yes)
				)
			)
		)
	)
	(footprint ""
		(layer "B.Cu")
		(at 132.715 -28.067 -90)
		(property "Reference" "R33"
			(at 0 0 90)
			(layer "B.SilkS")
			(hide yes)
			(effects
				(font
					(size 1.27 1.27)
				)
				(justify mirror)
			)
		)
		(property "Value" "1KR2F-3-GP"
			(at -0.064008 -3.993896 270)
			(unlocked yes)
			(layer "B.Fab")
			(hide yes)
			(effects
				(font
					(size 1.016 1.016)
					(thickness 0.1524)
				)
				(justify mirror)
			)
		)
		(property "Device Type" "R402H16"
			(at -0.064008 -5.517896 270)
			(unlocked yes)
			(layer "B.Fab")
			(hide yes)
			(effects
				(font
					(size 1.016 1.016)
					(thickness 0.1524)
				)
				(justify mirror)
			)
		)
		(duplicate_pad_numbers_are_jumpers no)
		(fp_rect
			(start 0.381 0.8382)
			(end -0.381 -0.8382)
			(stroke
				(width 0)
				(type default)
			)
			(fill no)
			(layer "B.CrtYd")
		)
		(fp_rect
			(start 0.381 0.8382)
			(end -0.381 -0.8382)
			(stroke
				(width 0)
				(type default)
			)
			(fill no)
			(layer "B.Fab")
		)
		(pad "1" smd custom
			(at 0 -0.4318 90)
			(size 0.127 0.127)
			(layers "B.Cu" "B.Mask" "B.Paste")
			(net "P1V0")
			(options
				(clearance outline)
				(anchor circle)
			)
			(primitives
				(gr_poly
					(pts
						(arc
							(start -0.2032 0.2794)
							(mid -0.239121 0.264521)
							(end -0.254 0.2286)
						)
						(arc
							(start -0.254 -0.2286)
							(mid -0.239121 -0.264521)
							(end -0.2032 -0.2794)
						)
						(arc
							(start 0.2032 -0.2794)
							(mid 0.239121 -0.264521)
							(end 0.254 -0.2286)
						)
						(arc
							(start 0.254 0.2286)
							(mid 0.239121 0.264521)
							(end 0.2032 0.2794)
						)
					)
					(width 0)
					(fill yes)
				)
			)
		)
		(pad "2" smd custom
			(at 0 0.4318 90)
			(size 0.127 0.127)
			(layers "B.Cu" "B.Mask" "B.Paste")
			(net "H_THERMTRIP_N_R")
			(options
				(clearance outline)
				(anchor circle)
			)
			(primitives
				(gr_poly
					(pts
						(arc
							(start -0.2032 0.2794)
							(mid -0.239121 0.264521)
							(end -0.254 0.2286)
						)
						(arc
							(start -0.254 -0.2286)
							(mid -0.239121 -0.264521)
							(end -0.2032 -0.2794)
						)
						(arc
							(start 0.2032 -0.2794)
							(mid 0.239121 -0.264521)
							(end 0.254 -0.2286)
						)
						(arc
							(start 0.254 0.2286)
							(mid 0.239121 0.264521)
							(end 0.2032 0.2794)
						)
					)
					(width 0)
					(fill yes)
				)
			)
		)
	)
	(footprint ""
		(layer "B.Cu")
		(at 96.901 -52.197 180)
		(property "Reference" "C117"
			(at 0 0 0)
			(layer "B.SilkS")
			(hide yes)
			(effects
				(font
					(size 1.27 1.27)
				)
				(justify mirror)
			)
		)
		(property "Value" "SC10U6D3V3MX-GP"
			(at 0 -2.8194 180)
			(unlocked yes)
			(layer "B.Fab")
			(hide yes)
			(effects
				(font
					(size 1.016 1.016)
					(thickness 0.1524)
				)
				(justify mirror)
			)
		)
		(property "Device Type" "C603H38"
			(at 0 -4.3434 180)
			(unlocked yes)
			(layer "B.Fab")
			(hide yes)
			(effects
				(font
					(size 1.016 1.016)
					(thickness 0.1524)
				)
				(justify mirror)
			)
		)
		(duplicate_pad_numbers_are_jumpers no)
		(fp_line
			(start 0.4064 0)
			(end -0.4064 0)
			(stroke
				(width 0.2286)
				(type default)
			)
			(layer "B.SilkS")
		)
		(fp_rect
			(start 0.635 1.1811)
			(end -0.635 -1.1811)
			(stroke
				(width 0)
				(type default)
			)
			(fill no)
			(layer "B.CrtYd")
		)
		(fp_rect
			(start 0.635 1.1811)
			(end -0.635 -1.1811)
			(stroke
				(width 0)
				(type default)
			)
			(fill no)
			(layer "B.Fab")
		)
		(pad "1" smd custom
			(at 0 -0.6604)
			(size 0.19685 0.19685)
			(layers "B.Cu" "B.Mask" "B.Paste")
			(net "VCCCLKDDR0")
			(options
				(clearance outline)
				(anchor circle)
			)
			(primitives
				(gr_poly
					(pts
						(arc
							(start 0.508 0.2921)
							(mid 0.478242 0.363942)
							(end 0.4064 0.3937)
						)
						(arc
							(start -0.4064 0.3937)
							(mid -0.478242 0.363942)
							(end -0.508 0.2921)
						)
						(arc
							(start -0.508 -0.2921)
							(mid -0.478242 -0.363942)
							(end -0.4064 -0.3937)
						)
						(arc
							(start 0.4064 -0.3937)
							(mid 0.478242 -0.363942)
							(end 0.508 -0.2921)
						)
					)
					(width 0)
					(fill yes)
				)
			)
		)
		(pad "2" smd custom
			(at 0 0.6604)
			(size 0.19685 0.19685)
			(layers "B.Cu" "B.Mask" "B.Paste")
			(net "GND")
			(options
				(clearance outline)
				(anchor circle)
			)
			(primitives
				(gr_poly
					(pts
						(arc
							(start 0.508 0.2921)
							(mid 0.478242 0.363942)
							(end 0.4064 0.3937)
						)
						(arc
							(start -0.4064 0.3937)
							(mid -0.478242 0.363942)
							(end -0.508 0.2921)
						)
						(arc
							(start -0.508 -0.2921)
							(mid -0.478242 -0.363942)
							(end -0.4064 -0.3937)
						)
						(arc
							(start 0.4064 -0.3937)
							(mid 0.478242 -0.363942)
							(end 0.508 -0.2921)
						)
					)
					(width 0)
					(fill yes)
				)
			)
		)
	)
	(footprint ""
		(layer "B.Cu")
		(at 187.0202 -34.0614 90)
		(property "Reference" "PR141"
			(at 0 0 90)
			(layer "B.SilkS")
			(hide yes)
			(effects
				(font
					(size 1.27 1.27)
				)
				(justify mirror)
			)
		)
		(property "Value" "75KR2J-GP"
			(at -1.7907 -1.1176 90)
			(unlocked yes)
			(layer "B.Fab")
			(hide yes)
			(effects
				(font
					(size 1.016 1.016)
					(thickness 0.1524)
				)
				(justify mirror)
			)
		)
		(property "Device Type" "R402H16"
			(at -1.7907 -2.6416 90)
			(unlocked yes)
			(layer "B.Fab")
			(hide yes)
			(effects
				(font
					(size 1.016 1.016)
					(thickness 0.1524)
				)
				(justify mirror)
			)
		)
		(duplicate_pad_numbers_are_jumpers no)
		(fp_rect
			(start 0.381 0.8382)
			(end -0.381 -0.8382)
			(stroke
				(width 0)
				(type default)
			)
			(fill no)
			(layer "B.CrtYd")
		)
		(fp_rect
			(start 0.381 0.8382)
			(end -0.381 -0.8382)
			(stroke
				(width 0)
				(type default)
			)
			(fill no)
			(layer "B.Fab")
		)
		(pad "1" smd custom
			(at 0 -0.4318 270)
			(size 0.127 0.127)
			(layers "B.Cu" "B.Mask" "B.Paste")
			(net "VR_PVDDR_A_IMON")
			(options
				(clearance outline)
				(anchor circle)
			)
			(primitives
				(gr_poly
					(pts
						(arc
							(start -0.2032 0.2794)
							(mid -0.239121 0.264521)
							(end -0.254 0.2286)
						)
						(arc
							(start -0.254 -0.2286)
							(mid -0.239121 -0.264521)
							(end -0.2032 -0.2794)
						)
						(arc
							(start 0.2032 -0.2794)
							(mid 0.239121 -0.264521)
							(end 0.254 -0.2286)
						)
						(arc
							(start 0.254 0.2286)
							(mid 0.239121 0.264521)
							(end 0.2032 0.2794)
						)
					)
					(width 0)
					(fill yes)
				)
			)
		)
		(pad "2" smd custom
			(at 0 0.4318 270)
			(size 0.127 0.127)
			(layers "B.Cu" "B.Mask" "B.Paste")
			(net "GND")
			(options
				(clearance outline)
				(anchor circle)
			)
			(primitives
				(gr_poly
					(pts
						(arc
							(start -0.2032 0.2794)
							(mid -0.239121 0.264521)
							(end -0.254 0.2286)
						)
						(arc
							(start -0.254 -0.2286)
							(mid -0.239121 -0.264521)
							(end -0.2032 -0.2794)
						)
						(arc
							(start 0.2032 -0.2794)
							(mid 0.239121 -0.264521)
							(end 0.254 -0.2286)
						)
						(arc
							(start 0.254 0.2286)
							(mid 0.239121 0.264521)
							(end 0.2032 0.2794)
						)
					)
					(width 0)
					(fill yes)
				)
			)
		)
	)
	(footprint ""
		(layer "B.Cu")
		(at 36.449 -24.003 180)
		(property "Reference" "R418"
			(at 0 0 0)
			(layer "B.SilkS")
			(hide yes)
			(effects
				(font
					(size 1.27 1.27)
				)
				(justify mirror)
			)
		)
		(property "Value" "43D2R2F-GP"
			(at -1.7907 -1.1176 180)
			(unlocked yes)
			(layer "B.Fab")
			(hide yes)
			(effects
				(font
					(size 1.016 1.016)
					(thickness 0.1524)
				)
				(justify mirror)
			)
		)
		(property "Device Type" "R402H16"
			(at -1.7907 -2.6416 180)
			(unlocked yes)
			(layer "B.Fab")
			(hide yes)
			(effects
				(font
					(size 1.016 1.016)
					(thickness 0.1524)
				)
				(justify mirror)
			)
		)
		(duplicate_pad_numbers_are_jumpers no)
		(fp_rect
			(start 0.381 0.8382)
			(end -0.381 -0.8382)
			(stroke
				(width 0)
				(type default)
			)
			(fill no)
			(layer "B.CrtYd")
		)
		(fp_rect
			(start 0.381 0.8382)
			(end -0.381 -0.8382)
			(stroke
				(width 0)
				(type default)
			)
			(fill no)
			(layer "B.Fab")
		)
		(pad "1" smd custom
			(at 0 -0.4318)
			(size 0.127 0.127)
			(layers "B.Cu" "B.Mask" "B.Paste")
			(net "CLK_100M_CLKBUFF_NGFF_DP")
			(options
				(clearance outline)
				(anchor circle)
			)
			(primitives
				(gr_poly
					(pts
						(arc
							(start -0.2032 0.2794)
							(mid -0.239121 0.264521)
							(end -0.254 0.2286)
						)
						(arc
							(start -0.254 -0.2286)
							(mid -0.239121 -0.264521)
							(end -0.2032 -0.2794)
						)
						(arc
							(start 0.2032 -0.2794)
							(mid 0.239121 -0.264521)
							(end 0.254 -0.2286)
						)
						(arc
							(start 0.254 0.2286)
							(mid 0.239121 0.264521)
							(end 0.2032 0.2794)
						)
					)
					(width 0)
					(fill yes)
				)
			)
		)
		(pad "2" smd custom
			(at 0 0.4318)
			(size 0.127 0.127)
			(layers "B.Cu" "B.Mask" "B.Paste")
			(net "GND")
			(options
				(clearance outline)
				(anchor circle)
			)
			(primitives
				(gr_poly
					(pts
						(arc
							(start -0.2032 0.2794)
							(mid -0.239121 0.264521)
							(end -0.254 0.2286)
						)
						(arc
							(start -0.254 -0.2286)
							(mid -0.239121 -0.264521)
							(end -0.2032 -0.2794)
						)
						(arc
							(start 0.2032 -0.2794)
							(mid 0.239121 -0.264521)
							(end 0.254 -0.2286)
						)
						(arc
							(start 0.254 0.2286)
							(mid 0.239121 0.264521)
							(end 0.2032 0.2794)
						)
					)
					(width 0)
					(fill yes)
				)
			)
		)
	)
	(footprint ""
		(layer "B.Cu")
		(at 5.6642 -39.8272 -90)
		(property "Reference" "PC182"
			(at 0 0 90)
			(layer "B.SilkS")
			(hide yes)
			(effects
				(font
					(size 1.27 1.27)
				)
				(justify mirror)
			)
		)
		(property "Value" "SC22U25V5MX-GP"
			(at 0 -4.9022 270)
			(unlocked yes)
			(layer "B.Fab")
			(hide yes)
			(effects
				(font
					(size 1.016 1.016)
					(thickness 0.1524)
				)
				(justify mirror)
			)
		)
		(property "Device Type" "C805H58"
			(at 0 -6.8072 270)
			(unlocked yes)
			(layer "B.Fab")
			(hide yes)
			(effects
				(font
					(size 1.016 1.016)
					(thickness 0.1524)
				)
				(justify mirror)
			)
		)
		(duplicate_pad_numbers_are_jumpers no)
		(fp_line
			(start -0.6096 0)
			(end 0.6096 0)
			(stroke
				(width 0.3048)
				(type default)
			)
			(layer "B.SilkS")
		)
		(fp_poly
			(pts
				(xy 0.9017 1.4351) (xy -0.9017 1.4351) (xy -0.9017 -1.4351) (xy 0.9017 -1.4351)
			)
			(stroke
				(width 0)
				(type default)
			)
			(fill no)
			(layer "B.CrtYd")
		)
		(fp_poly
			(pts
				(xy -0.9017 1.4351) (xy -0.9017 -1.4351) (xy 0.9017 -1.4351) (xy 0.9017 1.4351)
			)
			(stroke
				(width 0)
				(type default)
			)
			(fill no)
			(layer "B.Fab")
		)
		(pad "1" smd rect
			(at 0 -0.8382 90)
			(size 1.5494 0.9398)
			(layers "B.Cu" "B.Mask" "B.Paste")
			(net "P3V3_STBY_VIN")
		)
		(pad "2" smd rect
			(at 0 0.8382 90)
			(size 1.5494 0.9398)
			(layers "B.Cu" "B.Mask" "B.Paste")
			(net "GND")
		)
	)
	(footprint ""
		(layer "B.Cu")
		(at 38.989 -48.768 -90)
		(property "Reference" "R127"
			(at 0 0 90)
			(layer "B.SilkS")
			(hide yes)
			(effects
				(font
					(size 1.27 1.27)
				)
				(justify mirror)
			)
		)
		(property "Value" "33R2F-3-GP"
			(at -1.7907 -1.1176 270)
			(unlocked yes)
			(layer "B.Fab")
			(hide yes)
			(effects
				(font
					(size 1.016 1.016)
					(thickness 0.1524)
				)
				(justify mirror)
			)
		)
		(property "Device Type" "R402H16"
			(at -1.7907 -2.6416 270)
			(unlocked yes)
			(layer "B.Fab")
			(hide yes)
			(effects
				(font
					(size 1.016 1.016)
					(thickness 0.1524)
				)
				(justify mirror)
			)
		)
		(duplicate_pad_numbers_are_jumpers no)
		(fp_rect
			(start 0.381 0.8382)
			(end -0.381 -0.8382)
			(stroke
				(width 0)
				(type default)
			)
			(fill no)
			(layer "B.CrtYd")
		)
		(fp_rect
			(start 0.381 0.8382)
			(end -0.381 -0.8382)
			(stroke
				(width 0)
				(type default)
			)
			(fill no)
			(layer "B.Fab")
		)
		(pad "1" smd custom
			(at 0 -0.4318 90)
			(size 0.127 0.127)
			(layers "B.Cu" "B.Mask" "B.Paste")
			(net "CLK_14M_CPU_R")
			(options
				(clearance outline)
				(anchor circle)
			)
			(primitives
				(gr_poly
					(pts
						(arc
							(start -0.2032 0.2794)
							(mid -0.239121 0.264521)
							(end -0.254 0.2286)
						)
						(arc
							(start -0.254 -0.2286)
							(mid -0.239121 -0.264521)
							(end -0.2032 -0.2794)
						)
						(arc
							(start 0.2032 -0.2794)
							(mid 0.239121 -0.264521)
							(end 0.254 -0.2286)
						)
						(arc
							(start 0.254 0.2286)
							(mid 0.239121 0.264521)
							(end 0.2032 0.2794)
						)
					)
					(width 0)
					(fill yes)
				)
			)
		)
		(pad "2" smd custom
			(at 0 0.4318 90)
			(size 0.127 0.127)
			(layers "B.Cu" "B.Mask" "B.Paste")
			(net "CLK_14M_CPU")
			(options
				(clearance outline)
				(anchor circle)
			)
			(primitives
				(gr_poly
					(pts
						(arc
							(start -0.2032 0.2794)
							(mid -0.239121 0.264521)
							(end -0.254 0.2286)
						)
						(arc
							(start -0.254 -0.2286)
							(mid -0.239121 -0.264521)
							(end -0.2032 -0.2794)
						)
						(arc
							(start 0.2032 -0.2794)
							(mid 0.239121 -0.264521)
							(end 0.254 -0.2286)
						)
						(arc
							(start 0.254 0.2286)
							(mid 0.239121 0.264521)
							(end 0.2032 0.2794)
						)
					)
					(width 0)
					(fill yes)
				)
			)
		)
	)
	(footprint ""
		(layer "B.Cu")
		(at 85.217 -31.75 90)
		(property "Reference" "R357"
			(at 0 0 90)
			(layer "B.SilkS")
			(hide yes)
			(effects
				(font
					(size 1.27 1.27)
				)
				(justify mirror)
			)
		)
		(property "Value" "402R2F-GP"
			(at -0.064008 -3.993896 90)
			(unlocked yes)
			(layer "B.Fab")
			(hide yes)
			(effects
				(font
					(size 1.016 1.016)
					(thickness 0.1524)
				)
				(justify mirror)
			)
		)
		(property "Device Type" "R402H16"
			(at -0.064008 -5.517896 90)
			(unlocked yes)
			(layer "B.Fab")
			(hide yes)
			(effects
				(font
					(size 1.016 1.016)
					(thickness 0.1524)
				)
				(justify mirror)
			)
		)
		(duplicate_pad_numbers_are_jumpers no)
		(fp_rect
			(start 0.381 0.8382)
			(end -0.381 -0.8382)
			(stroke
				(width 0)
				(type default)
			)
			(fill no)
			(layer "B.CrtYd")
		)
		(fp_rect
			(start 0.381 0.8382)
			(end -0.381 -0.8382)
			(stroke
				(width 0)
				(type default)
			)
			(fill no)
			(layer "B.Fab")
		)
		(pad "1" smd custom
			(at 0 -0.4318 270)
			(size 0.127 0.127)
			(layers "B.Cu" "B.Mask" "B.Paste")
			(net "SATA3_OBS_P")
			(options
				(clearance outline)
				(anchor circle)
			)
			(primitives
				(gr_poly
					(pts
						(arc
							(start -0.2032 0.2794)
							(mid -0.239121 0.264521)
							(end -0.254 0.2286)
						)
						(arc
							(start -0.254 -0.2286)
							(mid -0.239121 -0.264521)
							(end -0.2032 -0.2794)
						)
						(arc
							(start 0.2032 -0.2794)
							(mid 0.239121 -0.264521)
							(end 0.254 -0.2286)
						)
						(arc
							(start 0.254 0.2286)
							(mid 0.239121 0.264521)
							(end 0.2032 0.2794)
						)
					)
					(width 0)
					(fill yes)
				)
			)
		)
		(pad "2" smd custom
			(at 0 0.4318 270)
			(size 0.127 0.127)
			(layers "B.Cu" "B.Mask" "B.Paste")
			(net "SATA3_OBS_N")
			(options
				(clearance outline)
				(anchor circle)
			)
			(primitives
				(gr_poly
					(pts
						(arc
							(start -0.2032 0.2794)
							(mid -0.239121 0.264521)
							(end -0.254 0.2286)
						)
						(arc
							(start -0.254 -0.2286)
							(mid -0.239121 -0.264521)
							(end -0.2032 -0.2794)
						)
						(arc
							(start 0.2032 -0.2794)
							(mid 0.239121 -0.264521)
							(end 0.254 -0.2286)
						)
						(arc
							(start 0.254 0.2286)
							(mid 0.239121 0.264521)
							(end 0.2032 0.2794)
						)
					)
					(width 0)
					(fill yes)
				)
			)
		)
	)
	(footprint ""
		(layer "B.Cu")
		(at 70.2056 -17.272 90)
		(property "Reference" "PC123"
			(at 0 0 90)
			(layer "B.SilkS")
			(hide yes)
			(effects
				(font
					(size 1.27 1.27)
				)
				(justify mirror)
			)
		)
		(property "Value" "SC22U6D3V5MX-2GP"
			(at 0 -4.9022 90)
			(unlocked yes)
			(layer "B.Fab")
			(hide yes)
			(effects
				(font
					(size 1.016 1.016)
					(thickness 0.1524)
				)
				(justify mirror)
			)
		)
		(property "Device Type" "C805H58"
			(at 0 -6.8072 90)
			(unlocked yes)
			(layer "B.Fab")
			(hide yes)
			(effects
				(font
					(size 1.016 1.016)
					(thickness 0.1524)
				)
				(justify mirror)
			)
		)
		(duplicate_pad_numbers_are_jumpers no)
		(fp_line
			(start -0.6096 0)
			(end 0.6096 0)
			(stroke
				(width 0.3048)
				(type default)
			)
			(layer "B.SilkS")
		)
		(fp_poly
			(pts
				(xy 0.9017 1.4351) (xy -0.9017 1.4351) (xy -0.9017 -1.4351) (xy 0.9017 -1.4351)
			)
			(stroke
				(width 0)
				(type default)
			)
			(fill no)
			(layer "B.CrtYd")
		)
		(fp_poly
			(pts
				(xy -0.9017 1.4351) (xy -0.9017 -1.4351) (xy 0.9017 -1.4351) (xy 0.9017 1.4351)
			)
			(stroke
				(width 0)
				(type default)
			)
			(fill no)
			(layer "B.Fab")
		)
		(pad "1" smd rect
			(at 0 -0.8382 270)
			(size 1.5494 0.9398)
			(layers "B.Cu" "B.Mask" "B.Paste")
			(net "P1V8_STBY_VOUT")
		)
		(pad "2" smd rect
			(at 0 0.8382 270)
			(size 1.5494 0.9398)
			(layers "B.Cu" "B.Mask" "B.Paste")
			(net "GND")
		)
	)
	(footprint ""
		(layer "B.Cu")
		(at 140.462 -47.625 -90)
		(property "Reference" "R297"
			(at 0 0 90)
			(layer "B.SilkS")
			(hide yes)
			(effects
				(font
					(size 1.27 1.27)
				)
				(justify mirror)
			)
		)
		(property "Value" "0R2J-2-GP"
			(at -1.7907 -1.1176 270)
			(unlocked yes)
			(layer "B.Fab")
			(hide yes)
			(effects
				(font
					(size 1.016 1.016)
					(thickness 0.1524)
				)
				(justify mirror)
			)
		)
		(property "Device Type" "R402H16"
			(at -1.7907 -2.6416 270)
			(unlocked yes)
			(layer "B.Fab")
			(hide yes)
			(effects
				(font
					(size 1.016 1.016)
					(thickness 0.1524)
				)
				(justify mirror)
			)
		)
		(duplicate_pad_numbers_are_jumpers no)
		(fp_rect
			(start 0.381 0.8382)
			(end -0.381 -0.8382)
			(stroke
				(width 0)
				(type default)
			)
			(fill no)
			(layer "B.CrtYd")
		)
		(fp_rect
			(start 0.381 0.8382)
			(end -0.381 -0.8382)
			(stroke
				(width 0)
				(type default)
			)
			(fill no)
			(layer "B.Fab")
		)
		(pad "1" smd custom
			(at 0 -0.4318 90)
			(size 0.127 0.127)
			(layers "B.Cu" "B.Mask" "B.Paste")
			(net "C_NCE_R#")
			(options
				(clearance outline)
				(anchor circle)
			)
			(primitives
				(gr_poly
					(pts
						(arc
							(start -0.2032 0.2794)
							(mid -0.239121 0.264521)
							(end -0.254 0.2286)
						)
						(arc
							(start -0.254 -0.2286)
							(mid -0.239121 -0.264521)
							(end -0.2032 -0.2794)
						)
						(arc
							(start 0.2032 -0.2794)
							(mid 0.239121 -0.264521)
							(end 0.254 -0.2286)
						)
						(arc
							(start 0.254 0.2286)
							(mid 0.239121 0.264521)
							(end 0.2032 0.2794)
						)
					)
					(width 0)
					(fill yes)
				)
			)
		)
		(pad "2" smd custom
			(at 0 0.4318 90)
			(size 0.127 0.127)
			(layers "B.Cu" "B.Mask" "B.Paste")
			(net "C_NCE#")
			(options
				(clearance outline)
				(anchor circle)
			)
			(primitives
				(gr_poly
					(pts
						(arc
							(start -0.2032 0.2794)
							(mid -0.239121 0.264521)
							(end -0.254 0.2286)
						)
						(arc
							(start -0.254 -0.2286)
							(mid -0.239121 -0.264521)
							(end -0.2032 -0.2794)
						)
						(arc
							(start 0.2032 -0.2794)
							(mid 0.239121 -0.264521)
							(end 0.254 -0.2286)
						)
						(arc
							(start 0.254 0.2286)
							(mid 0.239121 0.264521)
							(end 0.2032 0.2794)
						)
					)
					(width 0)
					(fill yes)
				)
			)
		)
	)
	(footprint ""
		(layer "B.Cu")
		(at 98.679 -51.435 180)
		(property "Reference" "R279"
			(at 0 0 0)
			(layer "B.SilkS")
			(hide yes)
			(effects
				(font
					(size 1.27 1.27)
				)
				(justify mirror)
			)
		)
		(property "Value" "23D7R2F-GP"
			(at -0.064008 -3.993896 180)
			(unlocked yes)
			(layer "B.Fab")
			(hide yes)
			(effects
				(font
					(size 1.016 1.016)
					(thickness 0.1524)
				)
				(justify mirror)
			)
		)
		(property "Device Type" "R402H16"
			(at -0.064008 -5.517896 180)
			(unlocked yes)
			(layer "B.Fab")
			(hide yes)
			(effects
				(font
					(size 1.016 1.016)
					(thickness 0.1524)
				)
				(justify mirror)
			)
		)
		(duplicate_pad_numbers_are_jumpers no)
		(fp_rect
			(start 0.381 0.8382)
			(end -0.381 -0.8382)
			(stroke
				(width 0)
				(type default)
			)
			(fill no)
			(layer "B.CrtYd")
		)
		(fp_rect
			(start 0.381 0.8382)
			(end -0.381 -0.8382)
			(stroke
				(width 0)
				(type default)
			)
			(fill no)
			(layer "B.Fab")
		)
		(pad "1" smd custom
			(at 0 -0.4318)
			(size 0.127 0.127)
			(layers "B.Cu" "B.Mask" "B.Paste")
			(net "M_A_CMDPU")
			(options
				(clearance outline)
				(anchor circle)
			)
			(primitives
				(gr_poly
					(pts
						(arc
							(start -0.2032 0.2794)
							(mid -0.239121 0.264521)
							(end -0.254 0.2286)
						)
						(arc
							(start -0.254 -0.2286)
							(mid -0.239121 -0.264521)
							(end -0.2032 -0.2794)
						)
						(arc
							(start 0.2032 -0.2794)
							(mid 0.239121 -0.264521)
							(end 0.254 -0.2286)
						)
						(arc
							(start 0.254 0.2286)
							(mid 0.239121 0.264521)
							(end 0.2032 0.2794)
						)
					)
					(width 0)
					(fill yes)
				)
			)
		)
		(pad "2" smd custom
			(at 0 0.4318)
			(size 0.127 0.127)
			(layers "B.Cu" "B.Mask" "B.Paste")
			(net "GND")
			(options
				(clearance outline)
				(anchor circle)
			)
			(primitives
				(gr_poly
					(pts
						(arc
							(start -0.2032 0.2794)
							(mid -0.239121 0.264521)
							(end -0.254 0.2286)
						)
						(arc
							(start -0.254 -0.2286)
							(mid -0.239121 -0.264521)
							(end -0.2032 -0.2794)
						)
						(arc
							(start 0.2032 -0.2794)
							(mid 0.239121 -0.264521)
							(end 0.254 -0.2286)
						)
						(arc
							(start 0.254 0.2286)
							(mid 0.239121 0.264521)
							(end 0.2032 0.2794)
						)
					)
					(width 0)
					(fill yes)
				)
			)
		)
	)
	(footprint ""
		(layer "B.Cu")
		(at 190.881 -27.94)
		(property "Reference" "PR154"
			(at 0 0 0)
			(layer "B.SilkS")
			(hide yes)
			(effects
				(font
					(size 1.27 1.27)
				)
				(justify mirror)
			)
		)
		(property "Value" "0R2J-2-GP"
			(at -1.7907 -1.1176 0)
			(unlocked yes)
			(layer "B.Fab")
			(hide yes)
			(effects
				(font
					(size 1.016 1.016)
					(thickness 0.1524)
				)
				(justify mirror)
			)
		)
		(property "Device Type" "R402H16"
			(at -1.7907 -2.6416 0)
			(unlocked yes)
			(layer "B.Fab")
			(hide yes)
			(effects
				(font
					(size 1.016 1.016)
					(thickness 0.1524)
				)
				(justify mirror)
			)
		)
		(duplicate_pad_numbers_are_jumpers no)
		(fp_rect
			(start 0.381 0.8382)
			(end -0.381 -0.8382)
			(stroke
				(width 0)
				(type default)
			)
			(fill no)
			(layer "B.CrtYd")
		)
		(fp_rect
			(start 0.381 0.8382)
			(end -0.381 -0.8382)
			(stroke
				(width 0)
				(type default)
			)
			(fill no)
			(layer "B.Fab")
		)
		(pad "1" smd custom
			(at 0 -0.4318 180)
			(size 0.127 0.127)
			(layers "B.Cu" "B.Mask" "B.Paste")
			(net "VR_PVDDR_A_VDD")
			(options
				(clearance outline)
				(anchor circle)
			)
			(primitives
				(gr_poly
					(pts
						(arc
							(start -0.2032 0.2794)
							(mid -0.239121 0.264521)
							(end -0.254 0.2286)
						)
						(arc
							(start -0.254 -0.2286)
							(mid -0.239121 -0.264521)
							(end -0.2032 -0.2794)
						)
						(arc
							(start 0.2032 -0.2794)
							(mid 0.239121 -0.264521)
							(end 0.254 -0.2286)
						)
						(arc
							(start 0.254 0.2286)
							(mid 0.239121 0.264521)
							(end 0.2032 0.2794)
						)
					)
					(width 0)
					(fill yes)
				)
			)
		)
		(pad "2" smd custom
			(at 0 0.4318 180)
			(size 0.127 0.127)
			(layers "B.Cu" "B.Mask" "B.Paste")
			(net "VDDR_5VBIAS")
			(options
				(clearance outline)
				(anchor circle)
			)
			(primitives
				(gr_poly
					(pts
						(arc
							(start -0.2032 0.2794)
							(mid -0.239121 0.264521)
							(end -0.254 0.2286)
						)
						(arc
							(start -0.254 -0.2286)
							(mid -0.239121 -0.264521)
							(end -0.2032 -0.2794)
						)
						(arc
							(start 0.2032 -0.2794)
							(mid 0.239121 -0.264521)
							(end 0.254 -0.2286)
						)
						(arc
							(start 0.254 0.2286)
							(mid 0.239121 0.264521)
							(end 0.2032 0.2794)
						)
					)
					(width 0)
					(fill yes)
				)
			)
		)
	)
	(footprint ""
		(layer "B.Cu")
		(at 34.2392 -12.7)
		(property "Reference" "C268"
			(at 0 0 0)
			(layer "B.SilkS")
			(hide yes)
			(effects
				(font
					(size 1.27 1.27)
				)
				(justify mirror)
			)
		)
		(property "Value" "SCD1U16V2KX-3GP"
			(at -1.1811 -2.7051 0)
			(unlocked yes)
			(layer "B.Fab")
			(hide yes)
			(effects
				(font
					(size 1.016 1.016)
					(thickness 0.1524)
				)
				(justify mirror)
			)
		)
		(property "Device Type" "C402H22"
			(at -1.1811 -4.2291 0)
			(unlocked yes)
			(layer "B.Fab")
			(hide yes)
			(effects
				(font
					(size 1.016 1.016)
					(thickness 0.1524)
				)
				(justify mirror)
			)
		)
		(duplicate_pad_numbers_are_jumpers no)
		(fp_rect
			(start 0.381 0.7366)
			(end -0.381 -0.7366)
			(stroke
				(width 0)
				(type default)
			)
			(fill no)
			(layer "B.CrtYd")
		)
		(fp_rect
			(start 0.381 0.7366)
			(end -0.381 -0.7366)
			(stroke
				(width 0)
				(type default)
			)
			(fill no)
			(layer "B.Fab")
		)
		(pad "1" smd custom
			(at 0 -0.4572 180)
			(size 0.1143 0.1143)
			(layers "B.Cu" "B.Mask" "B.Paste")
			(net "P2E_CPU_SAS_C_TX_DP7")
			(options
				(clearance outline)
				(anchor circle)
			)
			(primitives
				(gr_poly
					(pts
						(arc
							(start -0.254 0.1778)
							(mid -0.239121 0.213721)
							(end -0.2032 0.2286)
						)
						(arc
							(start 0.2032 0.2286)
							(mid 0.239121 0.213721)
							(end 0.254 0.1778)
						)
						(arc
							(start 0.254 -0.1778)
							(mid 0.239121 -0.213721)
							(end 0.2032 -0.2286)
						)
						(arc
							(start -0.2032 -0.2286)
							(mid -0.239121 -0.213721)
							(end -0.254 -0.1778)
						)
					)
					(width 0)
					(fill yes)
				)
			)
		)
		(pad "2" smd custom
			(at 0 0.4572 180)
			(size 0.1143 0.1143)
			(layers "B.Cu" "B.Mask" "B.Paste")
			(net "P2E_CPU_SAS_TX_DP7")
			(options
				(clearance outline)
				(anchor circle)
			)
			(primitives
				(gr_poly
					(pts
						(arc
							(start -0.254 0.1778)
							(mid -0.239121 0.213721)
							(end -0.2032 0.2286)
						)
						(arc
							(start 0.2032 0.2286)
							(mid 0.239121 0.213721)
							(end 0.254 0.1778)
						)
						(arc
							(start 0.254 -0.1778)
							(mid 0.239121 -0.213721)
							(end 0.2032 -0.2286)
						)
						(arc
							(start -0.2032 -0.2286)
							(mid -0.239121 -0.213721)
							(end -0.254 -0.1778)
						)
					)
					(width 0)
					(fill yes)
				)
			)
		)
	)
	(footprint ""
		(layer "B.Cu")
		(at 139.446 -45.466 -90)
		(property "Reference" "C172"
			(at 0 0 90)
			(layer "B.SilkS")
			(hide yes)
			(effects
				(font
					(size 1.27 1.27)
				)
				(justify mirror)
			)
		)
		(property "Value" "SCD1U10V2KX-5GP"
			(at -1.1811 -2.7051 270)
			(unlocked yes)
			(layer "B.Fab")
			(hide yes)
			(effects
				(font
					(size 1.016 1.016)
					(thickness 0.1524)
				)
				(justify mirror)
			)
		)
		(property "Device Type" "C402H22"
			(at -1.1811 -4.2291 270)
			(unlocked yes)
			(layer "B.Fab")
			(hide yes)
			(effects
				(font
					(size 1.016 1.016)
					(thickness 0.1524)
				)
				(justify mirror)
			)
		)
		(duplicate_pad_numbers_are_jumpers no)
		(fp_rect
			(start 0.381 0.7366)
			(end -0.381 -0.7366)
			(stroke
				(width 0)
				(type default)
			)
			(fill no)
			(layer "B.CrtYd")
		)
		(fp_rect
			(start 0.381 0.7366)
			(end -0.381 -0.7366)
			(stroke
				(width 0)
				(type default)
			)
			(fill no)
			(layer "B.Fab")
		)
		(pad "1" smd custom
			(at 0 -0.4572 90)
			(size 0.1143 0.1143)
			(layers "B.Cu" "B.Mask" "B.Paste")
			(net "P3V3_STBY")
			(options
				(clearance outline)
				(anchor circle)
			)
			(primitives
				(gr_poly
					(pts
						(arc
							(start -0.254 0.1778)
							(mid -0.239121 0.213721)
							(end -0.2032 0.2286)
						)
						(arc
							(start 0.2032 0.2286)
							(mid 0.239121 0.213721)
							(end 0.254 0.1778)
						)
						(arc
							(start 0.254 -0.1778)
							(mid 0.239121 -0.213721)
							(end 0.2032 -0.2286)
						)
						(arc
							(start -0.2032 -0.2286)
							(mid -0.239121 -0.213721)
							(end -0.254 -0.1778)
						)
					)
					(width 0)
					(fill yes)
				)
			)
		)
		(pad "2" smd custom
			(at 0 0.4572 90)
			(size 0.1143 0.1143)
			(layers "B.Cu" "B.Mask" "B.Paste")
			(net "GND")
			(options
				(clearance outline)
				(anchor circle)
			)
			(primitives
				(gr_poly
					(pts
						(arc
							(start -0.254 0.1778)
							(mid -0.239121 0.213721)
							(end -0.2032 0.2286)
						)
						(arc
							(start 0.2032 0.2286)
							(mid 0.239121 0.213721)
							(end 0.254 0.1778)
						)
						(arc
							(start 0.254 -0.1778)
							(mid 0.239121 -0.213721)
							(end 0.2032 -0.2286)
						)
						(arc
							(start -0.2032 -0.2286)
							(mid -0.239121 -0.213721)
							(end -0.254 -0.1778)
						)
					)
					(width 0)
					(fill yes)
				)
			)
		)
	)
	(footprint ""
		(layer "B.Cu")
		(at 187.96 -59.944)
		(property "Reference" "C352"
			(at 0 0 0)
			(layer "B.SilkS")
			(hide yes)
			(effects
				(font
					(size 1.27 1.27)
				)
				(justify mirror)
			)
		)
		(property "Value" "SC1U6D3V3KX-2GP"
			(at 0.0254 -2.0193 0)
			(unlocked yes)
			(layer "B.Fab")
			(hide yes)
			(effects
				(font
					(size 1.016 1.016)
					(thickness 0.1524)
				)
				(justify mirror)
			)
		)
		(property "Device Type" "C603H36"
			(at 0.0254 -3.5433 0)
			(unlocked yes)
			(layer "B.Fab")
			(hide yes)
			(effects
				(font
					(size 1.016 1.016)
					(thickness 0.1524)
				)
				(justify mirror)
			)
		)
		(duplicate_pad_numbers_are_jumpers no)
		(fp_line
			(start 0.4064 0)
			(end -0.4064 0)
			(stroke
				(width 0.2286)
				(type default)
			)
			(layer "B.SilkS")
		)
		(fp_rect
			(start 0.635 1.1811)
			(end -0.635 -1.1811)
			(stroke
				(width 0)
				(type default)
			)
			(fill no)
			(layer "B.CrtYd")
		)
		(fp_rect
			(start 0.635 1.1811)
			(end -0.635 -1.1811)
			(stroke
				(width 0)
				(type default)
			)
			(fill no)
			(layer "B.Fab")
		)
		(pad "1" smd custom
			(at 0 -0.6604 180)
			(size 0.19685 0.19685)
			(layers "B.Cu" "B.Mask" "B.Paste")
			(net "DDR3_M_A_VREF_DQ0")
			(options
				(clearance outline)
				(anchor circle)
			)
			(primitives
				(gr_poly
					(pts
						(arc
							(start 0.508 0.2921)
							(mid 0.478242 0.363942)
							(end 0.4064 0.3937)
						)
						(arc
							(start -0.4064 0.3937)
							(mid -0.478242 0.363942)
							(end -0.508 0.2921)
						)
						(arc
							(start -0.508 -0.2921)
							(mid -0.478242 -0.363942)
							(end -0.4064 -0.3937)
						)
						(arc
							(start 0.4064 -0.3937)
							(mid 0.478242 -0.363942)
							(end 0.508 -0.2921)
						)
					)
					(width 0)
					(fill yes)
				)
			)
		)
		(pad "2" smd custom
			(at 0 0.6604 180)
			(size 0.19685 0.19685)
			(layers "B.Cu" "B.Mask" "B.Paste")
			(net "GND")
			(options
				(clearance outline)
				(anchor circle)
			)
			(primitives
				(gr_poly
					(pts
						(arc
							(start 0.508 0.2921)
							(mid 0.478242 0.363942)
							(end 0.4064 0.3937)
						)
						(arc
							(start -0.4064 0.3937)
							(mid -0.478242 0.363942)
							(end -0.508 0.2921)
						)
						(arc
							(start -0.508 -0.2921)
							(mid -0.478242 -0.363942)
							(end -0.4064 -0.3937)
						)
						(arc
							(start 0.4064 -0.3937)
							(mid 0.478242 -0.363942)
							(end 0.508 -0.2921)
						)
					)
					(width 0)
					(fill yes)
				)
			)
		)
	)
	(footprint ""
		(layer "B.Cu")
		(at 203.4794 -62.5348 90)
		(property "Reference" "PC161"
			(at 0 0 90)
			(layer "B.SilkS")
			(hide yes)
			(effects
				(font
					(size 1.27 1.27)
				)
				(justify mirror)
			)
		)
		(property "Value" "SC22U6D3V5MX-2GP"
			(at 0 -4.9022 90)
			(unlocked yes)
			(layer "B.Fab")
			(hide yes)
			(effects
				(font
					(size 1.016 1.016)
					(thickness 0.1524)
				)
				(justify mirror)
			)
		)
		(property "Device Type" "C805H58"
			(at 0 -6.8072 90)
			(unlocked yes)
			(layer "B.Fab")
			(hide yes)
			(effects
				(font
					(size 1.016 1.016)
					(thickness 0.1524)
				)
				(justify mirror)
			)
		)
		(duplicate_pad_numbers_are_jumpers no)
		(fp_line
			(start -0.6096 0)
			(end 0.6096 0)
			(stroke
				(width 0.3048)
				(type default)
			)
			(layer "B.SilkS")
		)
		(fp_poly
			(pts
				(xy 0.9017 1.4351) (xy -0.9017 1.4351) (xy -0.9017 -1.4351) (xy 0.9017 -1.4351)
			)
			(stroke
				(width 0)
				(type default)
			)
			(fill no)
			(layer "B.CrtYd")
		)
		(fp_poly
			(pts
				(xy -0.9017 1.4351) (xy -0.9017 -1.4351) (xy 0.9017 -1.4351) (xy 0.9017 1.4351)
			)
			(stroke
				(width 0)
				(type default)
			)
			(fill no)
			(layer "B.Fab")
		)
		(pad "1" smd rect
			(at 0 -0.8382 270)
			(size 1.5494 0.9398)
			(layers "B.Cu" "B.Mask" "B.Paste")
			(net "PV_VDDR")
		)
		(pad "2" smd rect
			(at 0 0.8382 270)
			(size 1.5494 0.9398)
			(layers "B.Cu" "B.Mask" "B.Paste")
			(net "GND")
		)
	)
	(footprint ""
		(layer "B.Cu")
		(at 106.970068 -46.361096)
		(property "Reference" "C148"
			(at 0 0 0)
			(layer "B.SilkS")
			(hide yes)
			(effects
				(font
					(size 1.27 1.27)
				)
				(justify mirror)
			)
		)
		(property "Value" "SC1U10V2KX-1GP"
			(at -1.1811 -2.7051 0)
			(unlocked yes)
			(layer "B.Fab")
			(hide yes)
			(effects
				(font
					(size 1.016 1.016)
					(thickness 0.1524)
				)
				(justify mirror)
			)
		)
		(property "Device Type" "C402H22"
			(at -1.1811 -4.2291 0)
			(unlocked yes)
			(layer "B.Fab")
			(hide yes)
			(effects
				(font
					(size 1.016 1.016)
					(thickness 0.1524)
				)
				(justify mirror)
			)
		)
		(duplicate_pad_numbers_are_jumpers no)
		(fp_rect
			(start 0.381 0.7366)
			(end -0.381 -0.7366)
			(stroke
				(width 0)
				(type default)
			)
			(fill no)
			(layer "B.CrtYd")
		)
		(fp_rect
			(start 0.381 0.7366)
			(end -0.381 -0.7366)
			(stroke
				(width 0)
				(type default)
			)
			(fill no)
			(layer "B.Fab")
		)
		(pad "1" smd custom
			(at 0 -0.4572 180)
			(size 0.1143 0.1143)
			(layers "B.Cu" "B.Mask" "B.Paste")
			(net "PV_VDDR")
			(options
				(clearance outline)
				(anchor circle)
			)
			(primitives
				(gr_poly
					(pts
						(arc
							(start -0.254 0.1778)
							(mid -0.239121 0.213721)
							(end -0.2032 0.2286)
						)
						(arc
							(start 0.2032 0.2286)
							(mid 0.239121 0.213721)
							(end 0.254 0.1778)
						)
						(arc
							(start 0.254 -0.1778)
							(mid 0.239121 -0.213721)
							(end 0.2032 -0.2286)
						)
						(arc
							(start -0.2032 -0.2286)
							(mid -0.239121 -0.213721)
							(end -0.254 -0.1778)
						)
					)
					(width 0)
					(fill yes)
				)
			)
		)
		(pad "2" smd custom
			(at 0 0.4572 180)
			(size 0.1143 0.1143)
			(layers "B.Cu" "B.Mask" "B.Paste")
			(net "GND")
			(options
				(clearance outline)
				(anchor circle)
			)
			(primitives
				(gr_poly
					(pts
						(arc
							(start -0.254 0.1778)
							(mid -0.239121 0.213721)
							(end -0.2032 0.2286)
						)
						(arc
							(start 0.2032 0.2286)
							(mid 0.239121 0.213721)
							(end 0.254 0.1778)
						)
						(arc
							(start 0.254 -0.1778)
							(mid 0.239121 -0.213721)
							(end 0.2032 -0.2286)
						)
						(arc
							(start -0.2032 -0.2286)
							(mid -0.239121 -0.213721)
							(end -0.254 -0.1778)
						)
					)
					(width 0)
					(fill yes)
				)
			)
		)
	)
	(footprint ""
		(layer "B.Cu")
		(at 107.823 -41.021 180)
		(property "Reference" "C175"
			(at 0 0 0)
			(layer "B.SilkS")
			(hide yes)
			(effects
				(font
					(size 1.27 1.27)
				)
				(justify mirror)
			)
		)
		(property "Value" "SC1U10V2KX-1GP"
			(at -1.1811 -2.7051 180)
			(unlocked yes)
			(layer "B.Fab")
			(hide yes)
			(effects
				(font
					(size 1.016 1.016)
					(thickness 0.1524)
				)
				(justify mirror)
			)
		)
		(property "Device Type" "C402H22"
			(at -1.1811 -4.2291 180)
			(unlocked yes)
			(layer "B.Fab")
			(hide yes)
			(effects
				(font
					(size 1.016 1.016)
					(thickness 0.1524)
				)
				(justify mirror)
			)
		)
		(duplicate_pad_numbers_are_jumpers no)
		(fp_rect
			(start 0.381 0.7366)
			(end -0.381 -0.7366)
			(stroke
				(width 0)
				(type default)
			)
			(fill no)
			(layer "B.CrtYd")
		)
		(fp_rect
			(start 0.381 0.7366)
			(end -0.381 -0.7366)
			(stroke
				(width 0)
				(type default)
			)
			(fill no)
			(layer "B.Fab")
		)
		(pad "1" smd custom
			(at 0 -0.4572)
			(size 0.1143 0.1143)
			(layers "B.Cu" "B.Mask" "B.Paste")
			(net "PVCCP")
			(options
				(clearance outline)
				(anchor circle)
			)
			(primitives
				(gr_poly
					(pts
						(arc
							(start -0.254 0.1778)
							(mid -0.239121 0.213721)
							(end -0.2032 0.2286)
						)
						(arc
							(start 0.2032 0.2286)
							(mid 0.239121 0.213721)
							(end 0.254 0.1778)
						)
						(arc
							(start 0.254 -0.1778)
							(mid 0.239121 -0.213721)
							(end 0.2032 -0.2286)
						)
						(arc
							(start -0.2032 -0.2286)
							(mid -0.239121 -0.213721)
							(end -0.254 -0.1778)
						)
					)
					(width 0)
					(fill yes)
				)
			)
		)
		(pad "2" smd custom
			(at 0 0.4572)
			(size 0.1143 0.1143)
			(layers "B.Cu" "B.Mask" "B.Paste")
			(net "GND")
			(options
				(clearance outline)
				(anchor circle)
			)
			(primitives
				(gr_poly
					(pts
						(arc
							(start -0.254 0.1778)
							(mid -0.239121 0.213721)
							(end -0.2032 0.2286)
						)
						(arc
							(start 0.2032 0.2286)
							(mid 0.239121 0.213721)
							(end 0.254 0.1778)
						)
						(arc
							(start 0.254 -0.1778)
							(mid 0.239121 -0.213721)
							(end 0.2032 -0.2286)
						)
						(arc
							(start -0.2032 -0.2286)
							(mid -0.239121 -0.213721)
							(end -0.254 -0.1778)
						)
					)
					(width 0)
					(fill yes)
				)
			)
		)
	)
	(footprint ""
		(layer "B.Cu")
		(at 87.122 -45.974 90)
		(property "Reference" "R311"
			(at 0 0 90)
			(layer "B.SilkS")
			(hide yes)
			(effects
				(font
					(size 1.27 1.27)
				)
				(justify mirror)
			)
		)
		(property "Value" "3KR2F-GP"
			(at -0.064008 -3.993896 90)
			(unlocked yes)
			(layer "B.Fab")
			(hide yes)
			(effects
				(font
					(size 1.016 1.016)
					(thickness 0.1524)
				)
				(justify mirror)
			)
		)
		(property "Device Type" "R402H16"
			(at -0.064008 -5.517896 90)
			(unlocked yes)
			(layer "B.Fab")
			(hide yes)
			(effects
				(font
					(size 1.016 1.016)
					(thickness 0.1524)
				)
				(justify mirror)
			)
		)
		(duplicate_pad_numbers_are_jumpers no)
		(fp_rect
			(start 0.381 0.8382)
			(end -0.381 -0.8382)
			(stroke
				(width 0)
				(type default)
			)
			(fill no)
			(layer "B.CrtYd")
		)
		(fp_rect
			(start 0.381 0.8382)
			(end -0.381 -0.8382)
			(stroke
				(width 0)
				(type default)
			)
			(fill no)
			(layer "B.Fab")
		)
		(pad "1" smd custom
			(at 0 -0.4318 270)
			(size 0.127 0.127)
			(layers "B.Cu" "B.Mask" "B.Paste")
			(net "PD_USB_OBSP")
			(options
				(clearance outline)
				(anchor circle)
			)
			(primitives
				(gr_poly
					(pts
						(arc
							(start -0.2032 0.2794)
							(mid -0.239121 0.264521)
							(end -0.254 0.2286)
						)
						(arc
							(start -0.254 -0.2286)
							(mid -0.239121 -0.264521)
							(end -0.2032 -0.2794)
						)
						(arc
							(start 0.2032 -0.2794)
							(mid 0.239121 -0.264521)
							(end 0.254 -0.2286)
						)
						(arc
							(start 0.254 0.2286)
							(mid 0.239121 0.264521)
							(end 0.2032 0.2794)
						)
					)
					(width 0)
					(fill yes)
				)
			)
		)
		(pad "2" smd custom
			(at 0 0.4318 270)
			(size 0.127 0.127)
			(layers "B.Cu" "B.Mask" "B.Paste")
			(net "GND")
			(options
				(clearance outline)
				(anchor circle)
			)
			(primitives
				(gr_poly
					(pts
						(arc
							(start -0.2032 0.2794)
							(mid -0.239121 0.264521)
							(end -0.254 0.2286)
						)
						(arc
							(start -0.254 -0.2286)
							(mid -0.239121 -0.264521)
							(end -0.2032 -0.2794)
						)
						(arc
							(start 0.2032 -0.2794)
							(mid 0.239121 -0.264521)
							(end 0.254 -0.2286)
						)
						(arc
							(start 0.254 0.2286)
							(mid 0.239121 0.264521)
							(end 0.2032 0.2794)
						)
					)
					(width 0)
					(fill yes)
				)
			)
		)
	)
	(footprint ""
		(layer "B.Cu")
		(at 95.758 -14.097 180)
		(property "Reference" "C318"
			(at 0 0 0)
			(layer "B.SilkS")
			(hide yes)
			(effects
				(font
					(size 1.27 1.27)
				)
				(justify mirror)
			)
		)
		(property "Value" "SC22U25V5MX-GP"
			(at 0 -4.9022 180)
			(unlocked yes)
			(layer "B.Fab")
			(hide yes)
			(effects
				(font
					(size 1.016 1.016)
					(thickness 0.1524)
				)
				(justify mirror)
			)
		)
		(property "Device Type" "C805H58"
			(at 0 -6.8072 180)
			(unlocked yes)
			(layer "B.Fab")
			(hide yes)
			(effects
				(font
					(size 1.016 1.016)
					(thickness 0.1524)
				)
				(justify mirror)
			)
		)
		(duplicate_pad_numbers_are_jumpers no)
		(fp_line
			(start -0.6096 0)
			(end 0.6096 0)
			(stroke
				(width 0.3048)
				(type default)
			)
			(layer "B.SilkS")
		)
		(fp_poly
			(pts
				(xy 0.9017 1.4351) (xy -0.9017 1.4351) (xy -0.9017 -1.4351) (xy 0.9017 -1.4351)
			)
			(stroke
				(width 0)
				(type default)
			)
			(fill no)
			(layer "B.CrtYd")
		)
		(fp_poly
			(pts
				(xy -0.9017 1.4351) (xy -0.9017 -1.4351) (xy 0.9017 -1.4351) (xy 0.9017 1.4351)
			)
			(stroke
				(width 0)
				(type default)
			)
			(fill no)
			(layer "B.Fab")
		)
		(pad "1" smd rect
			(at 0 -0.8382)
			(size 1.5494 0.9398)
			(layers "B.Cu" "B.Mask" "B.Paste")
			(net "P12V")
		)
		(pad "2" smd rect
			(at 0 0.8382)
			(size 1.5494 0.9398)
			(layers "B.Cu" "B.Mask" "B.Paste")
			(net "GND")
		)
	)
	(footprint ""
		(layer "B.Cu")
		(at 86.233 -15.113)
		(property "Reference" "PC202"
			(at 0 0 0)
			(layer "B.SilkS")
			(hide yes)
			(effects
				(font
					(size 1.27 1.27)
				)
				(justify mirror)
			)
		)
		(property "Value" "SC10U6D3V5KX-4GP"
			(at 0.0762 -6.1214 0)
			(unlocked yes)
			(layer "B.Fab")
			(hide yes)
			(effects
				(font
					(size 1.016 1.016)
					(thickness 0.1524)
				)
				(justify mirror)
			)
		)
		(property "Device Type" "C805H58"
			(at 0.0762 -8.1534 0)
			(unlocked yes)
			(layer "B.Fab")
			(hide yes)
			(effects
				(font
					(size 1.016 1.016)
					(thickness 0.1524)
				)
				(justify mirror)
			)
		)
		(duplicate_pad_numbers_are_jumpers no)
		(fp_line
			(start -0.6096 0)
			(end 0.6096 0)
			(stroke
				(width 0.3048)
				(type default)
			)
			(layer "B.SilkS")
		)
		(fp_poly
			(pts
				(xy 0.9017 1.4351) (xy -0.9017 1.4351) (xy -0.9017 -1.4351) (xy 0.9017 -1.4351)
			)
			(stroke
				(width 0)
				(type default)
			)
			(fill no)
			(layer "B.CrtYd")
		)
		(fp_poly
			(pts
				(xy -0.9017 1.4351) (xy -0.9017 -1.4351) (xy 0.9017 -1.4351) (xy 0.9017 1.4351)
			)
			(stroke
				(width 0)
				(type default)
			)
			(fill no)
			(layer "B.Fab")
		)
		(pad "1" smd rect
			(at 0 -0.8382 180)
			(size 1.5494 0.9398)
			(layers "B.Cu" "B.Mask" "B.Paste")
			(net "TPS74801_1V35_OUT")
		)
		(pad "2" smd rect
			(at 0 0.8382 180)
			(size 1.5494 0.9398)
			(layers "B.Cu" "B.Mask" "B.Paste")
			(net "GND")
		)
	)
	(footprint ""
		(layer "B.Cu")
		(at 158.500064 -66.699892 180)
		(property "Reference" "DIMM1"
			(at 0 0 0)
			(layer "B.SilkS")
			(hide yes)
			(effects
				(font
					(size 1.27 1.27)
				)
				(justify mirror)
			)
		)
		(property "Value" "DDR3-204P-142-COLAY-1-GP-U"
			(at 41.312338 -16.676878 180)
			(unlocked yes)
			(layer "B.Fab")
			(hide yes)
			(effects
				(font
					(size 1.016 1.016)
					(thickness 0.1524)
				)
				(justify mirror)
			)
		)
		(property "Device Type" "AS0A626-J8R6-7H-COLAY-1"
			(at 41.312338 -18.200878 180)
			(unlocked yes)
			(layer "B.Fab")
			(hide yes)
			(effects
				(font
					(size 1.016 1.016)
					(thickness 0.1524)
				)
				(justify mirror)
			)
		)
		(duplicate_pad_numbers_are_jumpers no)
		(fp_line
			(start 39.9542 -9.4488)
			(end 39.9542 -14.5542)
			(stroke
				(width 0.1524)
				(type default)
			)
			(layer "B.SilkS")
		)
		(fp_line
			(start 39.9542 -14.5542)
			(end 38.630606 -14.5542)
			(stroke
				(width 0.1524)
				(type default)
			)
			(layer "B.SilkS")
		)
		(fp_line
			(start 38.630606 -14.5542)
			(end 38.630606 -23.749)
			(stroke
				(width 0.1524)
				(type default)
			)
			(layer "B.SilkS")
		)
		(fp_line
			(start 38.630606 -23.749)
			(end 31.8516 -23.749)
			(stroke
				(width 0.1524)
				(type default)
			)
			(layer "B.SilkS")
		)
		(fp_line
			(start 37.7571 -1.7526)
			(end 37.7571 -9.4488)
			(stroke
				(width 0.1524)
				(type default)
			)
			(layer "B.SilkS")
		)
		(fp_line
			(start 37.7571 -9.4488)
			(end 39.9542 -9.4488)
			(stroke
				(width 0.1524)
				(type default)
			)
			(layer "B.SilkS")
		)
		(fp_line
			(start 37.2491 0.254)
			(end 37.2491 -1.7526)
			(stroke
				(width 0.1524)
				(type default)
			)
			(layer "B.SilkS")
		)
		(fp_line
			(start 37.2491 -1.7526)
			(end 37.7571 -1.7526)
			(stroke
				(width 0.1524)
				(type default)
			)
			(layer "B.SilkS")
		)
		(fp_line
			(start 36.2585 5.2578)
			(end 36.2585 0.254)
			(stroke
				(width 0.1524)
				(type default)
			)
			(layer "B.SilkS")
		)
		(fp_line
			(start 36.2585 0.254)
			(end 37.2491 0.254)
			(stroke
				(width 0.1524)
				(type default)
			)
			(layer "B.SilkS")
		)
		(fp_line
			(start 32.17672 5.91566)
			(end 31.16072 5.91566)
			(stroke
				(width 0.1524)
				(type default)
			)
			(layer "B.SilkS")
		)
		(fp_line
			(start 31.8516 -21.3614)
			(end 31.3436 -21.3614)
			(stroke
				(width 0.1524)
				(type default)
			)
			(layer "B.SilkS")
		)
		(fp_line
			(start 31.8516 -23.749)
			(end 31.8516 -21.3614)
			(stroke
				(width 0.1524)
				(type default)
			)
			(layer "B.SilkS")
		)
		(fp_line
			(start 31.66872 6.42366)
			(end 31.66872 5.40766)
			(stroke
				(width 0.1524)
				(type default)
			)
			(layer "B.SilkS")
		)
		(fp_line
			(start 31.66872 5.40766)
			(end 32.17672 5.91566)
			(stroke
				(width 0.1524)
				(type default)
			)
			(layer "B.SilkS")
		)
		(fp_line
			(start 31.3436 -5.2578)
			(end -31.3436 -5.2578)
			(stroke
				(width 0.1524)
				(type default)
			)
			(layer "B.SilkS")
		)
		(fp_line
			(start 31.3436 -9.4488)
			(end 31.3436 -5.2578)
			(stroke
				(width 0.1524)
				(type default)
			)
			(layer "B.SilkS")
		)
		(fp_line
			(start 31.3436 -14.5542)
			(end 30.7975 -14.5542)
			(stroke
				(width 0.1524)
				(type default)
			)
			(layer "B.SilkS")
		)
		(fp_line
			(start 31.3436 -21.3614)
			(end 31.3436 -14.5542)
			(stroke
				(width 0.1524)
				(type default)
			)
			(layer "B.SilkS")
		)
		(fp_line
			(start 31.16072 5.91566)
			(end 31.66872 5.40766)
			(stroke
				(width 0.1524)
				(type default)
			)
			(layer "B.SilkS")
		)
		(fp_line
			(start 30.7975 -9.4488)
			(end 31.3436 -9.4488)
			(stroke
				(width 0.1524)
				(type default)
			)
			(layer "B.SilkS")
		)
		(fp_line
			(start 30.7975 -14.5542)
			(end 30.7975 -9.4488)
			(stroke
				(width 0.1524)
				(type default)
			)
			(layer "B.SilkS")
		)
		(fp_line
			(start -30.7975 -9.4488)
			(end -30.7975 -14.5542)
			(stroke
				(width 0.1524)
				(type default)
			)
			(layer "B.SilkS")
		)
		(fp_line
			(start -30.7975 -14.5542)
			(end -31.3436 -14.5542)
			(stroke
				(width 0.1524)
				(type default)
			)
			(layer "B.SilkS")
		)
		(fp_line
			(start -31.0515 -5.9055)
			(end -32.0675 -5.9055)
			(stroke
				(width 0.1524)
				(type default)
			)
			(layer "B.SilkS")
		)
		(fp_line
			(start -31.3436 -5.2578)
			(end -31.3436 -9.4488)
			(stroke
				(width 0.1524)
				(type default)
			)
			(layer "B.SilkS")
		)
		(fp_line
			(start -31.3436 -9.4488)
			(end -30.7975 -9.4488)
			(stroke
				(width 0.1524)
				(type default)
			)
			(layer "B.SilkS")
		)
		(fp_line
			(start -31.3436 -14.5542)
			(end -31.3436 -21.3614)
			(stroke
				(width 0.1524)
				(type default)
			)
			(layer "B.SilkS")
		)
		(fp_line
			(start -31.3436 -21.3614)
			(end -31.8516 -21.3614)
			(stroke
				(width 0.1524)
				(type default)
			)
			(layer "B.SilkS")
		)
		(fp_line
			(start -31.5595 -5.3975)
			(end -31.0515 -5.9055)
			(stroke
				(width 0.1524)
				(type default)
			)
			(layer "B.SilkS")
		)
		(fp_line
			(start -31.5595 -6.4135)
			(end -31.5595 -5.3975)
			(stroke
				(width 0.1524)
				(type default)
			)
			(layer "B.SilkS")
		)
		(fp_line
			(start -31.8516 -21.3614)
			(end -31.8516 -23.749)
			(stroke
				(width 0.1524)
				(type default)
			)
			(layer "B.SilkS")
		)
		(fp_line
			(start -31.8516 -23.749)
			(end -38.630606 -23.749)
			(stroke
				(width 0.1524)
				(type default)
			)
			(layer "B.SilkS")
		)
		(fp_line
			(start -32.0675 -5.9055)
			(end -31.5595 -5.3975)
			(stroke
				(width 0.1524)
				(type default)
			)
			(layer "B.SilkS")
		)
		(fp_line
			(start -36.2585 5.2578)
			(end 36.2585 5.2578)
			(stroke
				(width 0.1524)
				(type default)
			)
			(layer "B.SilkS")
		)
		(fp_line
			(start -36.2585 0.254)
			(end -36.2585 5.2578)
			(stroke
				(width 0.1524)
				(type default)
			)
			(layer "B.SilkS")
		)
		(fp_line
			(start -37.2491 0.254)
			(end -36.2585 0.254)
			(stroke
				(width 0.1524)
				(type default)
			)
			(layer "B.SilkS")
		)
		(fp_line
			(start -37.2491 -1.7526)
			(end -37.2491 0.254)
			(stroke
				(width 0.1524)
				(type default)
			)
			(layer "B.SilkS")
		)
		(fp_line
			(start -37.7571 -1.7526)
			(end -37.2491 -1.7526)
			(stroke
				(width 0.1524)
				(type default)
			)
			(layer "B.SilkS")
		)
		(fp_line
			(start -37.7571 -9.4488)
			(end -37.7571 -1.7526)
			(stroke
				(width 0.1524)
				(type default)
			)
			(layer "B.SilkS")
		)
		(fp_line
			(start -38.630606 -14.5542)
			(end -39.9542 -14.5542)
			(stroke
				(width 0.1524)
				(type default)
			)
			(layer "B.SilkS")
		)
		(fp_line
			(start -38.630606 -23.749)
			(end -38.630606 -14.5542)
			(stroke
				(width 0.1524)
				(type default)
			)
			(layer "B.SilkS")
		)
		(fp_line
			(start -39.9542 -9.4488)
			(end -37.7571 -9.4488)
			(stroke
				(width 0.1524)
				(type default)
			)
			(layer "B.SilkS")
		)
		(fp_line
			(start -39.9542 -14.5542)
			(end -39.9542 -9.4488)
			(stroke
				(width 0.1524)
				(type default)
			)
			(layer "B.SilkS")
		)
		(fp_poly
			(pts
				(xy 32.536384 -2.995168) (xy 32.536384 2.995168) (xy -32.295084 2.995168) (xy -32.295084 -2.995168)
			)
			(stroke
				(width 0)
				(type default)
			)
			(fill yes)
			(layer "B.SilkS")
		)
		(fp_poly
			(pts
				(xy 36.2585 5.2578) (xy 36.2585 0.254) (xy 37.2491 0.254) (xy 37.2491 -1.7526) (xy 37.7571 -1.7526)
				(xy 37.7571 -9.4488) (xy 39.9542 -9.4488) (xy 39.9542 -14.5542) (xy 38.630606 -14.5542) (xy 38.630606 -23.749)
				(xy 31.8516 -23.749) (xy 31.8516 -21.3614) (xy 31.3436 -21.3614) (xy 31.3436 -14.5542) (xy 30.7975 -14.5542)
				(xy 30.7975 -9.4488) (xy 31.3436 -9.4488) (xy 31.3436 -5.2578) (xy -31.3436 -5.2578) (xy -31.3436 -9.4488)
				(xy -30.7975 -9.4488) (xy -30.7975 -14.5542) (xy -31.3436 -14.5542) (xy -31.3436 -21.3614) (xy -31.8516 -21.3614)
				(xy -31.8516 -23.749) (xy -38.630606 -23.749) (xy -38.630606 -14.5542) (xy -39.9542 -14.5542) (xy -39.9542 -9.4488)
				(xy -37.7571 -9.4488) (xy -37.7571 -1.7526) (xy -37.2491 -1.7526) (xy -37.2491 0.254) (xy -36.2585 0.254)
				(xy -36.2585 5.2578)
			)
			(stroke
				(width 0)
				(type default)
			)
			(fill no)
			(layer "B.CrtYd")
		)
		(fp_poly
			(pts
				(xy 36.2585 5.2578) (xy 36.2585 0.254) (xy 37.2491 0.254) (xy 37.2491 -1.7526) (xy 37.7571 -1.7526)
				(xy 37.7571 -9.4488) (xy 39.9542 -9.4488) (xy 39.9542 -14.5542) (xy 38.630606 -14.5542) (xy 38.630606 -23.749)
				(xy 31.8516 -23.749) (xy 31.8516 -21.3614) (xy 31.3436 -21.3614) (xy 31.3436 -14.5542) (xy 30.7975 -14.5542)
				(xy 30.7975 -9.4488) (xy 31.3436 -9.4488) (xy 31.3436 -5.2578) (xy -31.3436 -5.2578) (xy -31.3436 -9.4488)
				(xy -30.7975 -9.4488) (xy -30.7975 -14.5542) (xy -31.3436 -14.5542) (xy -31.3436 -21.3614) (xy -31.8516 -21.3614)
				(xy -31.8516 -23.749) (xy -38.630606 -23.749) (xy -38.630606 -14.5542) (xy -39.9542 -14.5542) (xy -39.9542 -9.4488)
				(xy -37.7571 -9.4488) (xy -37.7571 -1.7526) (xy -37.2491 -1.7526) (xy -37.2491 0.254) (xy -36.2585 0.254)
				(xy -36.2585 5.2578)
			)
			(stroke
				(width 0)
				(type default)
			)
			(fill no)
			(layer "B.Fab")
		)
		(fp_text user "204"
			(at 34.929064 6.166358 180)
			(unlocked yes)
			(layer "B.SilkS")
			(effects
				(font
					(size 0.635 0.635)
					(thickness 0.1524)
				)
				(justify left mirror)
			)
		)
		(fp_text user "1"
			(at -32.507936 -6.724142 0)
			(unlocked yes)
			(layer "B.SilkS")
			(effects
				(font
					(size 0.635 0.635)
					(thickness 0.1524)
				)
				(justify left mirror)
			)
		)
		(pad "" np_thru_hole circle
			(at -33.399984 0)
			(size 0.254 0.254)
			(drill 1.6002)
			(layers "*.Cu" "*.Mask")
			(clearance 1.0287)
			(thermal_gap 1.0287)
		)
		(pad "" np_thru_hole circle
			(at 33.399984 0)
			(size 0.254 0.254)
			(drill 1.1176)
			(layers "*.Cu" "*.Mask")
			(clearance 0.7874)
			(thermal_gap 0.7874)
		)
		(pad "1" smd custom
			(at -31.649924 -4.100068)
			(size 0.1143 0.1143)
			(layers "B.Cu" "B.Mask" "B.Paste")
			(net "DDR3_M_A_VREF_DQ0")
			(options
				(clearance outline)
				(anchor circle)
			)
			(primitives
				(gr_poly
					(pts
						(xy 0 -0.9017) (xy -0.03175 -0.89916) (xy -0.0635 -0.889) (xy -0.09144 -0.87376) (xy -0.11684 -0.85344)
						(xy -0.13716 -0.82804) (xy -0.1524 -0.8001) (xy -0.16256 -0.76835) (xy -0.1651 -0.7366) (xy -0.1651 -0.44958)
						(xy -0.17272 -0.44196) (xy -0.19812 -0.4064) (xy -0.2032 -0.39624) (xy -0.20701 -0.38735) (xy -0.21209 -0.37719)
						(xy -0.2159 -0.36703) (xy -0.21844 -0.35687) (xy -0.22225 -0.34544) (xy -0.22352 -0.33528) (xy -0.22606 -0.32512)
						(xy -0.22733 -0.31369) (xy -0.22733 -0.30353) (xy -0.2286 -0.2921) (xy -0.22733 -0.28067) (xy -0.22733 -0.27051)
						(xy -0.22606 -0.25908) (xy -0.22352 -0.24892) (xy -0.22225 -0.23876) (xy -0.21844 -0.22733) (xy -0.2159 -0.21717)
						(xy -0.21209 -0.20701) (xy -0.20701 -0.19685) (xy -0.2032 -0.18796) (xy -0.19812 -0.1778) (xy -0.17272 -0.14224)
						(xy -0.1651 -0.13462) (xy -0.1651 0.7366) (xy -0.16256 0.76835) (xy -0.1524 0.8001) (xy -0.13716 0.82804)
						(xy -0.11684 0.85344) (xy -0.09144 0.87376) (xy -0.0635 0.889) (xy -0.03175 0.89916) (xy 0 0.9017)
						(xy 0.03175 0.89916) (xy 0.0635 0.889) (xy 0.09144 0.87376) (xy 0.11684 0.85344) (xy 0.13716 0.82804)
						(xy 0.1524 0.8001) (xy 0.16256 0.76835) (xy 0.1651 0.7366) (xy 0.1651 -0.13462) (xy 0.17272 -0.14224)
						(xy 0.19812 -0.1778) (xy 0.2032 -0.18796) (xy 0.20701 -0.19685) (xy 0.21209 -0.20701) (xy 0.2159 -0.21717)
						(xy 0.21844 -0.22733) (xy 0.22225 -0.23876) (xy 0.22352 -0.24892) (xy 0.22606 -0.25908) (xy 0.22733 -0.27051)
						(xy 0.22733 -0.28067) (xy 0.2286 -0.2921) (xy 0.22733 -0.30353) (xy 0.22733 -0.31369) (xy 0.22606 -0.32512)
						(xy 0.22352 -0.33528) (xy 0.22225 -0.34544) (xy 0.21844 -0.35687) (xy 0.2159 -0.36703) (xy 0.21209 -0.37719)
						(xy 0.20701 -0.38735) (xy 0.2032 -0.39624) (xy 0.19812 -0.4064) (xy 0.17272 -0.44196) (xy 0.1651 -0.44958)
						(xy 0.1651 -0.7366) (xy 0.16256 -0.76835) (xy 0.1524 -0.8001) (xy 0.13716 -0.82804) (xy 0.11684 -0.85344)
						(xy 0.09144 -0.87376) (xy 0.0635 -0.889) (xy 0.03175 -0.89916)
					)
					(width 0)
					(fill yes)
				)
			)
		)
		(pad "2" smd custom
			(at -31.34995 4.100068)
			(size 0.1143 0.1143)
			(layers "B.Cu" "B.Mask" "B.Paste")
			(net "GND")
			(options
				(clearance outline)
				(anchor circle)
			)
			(primitives
				(gr_poly
					(pts
						(xy 0 -0.9017) (xy -0.03175 -0.89916) (xy -0.0635 -0.889) (xy -0.09144 -0.87376) (xy -0.11684 -0.85344)
						(xy -0.13716 -0.82804) (xy -0.1524 -0.8001) (xy -0.16256 -0.76835) (xy -0.1651 -0.7366) (xy -0.1651 0.13462)
						(xy -0.17272 0.14224) (xy -0.19812 0.1778) (xy -0.2032 0.18796) (xy -0.20701 0.19685) (xy -0.21209 0.20701)
						(xy -0.2159 0.21717) (xy -0.21844 0.22733) (xy -0.22225 0.23876) (xy -0.22352 0.24892) (xy -0.22606 0.25908)
						(xy -0.22733 0.27051) (xy -0.22733 0.28067) (xy -0.2286 0.2921) (xy -0.22733 0.30353) (xy -0.22733 0.31369)
						(xy -0.22606 0.32512) (xy -0.22352 0.33528) (xy -0.22225 0.34544) (xy -0.21844 0.35687) (xy -0.2159 0.36703)
						(xy -0.21209 0.37719) (xy -0.20701 0.38735) (xy -0.2032 0.39624) (xy -0.19812 0.4064) (xy -0.17272 0.44196)
						(xy -0.1651 0.44958) (xy -0.1651 0.7366) (xy -0.16256 0.76835) (xy -0.1524 0.8001) (xy -0.13716 0.82804)
						(xy -0.11684 0.85344) (xy -0.09144 0.87376) (xy -0.0635 0.889) (xy -0.03175 0.89916) (xy 0 0.9017)
						(xy 0.03175 0.89916) (xy 0.0635 0.889) (xy 0.09144 0.87376) (xy 0.11684 0.85344) (xy 0.13716 0.82804)
						(xy 0.1524 0.8001) (xy 0.16256 0.76835) (xy 0.1651 0.7366) (xy 0.1651 0.44958) (xy 0.17272 0.44196)
						(xy 0.19812 0.4064) (xy 0.2032 0.39624) (xy 0.20701 0.38735) (xy 0.21209 0.37719) (xy 0.2159 0.36703)
						(xy 0.21844 0.35687) (xy 0.22225 0.34544) (xy 0.22352 0.33528) (xy 0.22606 0.32512) (xy 0.22733 0.31369)
						(xy 0.22733 0.30353) (xy 0.2286 0.2921) (xy 0.22733 0.28067) (xy 0.22733 0.27051) (xy 0.22606 0.25908)
						(xy 0.22352 0.24892) (xy 0.22225 0.23876) (xy 0.21844 0.22733) (xy 0.2159 0.21717) (xy 0.21209 0.20701)
						(xy 0.20701 0.19685) (xy 0.2032 0.18796) (xy 0.19812 0.1778) (xy 0.17272 0.14224) (xy 0.1651 0.13462)
						(xy 0.1651 -0.7366) (xy 0.16256 -0.76835) (xy 0.1524 -0.8001) (xy 0.13716 -0.82804) (xy 0.11684 -0.85344)
						(xy 0.09144 -0.87376) (xy 0.0635 -0.889) (xy 0.03175 -0.89916)
					)
					(width 0)
					(fill yes)
				)
			)
		)
		(pad "3" smd custom
			(at -31.049976 -4.100068)
			(size 0.1143 0.1143)
			(layers "B.Cu" "B.Mask" "B.Paste")
			(net "GND")
			(options
				(clearance outline)
				(anchor circle)
			)
			(primitives
				(gr_poly
					(pts
						(xy 0 -0.9017) (xy -0.03175 -0.89916) (xy -0.0635 -0.889) (xy -0.09144 -0.87376) (xy -0.11684 -0.85344)
						(xy -0.13716 -0.82804) (xy -0.1524 -0.8001) (xy -0.16256 -0.76835) (xy -0.1651 -0.7366) (xy -0.1651 -0.19685)
						(xy -0.17272 -0.18923) (xy -0.17907 -0.18034) (xy -0.18669 -0.17145) (xy -0.19177 -0.16256) (xy -0.19812 -0.15367)
						(xy -0.20828 -0.13335) (xy -0.21971 -0.10287) (xy -0.22225 -0.09271) (xy -0.22479 -0.08128) (xy -0.22606 -0.07112)
						(xy -0.2286 -0.05969) (xy -0.2286 -0.01651) (xy -0.22606 -0.00508) (xy -0.22479 0.00508) (xy -0.22225 0.01651)
						(xy -0.21971 0.02667) (xy -0.20828 0.05715) (xy -0.19812 0.07747) (xy -0.19177 0.08636) (xy -0.18669 0.09525)
						(xy -0.17907 0.10414) (xy -0.17272 0.11303) (xy -0.1651 0.12065) (xy -0.1651 0.7366) (xy -0.16256 0.76835)
						(xy -0.1524 0.8001) (xy -0.13716 0.82804) (xy -0.11684 0.85344) (xy -0.09144 0.87376) (xy -0.0635 0.889)
						(xy -0.03175 0.89916) (xy 0 0.9017) (xy 0.03175 0.89916) (xy 0.0635 0.889) (xy 0.09144 0.87376)
						(xy 0.11684 0.85344) (xy 0.13716 0.82804) (xy 0.1524 0.8001) (xy 0.16256 0.76835) (xy 0.1651 0.7366)
						(xy 0.1651 0.11938) (xy 0.17272 0.11176) (xy 0.19812 0.0762) (xy 0.2032 0.06604) (xy 0.20701 0.05715)
						(xy 0.21209 0.04699) (xy 0.2159 0.03683) (xy 0.21844 0.02667) (xy 0.22225 0.01524) (xy 0.22352 0.00508)
						(xy 0.22606 -0.00508) (xy 0.22733 -0.01651) (xy 0.22733 -0.02667) (xy 0.2286 -0.0381) (xy 0.22733 -0.04953)
						(xy 0.22733 -0.05969) (xy 0.22606 -0.07112) (xy 0.22352 -0.08128) (xy 0.22225 -0.09144) (xy 0.21844 -0.10287)
						(xy 0.2159 -0.11303) (xy 0.21209 -0.12319) (xy 0.20701 -0.13335) (xy 0.2032 -0.14224) (xy 0.19812 -0.1524)
						(xy 0.17272 -0.18796) (xy 0.1651 -0.19558) (xy 0.1651 -0.7366) (xy 0.16256 -0.76835) (xy 0.1524 -0.8001)
						(xy 0.13716 -0.82804) (xy 0.11684 -0.85344) (xy 0.09144 -0.87376) (xy 0.0635 -0.889) (xy 0.03175 -0.89916)
					)
					(width 0)
					(fill yes)
				)
			)
		)
		(pad "4" smd custom
			(at -30.750002 4.100068)
			(size 0.1143 0.1143)
			(layers "B.Cu" "B.Mask" "B.Paste")
			(net "M_A_DQ4")
			(options
				(clearance outline)
				(anchor circle)
			)
			(primitives
				(gr_poly
					(pts
						(xy 0 -0.9017) (xy -0.03175 -0.89916) (xy -0.0635 -0.889) (xy -0.09144 -0.87376) (xy -0.11684 -0.85344)
						(xy -0.13716 -0.82804) (xy -0.1524 -0.8001) (xy -0.16256 -0.76835) (xy -0.1651 -0.7366) (xy -0.1651 -0.11938)
						(xy -0.17272 -0.11176) (xy -0.19812 -0.0762) (xy -0.2032 -0.06604) (xy -0.20701 -0.05715) (xy -0.21209 -0.04699)
						(xy -0.2159 -0.03683) (xy -0.21844 -0.02667) (xy -0.22225 -0.01524) (xy -0.22352 -0.00508) (xy -0.22606 0.00508)
						(xy -0.22733 0.01651) (xy -0.22733 0.02667) (xy -0.2286 0.0381) (xy -0.22733 0.04953) (xy -0.22733 0.05969)
						(xy -0.22606 0.07112) (xy -0.22352 0.08128) (xy -0.22225 0.09144) (xy -0.21844 0.10287) (xy -0.2159 0.11303)
						(xy -0.21209 0.12319) (xy -0.20701 0.13335) (xy -0.2032 0.14224) (xy -0.19812 0.1524) (xy -0.17272 0.18796)
						(xy -0.1651 0.19558) (xy -0.1651 0.7366) (xy -0.16256 0.76835) (xy -0.1524 0.8001) (xy -0.13716 0.82804)
						(xy -0.11684 0.85344) (xy -0.09144 0.87376) (xy -0.0635 0.889) (xy -0.03175 0.89916) (xy 0 0.9017)
						(xy 0.03175 0.89916) (xy 0.0635 0.889) (xy 0.09144 0.87376) (xy 0.11684 0.85344) (xy 0.13716 0.82804)
						(xy 0.1524 0.8001) (xy 0.16256 0.76835) (xy 0.1651 0.7366) (xy 0.1651 0.19685) (xy 0.17272 0.18923)
						(xy 0.17907 0.18034) (xy 0.18669 0.17145) (xy 0.19177 0.16256) (xy 0.19812 0.15367) (xy 0.20828 0.13335)
						(xy 0.21971 0.10287) (xy 0.22225 0.09271) (xy 0.22479 0.08128) (xy 0.22606 0.07112) (xy 0.2286 0.05969)
						(xy 0.2286 0.01651) (xy 0.22606 0.00508) (xy 0.22479 -0.00508) (xy 0.22225 -0.01651) (xy 0.21971 -0.02667)
						(xy 0.20828 -0.05715) (xy 0.19812 -0.07747) (xy 0.19177 -0.08636) (xy 0.18669 -0.09525) (xy 0.17907 -0.10414)
						(xy 0.17272 -0.11303) (xy 0.1651 -0.12065) (xy 0.1651 -0.7366) (xy 0.16256 -0.76835) (xy 0.1524 -0.8001)
						(xy 0.13716 -0.82804) (xy 0.11684 -0.85344) (xy 0.09144 -0.87376) (xy 0.0635 -0.889) (xy 0.03175 -0.89916)
					)
					(width 0)
					(fill yes)
				)
			)
		)
		(pad "5" smd custom
			(at -30.450028 -4.100068)
			(size 0.1143 0.1143)
			(layers "B.Cu" "B.Mask" "B.Paste")
			(net "M_A_DQ0")
			(options
				(clearance outline)
				(anchor circle)
			)
			(primitives
				(gr_poly
					(pts
						(xy 0 -0.9017) (xy -0.03175 -0.89916) (xy -0.0635 -0.889) (xy -0.09144 -0.87376) (xy -0.11684 -0.85344)
						(xy -0.13716 -0.82804) (xy -0.1524 -0.8001) (xy -0.16256 -0.76835) (xy -0.1651 -0.7366) (xy -0.1651 -0.44958)
						(xy -0.17272 -0.44196) (xy -0.19812 -0.4064) (xy -0.2032 -0.39624) (xy -0.20701 -0.38735) (xy -0.21209 -0.37719)
						(xy -0.2159 -0.36703) (xy -0.21844 -0.35687) (xy -0.22225 -0.34544) (xy -0.22352 -0.33528) (xy -0.22606 -0.32512)
						(xy -0.22733 -0.31369) (xy -0.22733 -0.30353) (xy -0.2286 -0.2921) (xy -0.22733 -0.28067) (xy -0.22733 -0.27051)
						(xy -0.22606 -0.25908) (xy -0.22352 -0.24892) (xy -0.22225 -0.23876) (xy -0.21844 -0.22733) (xy -0.2159 -0.21717)
						(xy -0.21209 -0.20701) (xy -0.20701 -0.19685) (xy -0.2032 -0.18796) (xy -0.19812 -0.1778) (xy -0.17272 -0.14224)
						(xy -0.1651 -0.13462) (xy -0.1651 0.7366) (xy -0.16256 0.76835) (xy -0.1524 0.8001) (xy -0.13716 0.82804)
						(xy -0.11684 0.85344) (xy -0.09144 0.87376) (xy -0.0635 0.889) (xy -0.03175 0.89916) (xy 0 0.9017)
						(xy 0.03175 0.89916) (xy 0.0635 0.889) (xy 0.09144 0.87376) (xy 0.11684 0.85344) (xy 0.13716 0.82804)
						(xy 0.1524 0.8001) (xy 0.16256 0.76835) (xy 0.1651 0.7366) (xy 0.1651 -0.13462) (xy 0.17272 -0.14224)
						(xy 0.19812 -0.1778) (xy 0.2032 -0.18796) (xy 0.20701 -0.19685) (xy 0.21209 -0.20701) (xy 0.2159 -0.21717)
						(xy 0.21844 -0.22733) (xy 0.22225 -0.23876) (xy 0.22352 -0.24892) (xy 0.22606 -0.25908) (xy 0.22733 -0.27051)
						(xy 0.22733 -0.28067) (xy 0.2286 -0.2921) (xy 0.22733 -0.30353) (xy 0.22733 -0.31369) (xy 0.22606 -0.32512)
						(xy 0.22352 -0.33528) (xy 0.22225 -0.34544) (xy 0.21844 -0.35687) (xy 0.2159 -0.36703) (xy 0.21209 -0.37719)
						(xy 0.20701 -0.38735) (xy 0.2032 -0.39624) (xy 0.19812 -0.4064) (xy 0.17272 -0.44196) (xy 0.1651 -0.44958)
						(xy 0.1651 -0.7366) (xy 0.16256 -0.76835) (xy 0.1524 -0.8001) (xy 0.13716 -0.82804) (xy 0.11684 -0.85344)
						(xy 0.09144 -0.87376) (xy 0.0635 -0.889) (xy 0.03175 -0.89916)
					)
					(width 0)
					(fill yes)
				)
			)
		)
		(pad "6" smd custom
			(at -30.150054 4.100068)
			(size 0.1143 0.1143)
			(layers "B.Cu" "B.Mask" "B.Paste")
			(net "M_A_DQ5")
			(options
				(clearance outline)
				(anchor circle)
			)
			(primitives
				(gr_poly
					(pts
						(xy 0 -0.9017) (xy -0.03175 -0.89916) (xy -0.0635 -0.889) (xy -0.09144 -0.87376) (xy -0.11684 -0.85344)
						(xy -0.13716 -0.82804) (xy -0.1524 -0.8001) (xy -0.16256 -0.76835) (xy -0.1651 -0.7366) (xy -0.1651 0.13462)
						(xy -0.17272 0.14224) (xy -0.19812 0.1778) (xy -0.2032 0.18796) (xy -0.20701 0.19685) (xy -0.21209 0.20701)
						(xy -0.2159 0.21717) (xy -0.21844 0.22733) (xy -0.22225 0.23876) (xy -0.22352 0.24892) (xy -0.22606 0.25908)
						(xy -0.22733 0.27051) (xy -0.22733 0.28067) (xy -0.2286 0.2921) (xy -0.22733 0.30353) (xy -0.22733 0.31369)
						(xy -0.22606 0.32512) (xy -0.22352 0.33528) (xy -0.22225 0.34544) (xy -0.21844 0.35687) (xy -0.2159 0.36703)
						(xy -0.21209 0.37719) (xy -0.20701 0.38735) (xy -0.2032 0.39624) (xy -0.19812 0.4064) (xy -0.17272 0.44196)
						(xy -0.1651 0.44958) (xy -0.1651 0.7366) (xy -0.16256 0.76835) (xy -0.1524 0.8001) (xy -0.13716 0.82804)
						(xy -0.11684 0.85344) (xy -0.09144 0.87376) (xy -0.0635 0.889) (xy -0.03175 0.89916) (xy 0 0.9017)
						(xy 0.03175 0.89916) (xy 0.0635 0.889) (xy 0.09144 0.87376) (xy 0.11684 0.85344) (xy 0.13716 0.82804)
						(xy 0.1524 0.8001) (xy 0.16256 0.76835) (xy 0.1651 0.7366) (xy 0.1651 0.44958) (xy 0.17272 0.44196)
						(xy 0.19812 0.4064) (xy 0.2032 0.39624) (xy 0.20701 0.38735) (xy 0.21209 0.37719) (xy 0.2159 0.36703)
						(xy 0.21844 0.35687) (xy 0.22225 0.34544) (xy 0.22352 0.33528) (xy 0.22606 0.32512) (xy 0.22733 0.31369)
						(xy 0.22733 0.30353) (xy 0.2286 0.2921) (xy 0.22733 0.28067) (xy 0.22733 0.27051) (xy 0.22606 0.25908)
						(xy 0.22352 0.24892) (xy 0.22225 0.23876) (xy 0.21844 0.22733) (xy 0.2159 0.21717) (xy 0.21209 0.20701)
						(xy 0.20701 0.19685) (xy 0.2032 0.18796) (xy 0.19812 0.1778) (xy 0.17272 0.14224) (xy 0.1651 0.13462)
						(xy 0.1651 -0.7366) (xy 0.16256 -0.76835) (xy 0.1524 -0.8001) (xy 0.13716 -0.82804) (xy 0.11684 -0.85344)
						(xy 0.09144 -0.87376) (xy 0.0635 -0.889) (xy 0.03175 -0.89916)
					)
					(width 0)
					(fill yes)
				)
			)
		)
		(pad "7" smd custom
			(at -29.85008 -4.100068)
			(size 0.1143 0.1143)
			(layers "B.Cu" "B.Mask" "B.Paste")
			(net "M_A_DQ1")
			(options
				(clearance outline)
				(anchor circle)
			)
			(primitives
				(gr_poly
					(pts
						(xy 0 -0.9017) (xy -0.03175 -0.89916) (xy -0.0635 -0.889) (xy -0.09144 -0.87376) (xy -0.11684 -0.85344)
						(xy -0.13716 -0.82804) (xy -0.1524 -0.8001) (xy -0.16256 -0.76835) (xy -0.1651 -0.7366) (xy -0.1651 -0.19685)
						(xy -0.17272 -0.18923) (xy -0.17907 -0.18034) (xy -0.18669 -0.17145) (xy -0.19177 -0.16256) (xy -0.19812 -0.15367)
						(xy -0.20828 -0.13335) (xy -0.21971 -0.10287) (xy -0.22225 -0.09271) (xy -0.22479 -0.08128) (xy -0.22606 -0.07112)
						(xy -0.2286 -0.05969) (xy -0.2286 -0.01651) (xy -0.22606 -0.00508) (xy -0.22479 0.00508) (xy -0.22225 0.01651)
						(xy -0.21971 0.02667) (xy -0.20828 0.05715) (xy -0.19812 0.07747) (xy -0.19177 0.08636) (xy -0.18669 0.09525)
						(xy -0.17907 0.10414) (xy -0.17272 0.11303) (xy -0.1651 0.12065) (xy -0.1651 0.7366) (xy -0.16256 0.76835)
						(xy -0.1524 0.8001) (xy -0.13716 0.82804) (xy -0.11684 0.85344) (xy -0.09144 0.87376) (xy -0.0635 0.889)
						(xy -0.03175 0.89916) (xy 0 0.9017) (xy 0.03175 0.89916) (xy 0.0635 0.889) (xy 0.09144 0.87376)
						(xy 0.11684 0.85344) (xy 0.13716 0.82804) (xy 0.1524 0.8001) (xy 0.16256 0.76835) (xy 0.1651 0.7366)
						(xy 0.1651 0.11938) (xy 0.17272 0.11176) (xy 0.19812 0.0762) (xy 0.2032 0.06604) (xy 0.20701 0.05715)
						(xy 0.21209 0.04699) (xy 0.2159 0.03683) (xy 0.21844 0.02667) (xy 0.22225 0.01524) (xy 0.22352 0.00508)
						(xy 0.22606 -0.00508) (xy 0.22733 -0.01651) (xy 0.22733 -0.02667) (xy 0.2286 -0.0381) (xy 0.22733 -0.04953)
						(xy 0.22733 -0.05969) (xy 0.22606 -0.07112) (xy 0.22352 -0.08128) (xy 0.22225 -0.09144) (xy 0.21844 -0.10287)
						(xy 0.2159 -0.11303) (xy 0.21209 -0.12319) (xy 0.20701 -0.13335) (xy 0.2032 -0.14224) (xy 0.19812 -0.1524)
						(xy 0.17272 -0.18796) (xy 0.1651 -0.19558) (xy 0.1651 -0.7366) (xy 0.16256 -0.76835) (xy 0.1524 -0.8001)
						(xy 0.13716 -0.82804) (xy 0.11684 -0.85344) (xy 0.09144 -0.87376) (xy 0.0635 -0.889) (xy 0.03175 -0.89916)
					)
					(width 0)
					(fill yes)
				)
			)
		)
		(pad "8" smd custom
			(at -29.550106 4.100068)
			(size 0.1143 0.1143)
			(layers "B.Cu" "B.Mask" "B.Paste")
			(net "GND")
			(options
				(clearance outline)
				(anchor circle)
			)
			(primitives
				(gr_poly
					(pts
						(xy 0 -0.9017) (xy -0.03175 -0.89916) (xy -0.0635 -0.889) (xy -0.09144 -0.87376) (xy -0.11684 -0.85344)
						(xy -0.13716 -0.82804) (xy -0.1524 -0.8001) (xy -0.16256 -0.76835) (xy -0.1651 -0.7366) (xy -0.1651 -0.11938)
						(xy -0.17272 -0.11176) (xy -0.19812 -0.0762) (xy -0.2032 -0.06604) (xy -0.20701 -0.05715) (xy -0.21209 -0.04699)
						(xy -0.2159 -0.03683) (xy -0.21844 -0.02667) (xy -0.22225 -0.01524) (xy -0.22352 -0.00508) (xy -0.22606 0.00508)
						(xy -0.22733 0.01651) (xy -0.22733 0.02667) (xy -0.2286 0.0381) (xy -0.22733 0.04953) (xy -0.22733 0.05969)
						(xy -0.22606 0.07112) (xy -0.22352 0.08128) (xy -0.22225 0.09144) (xy -0.21844 0.10287) (xy -0.2159 0.11303)
						(xy -0.21209 0.12319) (xy -0.20701 0.13335) (xy -0.2032 0.14224) (xy -0.19812 0.1524) (xy -0.17272 0.18796)
						(xy -0.1651 0.19558) (xy -0.1651 0.7366) (xy -0.16256 0.76835) (xy -0.1524 0.8001) (xy -0.13716 0.82804)
						(xy -0.11684 0.85344) (xy -0.09144 0.87376) (xy -0.0635 0.889) (xy -0.03175 0.89916) (xy 0 0.9017)
						(xy 0.03175 0.89916) (xy 0.0635 0.889) (xy 0.09144 0.87376) (xy 0.11684 0.85344) (xy 0.13716 0.82804)
						(xy 0.1524 0.8001) (xy 0.16256 0.76835) (xy 0.1651 0.7366) (xy 0.1651 0.19685) (xy 0.17272 0.18923)
						(xy 0.17907 0.18034) (xy 0.18669 0.17145) (xy 0.19177 0.16256) (xy 0.19812 0.15367) (xy 0.20828 0.13335)
						(xy 0.21971 0.10287) (xy 0.22225 0.09271) (xy 0.22479 0.08128) (xy 0.22606 0.07112) (xy 0.2286 0.05969)
						(xy 0.2286 0.01651) (xy 0.22606 0.00508) (xy 0.22479 -0.00508) (xy 0.22225 -0.01651) (xy 0.21971 -0.02667)
						(xy 0.20828 -0.05715) (xy 0.19812 -0.07747) (xy 0.19177 -0.08636) (xy 0.18669 -0.09525) (xy 0.17907 -0.10414)
						(xy 0.17272 -0.11303) (xy 0.1651 -0.12065) (xy 0.1651 -0.7366) (xy 0.16256 -0.76835) (xy 0.1524 -0.8001)
						(xy 0.13716 -0.82804) (xy 0.11684 -0.85344) (xy 0.09144 -0.87376) (xy 0.0635 -0.889) (xy 0.03175 -0.89916)
					)
					(width 0)
					(fill yes)
				)
			)
		)
		(pad "9" smd custom
			(at -29.249878 -4.100068)
			(size 0.1143 0.1143)
			(layers "B.Cu" "B.Mask" "B.Paste")
			(net "GND")
			(options
				(clearance outline)
				(anchor circle)
			)
			(primitives
				(gr_poly
					(pts
						(xy 0 -0.9017) (xy -0.03175 -0.89916) (xy -0.0635 -0.889) (xy -0.09144 -0.87376) (xy -0.11684 -0.85344)
						(xy -0.13716 -0.82804) (xy -0.1524 -0.8001) (xy -0.16256 -0.76835) (xy -0.1651 -0.7366) (xy -0.1651 -0.44958)
						(xy -0.17272 -0.44196) (xy -0.19812 -0.4064) (xy -0.2032 -0.39624) (xy -0.20701 -0.38735) (xy -0.21209 -0.37719)
						(xy -0.2159 -0.36703) (xy -0.21844 -0.35687) (xy -0.22225 -0.34544) (xy -0.22352 -0.33528) (xy -0.22606 -0.32512)
						(xy -0.22733 -0.31369) (xy -0.22733 -0.30353) (xy -0.2286 -0.2921) (xy -0.22733 -0.28067) (xy -0.22733 -0.27051)
						(xy -0.22606 -0.25908) (xy -0.22352 -0.24892) (xy -0.22225 -0.23876) (xy -0.21844 -0.22733) (xy -0.2159 -0.21717)
						(xy -0.21209 -0.20701) (xy -0.20701 -0.19685) (xy -0.2032 -0.18796) (xy -0.19812 -0.1778) (xy -0.17272 -0.14224)
						(xy -0.1651 -0.13462) (xy -0.1651 0.7366) (xy -0.16256 0.76835) (xy -0.1524 0.8001) (xy -0.13716 0.82804)
						(xy -0.11684 0.85344) (xy -0.09144 0.87376) (xy -0.0635 0.889) (xy -0.03175 0.89916) (xy 0 0.9017)
						(xy 0.03175 0.89916) (xy 0.0635 0.889) (xy 0.09144 0.87376) (xy 0.11684 0.85344) (xy 0.13716 0.82804)
						(xy 0.1524 0.8001) (xy 0.16256 0.76835) (xy 0.1651 0.7366) (xy 0.1651 -0.13462) (xy 0.17272 -0.14224)
						(xy 0.19812 -0.1778) (xy 0.2032 -0.18796) (xy 0.20701 -0.19685) (xy 0.21209 -0.20701) (xy 0.2159 -0.21717)
						(xy 0.21844 -0.22733) (xy 0.22225 -0.23876) (xy 0.22352 -0.24892) (xy 0.22606 -0.25908) (xy 0.22733 -0.27051)
						(xy 0.22733 -0.28067) (xy 0.2286 -0.2921) (xy 0.22733 -0.30353) (xy 0.22733 -0.31369) (xy 0.22606 -0.32512)
						(xy 0.22352 -0.33528) (xy 0.22225 -0.34544) (xy 0.21844 -0.35687) (xy 0.2159 -0.36703) (xy 0.21209 -0.37719)
						(xy 0.20701 -0.38735) (xy 0.2032 -0.39624) (xy 0.19812 -0.4064) (xy 0.17272 -0.44196) (xy 0.1651 -0.44958)
						(xy 0.1651 -0.7366) (xy 0.16256 -0.76835) (xy 0.1524 -0.8001) (xy 0.13716 -0.82804) (xy 0.11684 -0.85344)
						(xy 0.09144 -0.87376) (xy 0.0635 -0.889) (xy 0.03175 -0.89916)
					)
					(width 0)
					(fill yes)
				)
			)
		)
		(pad "10" smd custom
			(at -28.949904 4.100068)
			(size 0.1143 0.1143)
			(layers "B.Cu" "B.Mask" "B.Paste")
			(net "M_A_DQS_DN0")
			(options
				(clearance outline)
				(anchor circle)
			)
			(primitives
				(gr_poly
					(pts
						(xy 0 -0.9017) (xy -0.03175 -0.89916) (xy -0.0635 -0.889) (xy -0.09144 -0.87376) (xy -0.11684 -0.85344)
						(xy -0.13716 -0.82804) (xy -0.1524 -0.8001) (xy -0.16256 -0.76835) (xy -0.1651 -0.7366) (xy -0.1651 0.13462)
						(xy -0.17272 0.14224) (xy -0.19812 0.1778) (xy -0.2032 0.18796) (xy -0.20701 0.19685) (xy -0.21209 0.20701)
						(xy -0.2159 0.21717) (xy -0.21844 0.22733) (xy -0.22225 0.23876) (xy -0.22352 0.24892) (xy -0.22606 0.25908)
						(xy -0.22733 0.27051) (xy -0.22733 0.28067) (xy -0.2286 0.2921) (xy -0.22733 0.30353) (xy -0.22733 0.31369)
						(xy -0.22606 0.32512) (xy -0.22352 0.33528) (xy -0.22225 0.34544) (xy -0.21844 0.35687) (xy -0.2159 0.36703)
						(xy -0.21209 0.37719) (xy -0.20701 0.38735) (xy -0.2032 0.39624) (xy -0.19812 0.4064) (xy -0.17272 0.44196)
						(xy -0.1651 0.44958) (xy -0.1651 0.7366) (xy -0.16256 0.76835) (xy -0.1524 0.8001) (xy -0.13716 0.82804)
						(xy -0.11684 0.85344) (xy -0.09144 0.87376) (xy -0.0635 0.889) (xy -0.03175 0.89916) (xy 0 0.9017)
						(xy 0.03175 0.89916) (xy 0.0635 0.889) (xy 0.09144 0.87376) (xy 0.11684 0.85344) (xy 0.13716 0.82804)
						(xy 0.1524 0.8001) (xy 0.16256 0.76835) (xy 0.1651 0.7366) (xy 0.1651 0.44958) (xy 0.17272 0.44196)
						(xy 0.19812 0.4064) (xy 0.2032 0.39624) (xy 0.20701 0.38735) (xy 0.21209 0.37719) (xy 0.2159 0.36703)
						(xy 0.21844 0.35687) (xy 0.22225 0.34544) (xy 0.22352 0.33528) (xy 0.22606 0.32512) (xy 0.22733 0.31369)
						(xy 0.22733 0.30353) (xy 0.2286 0.2921) (xy 0.22733 0.28067) (xy 0.22733 0.27051) (xy 0.22606 0.25908)
						(xy 0.22352 0.24892) (xy 0.22225 0.23876) (xy 0.21844 0.22733) (xy 0.2159 0.21717) (xy 0.21209 0.20701)
						(xy 0.20701 0.19685) (xy 0.2032 0.18796) (xy 0.19812 0.1778) (xy 0.17272 0.14224) (xy 0.1651 0.13462)
						(xy 0.1651 -0.7366) (xy 0.16256 -0.76835) (xy 0.1524 -0.8001) (xy 0.13716 -0.82804) (xy 0.11684 -0.85344)
						(xy 0.09144 -0.87376) (xy 0.0635 -0.889) (xy 0.03175 -0.89916)
					)
					(width 0)
					(fill yes)
				)
			)
		)
		(pad "11" smd custom
			(at -28.64993 -4.100068)
			(size 0.1143 0.1143)
			(layers "B.Cu" "B.Mask" "B.Paste")
			(net "GND")
			(options
				(clearance outline)
				(anchor circle)
			)
			(primitives
				(gr_poly
					(pts
						(xy 0 -0.9017) (xy -0.03175 -0.89916) (xy -0.0635 -0.889) (xy -0.09144 -0.87376) (xy -0.11684 -0.85344)
						(xy -0.13716 -0.82804) (xy -0.1524 -0.8001) (xy -0.16256 -0.76835) (xy -0.1651 -0.7366) (xy -0.1651 -0.19685)
						(xy -0.17272 -0.18923) (xy -0.17907 -0.18034) (xy -0.18669 -0.17145) (xy -0.19177 -0.16256) (xy -0.19812 -0.15367)
						(xy -0.20828 -0.13335) (xy -0.21971 -0.10287) (xy -0.22225 -0.09271) (xy -0.22479 -0.08128) (xy -0.22606 -0.07112)
						(xy -0.2286 -0.05969) (xy -0.2286 -0.01651) (xy -0.22606 -0.00508) (xy -0.22479 0.00508) (xy -0.22225 0.01651)
						(xy -0.21971 0.02667) (xy -0.20828 0.05715) (xy -0.19812 0.07747) (xy -0.19177 0.08636) (xy -0.18669 0.09525)
						(xy -0.17907 0.10414) (xy -0.17272 0.11303) (xy -0.1651 0.12065) (xy -0.1651 0.7366) (xy -0.16256 0.76835)
						(xy -0.1524 0.8001) (xy -0.13716 0.82804) (xy -0.11684 0.85344) (xy -0.09144 0.87376) (xy -0.0635 0.889)
						(xy -0.03175 0.89916) (xy 0 0.9017) (xy 0.03175 0.89916) (xy 0.0635 0.889) (xy 0.09144 0.87376)
						(xy 0.11684 0.85344) (xy 0.13716 0.82804) (xy 0.1524 0.8001) (xy 0.16256 0.76835) (xy 0.1651 0.7366)
						(xy 0.1651 0.11938) (xy 0.17272 0.11176) (xy 0.19812 0.0762) (xy 0.2032 0.06604) (xy 0.20701 0.05715)
						(xy 0.21209 0.04699) (xy 0.2159 0.03683) (xy 0.21844 0.02667) (xy 0.22225 0.01524) (xy 0.22352 0.00508)
						(xy 0.22606 -0.00508) (xy 0.22733 -0.01651) (xy 0.22733 -0.02667) (xy 0.2286 -0.0381) (xy 0.22733 -0.04953)
						(xy 0.22733 -0.05969) (xy 0.22606 -0.07112) (xy 0.22352 -0.08128) (xy 0.22225 -0.09144) (xy 0.21844 -0.10287)
						(xy 0.2159 -0.11303) (xy 0.21209 -0.12319) (xy 0.20701 -0.13335) (xy 0.2032 -0.14224) (xy 0.19812 -0.1524)
						(xy 0.17272 -0.18796) (xy 0.1651 -0.19558) (xy 0.1651 -0.7366) (xy 0.16256 -0.76835) (xy 0.1524 -0.8001)
						(xy 0.13716 -0.82804) (xy 0.11684 -0.85344) (xy 0.09144 -0.87376) (xy 0.0635 -0.889) (xy 0.03175 -0.89916)
					)
					(width 0)
					(fill yes)
				)
			)
		)
		(pad "12" smd custom
			(at -28.349956 4.100068)
			(size 0.1143 0.1143)
			(layers "B.Cu" "B.Mask" "B.Paste")
			(net "M_A_DQS_DP0")
			(options
				(clearance outline)
				(anchor circle)
			)
			(primitives
				(gr_poly
					(pts
						(xy 0 -0.9017) (xy -0.03175 -0.89916) (xy -0.0635 -0.889) (xy -0.09144 -0.87376) (xy -0.11684 -0.85344)
						(xy -0.13716 -0.82804) (xy -0.1524 -0.8001) (xy -0.16256 -0.76835) (xy -0.1651 -0.7366) (xy -0.1651 -0.11938)
						(xy -0.17272 -0.11176) (xy -0.19812 -0.0762) (xy -0.2032 -0.06604) (xy -0.20701 -0.05715) (xy -0.21209 -0.04699)
						(xy -0.2159 -0.03683) (xy -0.21844 -0.02667) (xy -0.22225 -0.01524) (xy -0.22352 -0.00508) (xy -0.22606 0.00508)
						(xy -0.22733 0.01651) (xy -0.22733 0.02667) (xy -0.2286 0.0381) (xy -0.22733 0.04953) (xy -0.22733 0.05969)
						(xy -0.22606 0.07112) (xy -0.22352 0.08128) (xy -0.22225 0.09144) (xy -0.21844 0.10287) (xy -0.2159 0.11303)
						(xy -0.21209 0.12319) (xy -0.20701 0.13335) (xy -0.2032 0.14224) (xy -0.19812 0.1524) (xy -0.17272 0.18796)
						(xy -0.1651 0.19558) (xy -0.1651 0.7366) (xy -0.16256 0.76835) (xy -0.1524 0.8001) (xy -0.13716 0.82804)
						(xy -0.11684 0.85344) (xy -0.09144 0.87376) (xy -0.0635 0.889) (xy -0.03175 0.89916) (xy 0 0.9017)
						(xy 0.03175 0.89916) (xy 0.0635 0.889) (xy 0.09144 0.87376) (xy 0.11684 0.85344) (xy 0.13716 0.82804)
						(xy 0.1524 0.8001) (xy 0.16256 0.76835) (xy 0.1651 0.7366) (xy 0.1651 0.19685) (xy 0.17272 0.18923)
						(xy 0.17907 0.18034) (xy 0.18669 0.17145) (xy 0.19177 0.16256) (xy 0.19812 0.15367) (xy 0.20828 0.13335)
						(xy 0.21971 0.10287) (xy 0.22225 0.09271) (xy 0.22479 0.08128) (xy 0.22606 0.07112) (xy 0.2286 0.05969)
						(xy 0.2286 0.01651) (xy 0.22606 0.00508) (xy 0.22479 -0.00508) (xy 0.22225 -0.01651) (xy 0.21971 -0.02667)
						(xy 0.20828 -0.05715) (xy 0.19812 -0.07747) (xy 0.19177 -0.08636) (xy 0.18669 -0.09525) (xy 0.17907 -0.10414)
						(xy 0.17272 -0.11303) (xy 0.1651 -0.12065) (xy 0.1651 -0.7366) (xy 0.16256 -0.76835) (xy 0.1524 -0.8001)
						(xy 0.13716 -0.82804) (xy 0.11684 -0.85344) (xy 0.09144 -0.87376) (xy 0.0635 -0.889) (xy 0.03175 -0.89916)
					)
					(width 0)
					(fill yes)
				)
			)
		)
		(pad "13" smd custom
			(at -28.049982 -4.100068)
			(size 0.1143 0.1143)
			(layers "B.Cu" "B.Mask" "B.Paste")
			(net "M_A_DQ2")
			(options
				(clearance outline)
				(anchor circle)
			)
			(primitives
				(gr_poly
					(pts
						(xy 0 -0.9017) (xy -0.03175 -0.89916) (xy -0.0635 -0.889) (xy -0.09144 -0.87376) (xy -0.11684 -0.85344)
						(xy -0.13716 -0.82804) (xy -0.1524 -0.8001) (xy -0.16256 -0.76835) (xy -0.1651 -0.7366) (xy -0.1651 -0.44958)
						(xy -0.17272 -0.44196) (xy -0.19812 -0.4064) (xy -0.2032 -0.39624) (xy -0.20701 -0.38735) (xy -0.21209 -0.37719)
						(xy -0.2159 -0.36703) (xy -0.21844 -0.35687) (xy -0.22225 -0.34544) (xy -0.22352 -0.33528) (xy -0.22606 -0.32512)
						(xy -0.22733 -0.31369) (xy -0.22733 -0.30353) (xy -0.2286 -0.2921) (xy -0.22733 -0.28067) (xy -0.22733 -0.27051)
						(xy -0.22606 -0.25908) (xy -0.22352 -0.24892) (xy -0.22225 -0.23876) (xy -0.21844 -0.22733) (xy -0.2159 -0.21717)
						(xy -0.21209 -0.20701) (xy -0.20701 -0.19685) (xy -0.2032 -0.18796) (xy -0.19812 -0.1778) (xy -0.17272 -0.14224)
						(xy -0.1651 -0.13462) (xy -0.1651 0.7366) (xy -0.16256 0.76835) (xy -0.1524 0.8001) (xy -0.13716 0.82804)
						(xy -0.11684 0.85344) (xy -0.09144 0.87376) (xy -0.0635 0.889) (xy -0.03175 0.89916) (xy 0 0.9017)
						(xy 0.03175 0.89916) (xy 0.0635 0.889) (xy 0.09144 0.87376) (xy 0.11684 0.85344) (xy 0.13716 0.82804)
						(xy 0.1524 0.8001) (xy 0.16256 0.76835) (xy 0.1651 0.7366) (xy 0.1651 -0.13462) (xy 0.17272 -0.14224)
						(xy 0.19812 -0.1778) (xy 0.2032 -0.18796) (xy 0.20701 -0.19685) (xy 0.21209 -0.20701) (xy 0.2159 -0.21717)
						(xy 0.21844 -0.22733) (xy 0.22225 -0.23876) (xy 0.22352 -0.24892) (xy 0.22606 -0.25908) (xy 0.22733 -0.27051)
						(xy 0.22733 -0.28067) (xy 0.2286 -0.2921) (xy 0.22733 -0.30353) (xy 0.22733 -0.31369) (xy 0.22606 -0.32512)
						(xy 0.22352 -0.33528) (xy 0.22225 -0.34544) (xy 0.21844 -0.35687) (xy 0.2159 -0.36703) (xy 0.21209 -0.37719)
						(xy 0.20701 -0.38735) (xy 0.2032 -0.39624) (xy 0.19812 -0.4064) (xy 0.17272 -0.44196) (xy 0.1651 -0.44958)
						(xy 0.1651 -0.7366) (xy 0.16256 -0.76835) (xy 0.1524 -0.8001) (xy 0.13716 -0.82804) (xy 0.11684 -0.85344)
						(xy 0.09144 -0.87376) (xy 0.0635 -0.889) (xy 0.03175 -0.89916)
					)
					(width 0)
					(fill yes)
				)
			)
		)
		(pad "14" smd custom
			(at -27.750008 4.100068)
			(size 0.1143 0.1143)
			(layers "B.Cu" "B.Mask" "B.Paste")
			(net "GND")
			(options
				(clearance outline)
				(anchor circle)
			)
			(primitives
				(gr_poly
					(pts
						(xy 0 -0.9017) (xy -0.03175 -0.89916) (xy -0.0635 -0.889) (xy -0.09144 -0.87376) (xy -0.11684 -0.85344)
						(xy -0.13716 -0.82804) (xy -0.1524 -0.8001) (xy -0.16256 -0.76835) (xy -0.1651 -0.7366) (xy -0.1651 0.13462)
						(xy -0.17272 0.14224) (xy -0.19812 0.1778) (xy -0.2032 0.18796) (xy -0.20701 0.19685) (xy -0.21209 0.20701)
						(xy -0.2159 0.21717) (xy -0.21844 0.22733) (xy -0.22225 0.23876) (xy -0.22352 0.24892) (xy -0.22606 0.25908)
						(xy -0.22733 0.27051) (xy -0.22733 0.28067) (xy -0.2286 0.2921) (xy -0.22733 0.30353) (xy -0.22733 0.31369)
						(xy -0.22606 0.32512) (xy -0.22352 0.33528) (xy -0.22225 0.34544) (xy -0.21844 0.35687) (xy -0.2159 0.36703)
						(xy -0.21209 0.37719) (xy -0.20701 0.38735) (xy -0.2032 0.39624) (xy -0.19812 0.4064) (xy -0.17272 0.44196)
						(xy -0.1651 0.44958) (xy -0.1651 0.7366) (xy -0.16256 0.76835) (xy -0.1524 0.8001) (xy -0.13716 0.82804)
						(xy -0.11684 0.85344) (xy -0.09144 0.87376) (xy -0.0635 0.889) (xy -0.03175 0.89916) (xy 0 0.9017)
						(xy 0.03175 0.89916) (xy 0.0635 0.889) (xy 0.09144 0.87376) (xy 0.11684 0.85344) (xy 0.13716 0.82804)
						(xy 0.1524 0.8001) (xy 0.16256 0.76835) (xy 0.1651 0.7366) (xy 0.1651 0.44958) (xy 0.17272 0.44196)
						(xy 0.19812 0.4064) (xy 0.2032 0.39624) (xy 0.20701 0.38735) (xy 0.21209 0.37719) (xy 0.2159 0.36703)
						(xy 0.21844 0.35687) (xy 0.22225 0.34544) (xy 0.22352 0.33528) (xy 0.22606 0.32512) (xy 0.22733 0.31369)
						(xy 0.22733 0.30353) (xy 0.2286 0.2921) (xy 0.22733 0.28067) (xy 0.22733 0.27051) (xy 0.22606 0.25908)
						(xy 0.22352 0.24892) (xy 0.22225 0.23876) (xy 0.21844 0.22733) (xy 0.2159 0.21717) (xy 0.21209 0.20701)
						(xy 0.20701 0.19685) (xy 0.2032 0.18796) (xy 0.19812 0.1778) (xy 0.17272 0.14224) (xy 0.1651 0.13462)
						(xy 0.1651 -0.7366) (xy 0.16256 -0.76835) (xy 0.1524 -0.8001) (xy 0.13716 -0.82804) (xy 0.11684 -0.85344)
						(xy 0.09144 -0.87376) (xy 0.0635 -0.889) (xy 0.03175 -0.89916)
					)
					(width 0)
					(fill yes)
				)
			)
		)
		(pad "15" smd custom
			(at -27.450034 -4.100068)
			(size 0.1143 0.1143)
			(layers "B.Cu" "B.Mask" "B.Paste")
			(net "M_A_DQ3")
			(options
				(clearance outline)
				(anchor circle)
			)
			(primitives
				(gr_poly
					(pts
						(xy 0 -0.9017) (xy -0.03175 -0.89916) (xy -0.0635 -0.889) (xy -0.09144 -0.87376) (xy -0.11684 -0.85344)
						(xy -0.13716 -0.82804) (xy -0.1524 -0.8001) (xy -0.16256 -0.76835) (xy -0.1651 -0.7366) (xy -0.1651 -0.19685)
						(xy -0.17272 -0.18923) (xy -0.17907 -0.18034) (xy -0.18669 -0.17145) (xy -0.19177 -0.16256) (xy -0.19812 -0.15367)
						(xy -0.20828 -0.13335) (xy -0.21971 -0.10287) (xy -0.22225 -0.09271) (xy -0.22479 -0.08128) (xy -0.22606 -0.07112)
						(xy -0.2286 -0.05969) (xy -0.2286 -0.01651) (xy -0.22606 -0.00508) (xy -0.22479 0.00508) (xy -0.22225 0.01651)
						(xy -0.21971 0.02667) (xy -0.20828 0.05715) (xy -0.19812 0.07747) (xy -0.19177 0.08636) (xy -0.18669 0.09525)
						(xy -0.17907 0.10414) (xy -0.17272 0.11303) (xy -0.1651 0.12065) (xy -0.1651 0.7366) (xy -0.16256 0.76835)
						(xy -0.1524 0.8001) (xy -0.13716 0.82804) (xy -0.11684 0.85344) (xy -0.09144 0.87376) (xy -0.0635 0.889)
						(xy -0.03175 0.89916) (xy 0 0.9017) (xy 0.03175 0.89916) (xy 0.0635 0.889) (xy 0.09144 0.87376)
						(xy 0.11684 0.85344) (xy 0.13716 0.82804) (xy 0.1524 0.8001) (xy 0.16256 0.76835) (xy 0.1651 0.7366)
						(xy 0.1651 0.11938) (xy 0.17272 0.11176) (xy 0.19812 0.0762) (xy 0.2032 0.06604) (xy 0.20701 0.05715)
						(xy 0.21209 0.04699) (xy 0.2159 0.03683) (xy 0.21844 0.02667) (xy 0.22225 0.01524) (xy 0.22352 0.00508)
						(xy 0.22606 -0.00508) (xy 0.22733 -0.01651) (xy 0.22733 -0.02667) (xy 0.2286 -0.0381) (xy 0.22733 -0.04953)
						(xy 0.22733 -0.05969) (xy 0.22606 -0.07112) (xy 0.22352 -0.08128) (xy 0.22225 -0.09144) (xy 0.21844 -0.10287)
						(xy 0.2159 -0.11303) (xy 0.21209 -0.12319) (xy 0.20701 -0.13335) (xy 0.2032 -0.14224) (xy 0.19812 -0.1524)
						(xy 0.17272 -0.18796) (xy 0.1651 -0.19558) (xy 0.1651 -0.7366) (xy 0.16256 -0.76835) (xy 0.1524 -0.8001)
						(xy 0.13716 -0.82804) (xy 0.11684 -0.85344) (xy 0.09144 -0.87376) (xy 0.0635 -0.889) (xy 0.03175 -0.89916)
					)
					(width 0)
					(fill yes)
				)
			)
		)
		(pad "16" smd custom
			(at -27.15006 4.100068)
			(size 0.1143 0.1143)
			(layers "B.Cu" "B.Mask" "B.Paste")
			(net "M_A_DQ6")
			(options
				(clearance outline)
				(anchor circle)
			)
			(primitives
				(gr_poly
					(pts
						(xy 0 -0.9017) (xy -0.03175 -0.89916) (xy -0.0635 -0.889) (xy -0.09144 -0.87376) (xy -0.11684 -0.85344)
						(xy -0.13716 -0.82804) (xy -0.1524 -0.8001) (xy -0.16256 -0.76835) (xy -0.1651 -0.7366) (xy -0.1651 -0.11938)
						(xy -0.17272 -0.11176) (xy -0.19812 -0.0762) (xy -0.2032 -0.06604) (xy -0.20701 -0.05715) (xy -0.21209 -0.04699)
						(xy -0.2159 -0.03683) (xy -0.21844 -0.02667) (xy -0.22225 -0.01524) (xy -0.22352 -0.00508) (xy -0.22606 0.00508)
						(xy -0.22733 0.01651) (xy -0.22733 0.02667) (xy -0.2286 0.0381) (xy -0.22733 0.04953) (xy -0.22733 0.05969)
						(xy -0.22606 0.07112) (xy -0.22352 0.08128) (xy -0.22225 0.09144) (xy -0.21844 0.10287) (xy -0.2159 0.11303)
						(xy -0.21209 0.12319) (xy -0.20701 0.13335) (xy -0.2032 0.14224) (xy -0.19812 0.1524) (xy -0.17272 0.18796)
						(xy -0.1651 0.19558) (xy -0.1651 0.7366) (xy -0.16256 0.76835) (xy -0.1524 0.8001) (xy -0.13716 0.82804)
						(xy -0.11684 0.85344) (xy -0.09144 0.87376) (xy -0.0635 0.889) (xy -0.03175 0.89916) (xy 0 0.9017)
						(xy 0.03175 0.89916) (xy 0.0635 0.889) (xy 0.09144 0.87376) (xy 0.11684 0.85344) (xy 0.13716 0.82804)
						(xy 0.1524 0.8001) (xy 0.16256 0.76835) (xy 0.1651 0.7366) (xy 0.1651 0.19685) (xy 0.17272 0.18923)
						(xy 0.17907 0.18034) (xy 0.18669 0.17145) (xy 0.19177 0.16256) (xy 0.19812 0.15367) (xy 0.20828 0.13335)
						(xy 0.21971 0.10287) (xy 0.22225 0.09271) (xy 0.22479 0.08128) (xy 0.22606 0.07112) (xy 0.2286 0.05969)
						(xy 0.2286 0.01651) (xy 0.22606 0.00508) (xy 0.22479 -0.00508) (xy 0.22225 -0.01651) (xy 0.21971 -0.02667)
						(xy 0.20828 -0.05715) (xy 0.19812 -0.07747) (xy 0.19177 -0.08636) (xy 0.18669 -0.09525) (xy 0.17907 -0.10414)
						(xy 0.17272 -0.11303) (xy 0.1651 -0.12065) (xy 0.1651 -0.7366) (xy 0.16256 -0.76835) (xy 0.1524 -0.8001)
						(xy 0.13716 -0.82804) (xy 0.11684 -0.85344) (xy 0.09144 -0.87376) (xy 0.0635 -0.889) (xy 0.03175 -0.89916)
					)
					(width 0)
					(fill yes)
				)
			)
		)
		(pad "17" smd custom
			(at -26.850086 -4.100068)
			(size 0.1143 0.1143)
			(layers "B.Cu" "B.Mask" "B.Paste")
			(net "GND")
			(options
				(clearance outline)
				(anchor circle)
			)
			(primitives
				(gr_poly
					(pts
						(xy 0 -0.9017) (xy -0.03175 -0.89916) (xy -0.0635 -0.889) (xy -0.09144 -0.87376) (xy -0.11684 -0.85344)
						(xy -0.13716 -0.82804) (xy -0.1524 -0.8001) (xy -0.16256 -0.76835) (xy -0.1651 -0.7366) (xy -0.1651 -0.44958)
						(xy -0.17272 -0.44196) (xy -0.19812 -0.4064) (xy -0.2032 -0.39624) (xy -0.20701 -0.38735) (xy -0.21209 -0.37719)
						(xy -0.2159 -0.36703) (xy -0.21844 -0.35687) (xy -0.22225 -0.34544) (xy -0.22352 -0.33528) (xy -0.22606 -0.32512)
						(xy -0.22733 -0.31369) (xy -0.22733 -0.30353) (xy -0.2286 -0.2921) (xy -0.22733 -0.28067) (xy -0.22733 -0.27051)
						(xy -0.22606 -0.25908) (xy -0.22352 -0.24892) (xy -0.22225 -0.23876) (xy -0.21844 -0.22733) (xy -0.2159 -0.21717)
						(xy -0.21209 -0.20701) (xy -0.20701 -0.19685) (xy -0.2032 -0.18796) (xy -0.19812 -0.1778) (xy -0.17272 -0.14224)
						(xy -0.1651 -0.13462) (xy -0.1651 0.7366) (xy -0.16256 0.76835) (xy -0.1524 0.8001) (xy -0.13716 0.82804)
						(xy -0.11684 0.85344) (xy -0.09144 0.87376) (xy -0.0635 0.889) (xy -0.03175 0.89916) (xy 0 0.9017)
						(xy 0.03175 0.89916) (xy 0.0635 0.889) (xy 0.09144 0.87376) (xy 0.11684 0.85344) (xy 0.13716 0.82804)
						(xy 0.1524 0.8001) (xy 0.16256 0.76835) (xy 0.1651 0.7366) (xy 0.1651 -0.13462) (xy 0.17272 -0.14224)
						(xy 0.19812 -0.1778) (xy 0.2032 -0.18796) (xy 0.20701 -0.19685) (xy 0.21209 -0.20701) (xy 0.2159 -0.21717)
						(xy 0.21844 -0.22733) (xy 0.22225 -0.23876) (xy 0.22352 -0.24892) (xy 0.22606 -0.25908) (xy 0.22733 -0.27051)
						(xy 0.22733 -0.28067) (xy 0.2286 -0.2921) (xy 0.22733 -0.30353) (xy 0.22733 -0.31369) (xy 0.22606 -0.32512)
						(xy 0.22352 -0.33528) (xy 0.22225 -0.34544) (xy 0.21844 -0.35687) (xy 0.2159 -0.36703) (xy 0.21209 -0.37719)
						(xy 0.20701 -0.38735) (xy 0.2032 -0.39624) (xy 0.19812 -0.4064) (xy 0.17272 -0.44196) (xy 0.1651 -0.44958)
						(xy 0.1651 -0.7366) (xy 0.16256 -0.76835) (xy 0.1524 -0.8001) (xy 0.13716 -0.82804) (xy 0.11684 -0.85344)
						(xy 0.09144 -0.87376) (xy 0.0635 -0.889) (xy 0.03175 -0.89916)
					)
					(width 0)
					(fill yes)
				)
			)
		)
		(pad "18" smd custom
			(at -26.550112 4.100068)
			(size 0.1143 0.1143)
			(layers "B.Cu" "B.Mask" "B.Paste")
			(net "M_A_DQ7")
			(options
				(clearance outline)
				(anchor circle)
			)
			(primitives
				(gr_poly
					(pts
						(xy 0 -0.9017) (xy -0.03175 -0.89916) (xy -0.0635 -0.889) (xy -0.09144 -0.87376) (xy -0.11684 -0.85344)
						(xy -0.13716 -0.82804) (xy -0.1524 -0.8001) (xy -0.16256 -0.76835) (xy -0.1651 -0.7366) (xy -0.1651 0.13462)
						(xy -0.17272 0.14224) (xy -0.19812 0.1778) (xy -0.2032 0.18796) (xy -0.20701 0.19685) (xy -0.21209 0.20701)
						(xy -0.2159 0.21717) (xy -0.21844 0.22733) (xy -0.22225 0.23876) (xy -0.22352 0.24892) (xy -0.22606 0.25908)
						(xy -0.22733 0.27051) (xy -0.22733 0.28067) (xy -0.2286 0.2921) (xy -0.22733 0.30353) (xy -0.22733 0.31369)
						(xy -0.22606 0.32512) (xy -0.22352 0.33528) (xy -0.22225 0.34544) (xy -0.21844 0.35687) (xy -0.2159 0.36703)
						(xy -0.21209 0.37719) (xy -0.20701 0.38735) (xy -0.2032 0.39624) (xy -0.19812 0.4064) (xy -0.17272 0.44196)
						(xy -0.1651 0.44958) (xy -0.1651 0.7366) (xy -0.16256 0.76835) (xy -0.1524 0.8001) (xy -0.13716 0.82804)
						(xy -0.11684 0.85344) (xy -0.09144 0.87376) (xy -0.0635 0.889) (xy -0.03175 0.89916) (xy 0 0.9017)
						(xy 0.03175 0.89916) (xy 0.0635 0.889) (xy 0.09144 0.87376) (xy 0.11684 0.85344) (xy 0.13716 0.82804)
						(xy 0.1524 0.8001) (xy 0.16256 0.76835) (xy 0.1651 0.7366) (xy 0.1651 0.44958) (xy 0.17272 0.44196)
						(xy 0.19812 0.4064) (xy 0.2032 0.39624) (xy 0.20701 0.38735) (xy 0.21209 0.37719) (xy 0.2159 0.36703)
						(xy 0.21844 0.35687) (xy 0.22225 0.34544) (xy 0.22352 0.33528) (xy 0.22606 0.32512) (xy 0.22733 0.31369)
						(xy 0.22733 0.30353) (xy 0.2286 0.2921) (xy 0.22733 0.28067) (xy 0.22733 0.27051) (xy 0.22606 0.25908)
						(xy 0.22352 0.24892) (xy 0.22225 0.23876) (xy 0.21844 0.22733) (xy 0.2159 0.21717) (xy 0.21209 0.20701)
						(xy 0.20701 0.19685) (xy 0.2032 0.18796) (xy 0.19812 0.1778) (xy 0.17272 0.14224) (xy 0.1651 0.13462)
						(xy 0.1651 -0.7366) (xy 0.16256 -0.76835) (xy 0.1524 -0.8001) (xy 0.13716 -0.82804) (xy 0.11684 -0.85344)
						(xy 0.09144 -0.87376) (xy 0.0635 -0.889) (xy 0.03175 -0.89916)
					)
					(width 0)
					(fill yes)
				)
			)
		)
		(pad "19" smd custom
			(at -26.249884 -4.100068)
			(size 0.1143 0.1143)
			(layers "B.Cu" "B.Mask" "B.Paste")
			(net "M_A_DQ8")
			(options
				(clearance outline)
				(anchor circle)
			)
			(primitives
				(gr_poly
					(pts
						(xy 0 -0.9017) (xy -0.03175 -0.89916) (xy -0.0635 -0.889) (xy -0.09144 -0.87376) (xy -0.11684 -0.85344)
						(xy -0.13716 -0.82804) (xy -0.1524 -0.8001) (xy -0.16256 -0.76835) (xy -0.1651 -0.7366) (xy -0.1651 -0.19685)
						(xy -0.17272 -0.18923) (xy -0.17907 -0.18034) (xy -0.18669 -0.17145) (xy -0.19177 -0.16256) (xy -0.19812 -0.15367)
						(xy -0.20828 -0.13335) (xy -0.21971 -0.10287) (xy -0.22225 -0.09271) (xy -0.22479 -0.08128) (xy -0.22606 -0.07112)
						(xy -0.2286 -0.05969) (xy -0.2286 -0.01651) (xy -0.22606 -0.00508) (xy -0.22479 0.00508) (xy -0.22225 0.01651)
						(xy -0.21971 0.02667) (xy -0.20828 0.05715) (xy -0.19812 0.07747) (xy -0.19177 0.08636) (xy -0.18669 0.09525)
						(xy -0.17907 0.10414) (xy -0.17272 0.11303) (xy -0.1651 0.12065) (xy -0.1651 0.7366) (xy -0.16256 0.76835)
						(xy -0.1524 0.8001) (xy -0.13716 0.82804) (xy -0.11684 0.85344) (xy -0.09144 0.87376) (xy -0.0635 0.889)
						(xy -0.03175 0.89916) (xy 0 0.9017) (xy 0.03175 0.89916) (xy 0.0635 0.889) (xy 0.09144 0.87376)
						(xy 0.11684 0.85344) (xy 0.13716 0.82804) (xy 0.1524 0.8001) (xy 0.16256 0.76835) (xy 0.1651 0.7366)
						(xy 0.1651 0.11938) (xy 0.17272 0.11176) (xy 0.19812 0.0762) (xy 0.2032 0.06604) (xy 0.20701 0.05715)
						(xy 0.21209 0.04699) (xy 0.2159 0.03683) (xy 0.21844 0.02667) (xy 0.22225 0.01524) (xy 0.22352 0.00508)
						(xy 0.22606 -0.00508) (xy 0.22733 -0.01651) (xy 0.22733 -0.02667) (xy 0.2286 -0.0381) (xy 0.22733 -0.04953)
						(xy 0.22733 -0.05969) (xy 0.22606 -0.07112) (xy 0.22352 -0.08128) (xy 0.22225 -0.09144) (xy 0.21844 -0.10287)
						(xy 0.2159 -0.11303) (xy 0.21209 -0.12319) (xy 0.20701 -0.13335) (xy 0.2032 -0.14224) (xy 0.19812 -0.1524)
						(xy 0.17272 -0.18796) (xy 0.1651 -0.19558) (xy 0.1651 -0.7366) (xy 0.16256 -0.76835) (xy 0.1524 -0.8001)
						(xy 0.13716 -0.82804) (xy 0.11684 -0.85344) (xy 0.09144 -0.87376) (xy 0.0635 -0.889) (xy 0.03175 -0.89916)
					)
					(width 0)
					(fill yes)
				)
			)
		)
		(pad "20" smd custom
			(at -25.94991 4.100068)
			(size 0.1143 0.1143)
			(layers "B.Cu" "B.Mask" "B.Paste")
			(net "GND")
			(options
				(clearance outline)
				(anchor circle)
			)
			(primitives
				(gr_poly
					(pts
						(xy 0 -0.9017) (xy -0.03175 -0.89916) (xy -0.0635 -0.889) (xy -0.09144 -0.87376) (xy -0.11684 -0.85344)
						(xy -0.13716 -0.82804) (xy -0.1524 -0.8001) (xy -0.16256 -0.76835) (xy -0.1651 -0.7366) (xy -0.1651 -0.11938)
						(xy -0.17272 -0.11176) (xy -0.19812 -0.0762) (xy -0.2032 -0.06604) (xy -0.20701 -0.05715) (xy -0.21209 -0.04699)
						(xy -0.2159 -0.03683) (xy -0.21844 -0.02667) (xy -0.22225 -0.01524) (xy -0.22352 -0.00508) (xy -0.22606 0.00508)
						(xy -0.22733 0.01651) (xy -0.22733 0.02667) (xy -0.2286 0.0381) (xy -0.22733 0.04953) (xy -0.22733 0.05969)
						(xy -0.22606 0.07112) (xy -0.22352 0.08128) (xy -0.22225 0.09144) (xy -0.21844 0.10287) (xy -0.2159 0.11303)
						(xy -0.21209 0.12319) (xy -0.20701 0.13335) (xy -0.2032 0.14224) (xy -0.19812 0.1524) (xy -0.17272 0.18796)
						(xy -0.1651 0.19558) (xy -0.1651 0.7366) (xy -0.16256 0.76835) (xy -0.1524 0.8001) (xy -0.13716 0.82804)
						(xy -0.11684 0.85344) (xy -0.09144 0.87376) (xy -0.0635 0.889) (xy -0.03175 0.89916) (xy 0 0.9017)
						(xy 0.03175 0.89916) (xy 0.0635 0.889) (xy 0.09144 0.87376) (xy 0.11684 0.85344) (xy 0.13716 0.82804)
						(xy 0.1524 0.8001) (xy 0.16256 0.76835) (xy 0.1651 0.7366) (xy 0.1651 0.19685) (xy 0.17272 0.18923)
						(xy 0.17907 0.18034) (xy 0.18669 0.17145) (xy 0.19177 0.16256) (xy 0.19812 0.15367) (xy 0.20828 0.13335)
						(xy 0.21971 0.10287) (xy 0.22225 0.09271) (xy 0.22479 0.08128) (xy 0.22606 0.07112) (xy 0.2286 0.05969)
						(xy 0.2286 0.01651) (xy 0.22606 0.00508) (xy 0.22479 -0.00508) (xy 0.22225 -0.01651) (xy 0.21971 -0.02667)
						(xy 0.20828 -0.05715) (xy 0.19812 -0.07747) (xy 0.19177 -0.08636) (xy 0.18669 -0.09525) (xy 0.17907 -0.10414)
						(xy 0.17272 -0.11303) (xy 0.1651 -0.12065) (xy 0.1651 -0.7366) (xy 0.16256 -0.76835) (xy 0.1524 -0.8001)
						(xy 0.13716 -0.82804) (xy 0.11684 -0.85344) (xy 0.09144 -0.87376) (xy 0.0635 -0.889) (xy 0.03175 -0.89916)
					)
					(width 0)
					(fill yes)
				)
			)
		)
		(pad "21" smd custom
			(at -25.649936 -4.100068)
			(size 0.1143 0.1143)
			(layers "B.Cu" "B.Mask" "B.Paste")
			(net "M_A_DQ9")
			(options
				(clearance outline)
				(anchor circle)
			)
			(primitives
				(gr_poly
					(pts
						(xy 0 -0.9017) (xy -0.03175 -0.89916) (xy -0.0635 -0.889) (xy -0.09144 -0.87376) (xy -0.11684 -0.85344)
						(xy -0.13716 -0.82804) (xy -0.1524 -0.8001) (xy -0.16256 -0.76835) (xy -0.1651 -0.7366) (xy -0.1651 -0.44958)
						(xy -0.17272 -0.44196) (xy -0.19812 -0.4064) (xy -0.2032 -0.39624) (xy -0.20701 -0.38735) (xy -0.21209 -0.37719)
						(xy -0.2159 -0.36703) (xy -0.21844 -0.35687) (xy -0.22225 -0.34544) (xy -0.22352 -0.33528) (xy -0.22606 -0.32512)
						(xy -0.22733 -0.31369) (xy -0.22733 -0.30353) (xy -0.2286 -0.2921) (xy -0.22733 -0.28067) (xy -0.22733 -0.27051)
						(xy -0.22606 -0.25908) (xy -0.22352 -0.24892) (xy -0.22225 -0.23876) (xy -0.21844 -0.22733) (xy -0.2159 -0.21717)
						(xy -0.21209 -0.20701) (xy -0.20701 -0.19685) (xy -0.2032 -0.18796) (xy -0.19812 -0.1778) (xy -0.17272 -0.14224)
						(xy -0.1651 -0.13462) (xy -0.1651 0.7366) (xy -0.16256 0.76835) (xy -0.1524 0.8001) (xy -0.13716 0.82804)
						(xy -0.11684 0.85344) (xy -0.09144 0.87376) (xy -0.0635 0.889) (xy -0.03175 0.89916) (xy 0 0.9017)
						(xy 0.03175 0.89916) (xy 0.0635 0.889) (xy 0.09144 0.87376) (xy 0.11684 0.85344) (xy 0.13716 0.82804)
						(xy 0.1524 0.8001) (xy 0.16256 0.76835) (xy 0.1651 0.7366) (xy 0.1651 -0.13462) (xy 0.17272 -0.14224)
						(xy 0.19812 -0.1778) (xy 0.2032 -0.18796) (xy 0.20701 -0.19685) (xy 0.21209 -0.20701) (xy 0.2159 -0.21717)
						(xy 0.21844 -0.22733) (xy 0.22225 -0.23876) (xy 0.22352 -0.24892) (xy 0.22606 -0.25908) (xy 0.22733 -0.27051)
						(xy 0.22733 -0.28067) (xy 0.2286 -0.2921) (xy 0.22733 -0.30353) (xy 0.22733 -0.31369) (xy 0.22606 -0.32512)
						(xy 0.22352 -0.33528) (xy 0.22225 -0.34544) (xy 0.21844 -0.35687) (xy 0.2159 -0.36703) (xy 0.21209 -0.37719)
						(xy 0.20701 -0.38735) (xy 0.2032 -0.39624) (xy 0.19812 -0.4064) (xy 0.17272 -0.44196) (xy 0.1651 -0.44958)
						(xy 0.1651 -0.7366) (xy 0.16256 -0.76835) (xy 0.1524 -0.8001) (xy 0.13716 -0.82804) (xy 0.11684 -0.85344)
						(xy 0.09144 -0.87376) (xy 0.0635 -0.889) (xy 0.03175 -0.89916)
					)
					(width 0)
					(fill yes)
				)
			)
		)
		(pad "22" smd custom
			(at -25.349962 4.100068)
			(size 0.1143 0.1143)
			(layers "B.Cu" "B.Mask" "B.Paste")
			(net "M_A_DQ12")
			(options
				(clearance outline)
				(anchor circle)
			)
			(primitives
				(gr_poly
					(pts
						(xy 0 -0.9017) (xy -0.03175 -0.89916) (xy -0.0635 -0.889) (xy -0.09144 -0.87376) (xy -0.11684 -0.85344)
						(xy -0.13716 -0.82804) (xy -0.1524 -0.8001) (xy -0.16256 -0.76835) (xy -0.1651 -0.7366) (xy -0.1651 0.13462)
						(xy -0.17272 0.14224) (xy -0.19812 0.1778) (xy -0.2032 0.18796) (xy -0.20701 0.19685) (xy -0.21209 0.20701)
						(xy -0.2159 0.21717) (xy -0.21844 0.22733) (xy -0.22225 0.23876) (xy -0.22352 0.24892) (xy -0.22606 0.25908)
						(xy -0.22733 0.27051) (xy -0.22733 0.28067) (xy -0.2286 0.2921) (xy -0.22733 0.30353) (xy -0.22733 0.31369)
						(xy -0.22606 0.32512) (xy -0.22352 0.33528) (xy -0.22225 0.34544) (xy -0.21844 0.35687) (xy -0.2159 0.36703)
						(xy -0.21209 0.37719) (xy -0.20701 0.38735) (xy -0.2032 0.39624) (xy -0.19812 0.4064) (xy -0.17272 0.44196)
						(xy -0.1651 0.44958) (xy -0.1651 0.7366) (xy -0.16256 0.76835) (xy -0.1524 0.8001) (xy -0.13716 0.82804)
						(xy -0.11684 0.85344) (xy -0.09144 0.87376) (xy -0.0635 0.889) (xy -0.03175 0.89916) (xy 0 0.9017)
						(xy 0.03175 0.89916) (xy 0.0635 0.889) (xy 0.09144 0.87376) (xy 0.11684 0.85344) (xy 0.13716 0.82804)
						(xy 0.1524 0.8001) (xy 0.16256 0.76835) (xy 0.1651 0.7366) (xy 0.1651 0.44958) (xy 0.17272 0.44196)
						(xy 0.19812 0.4064) (xy 0.2032 0.39624) (xy 0.20701 0.38735) (xy 0.21209 0.37719) (xy 0.2159 0.36703)
						(xy 0.21844 0.35687) (xy 0.22225 0.34544) (xy 0.22352 0.33528) (xy 0.22606 0.32512) (xy 0.22733 0.31369)
						(xy 0.22733 0.30353) (xy 0.2286 0.2921) (xy 0.22733 0.28067) (xy 0.22733 0.27051) (xy 0.22606 0.25908)
						(xy 0.22352 0.24892) (xy 0.22225 0.23876) (xy 0.21844 0.22733) (xy 0.2159 0.21717) (xy 0.21209 0.20701)
						(xy 0.20701 0.19685) (xy 0.2032 0.18796) (xy 0.19812 0.1778) (xy 0.17272 0.14224) (xy 0.1651 0.13462)
						(xy 0.1651 -0.7366) (xy 0.16256 -0.76835) (xy 0.1524 -0.8001) (xy 0.13716 -0.82804) (xy 0.11684 -0.85344)
						(xy 0.09144 -0.87376) (xy 0.0635 -0.889) (xy 0.03175 -0.89916)
					)
					(width 0)
					(fill yes)
				)
			)
		)
		(pad "23" smd custom
			(at -25.049988 -4.100068)
			(size 0.1143 0.1143)
			(layers "B.Cu" "B.Mask" "B.Paste")
			(net "GND")
			(options
				(clearance outline)
				(anchor circle)
			)
			(primitives
				(gr_poly
					(pts
						(xy 0 -0.9017) (xy -0.03175 -0.89916) (xy -0.0635 -0.889) (xy -0.09144 -0.87376) (xy -0.11684 -0.85344)
						(xy -0.13716 -0.82804) (xy -0.1524 -0.8001) (xy -0.16256 -0.76835) (xy -0.1651 -0.7366) (xy -0.1651 -0.19685)
						(xy -0.17272 -0.18923) (xy -0.17907 -0.18034) (xy -0.18669 -0.17145) (xy -0.19177 -0.16256) (xy -0.19812 -0.15367)
						(xy -0.20828 -0.13335) (xy -0.21971 -0.10287) (xy -0.22225 -0.09271) (xy -0.22479 -0.08128) (xy -0.22606 -0.07112)
						(xy -0.2286 -0.05969) (xy -0.2286 -0.01651) (xy -0.22606 -0.00508) (xy -0.22479 0.00508) (xy -0.22225 0.01651)
						(xy -0.21971 0.02667) (xy -0.20828 0.05715) (xy -0.19812 0.07747) (xy -0.19177 0.08636) (xy -0.18669 0.09525)
						(xy -0.17907 0.10414) (xy -0.17272 0.11303) (xy -0.1651 0.12065) (xy -0.1651 0.7366) (xy -0.16256 0.76835)
						(xy -0.1524 0.8001) (xy -0.13716 0.82804) (xy -0.11684 0.85344) (xy -0.09144 0.87376) (xy -0.0635 0.889)
						(xy -0.03175 0.89916) (xy 0 0.9017) (xy 0.03175 0.89916) (xy 0.0635 0.889) (xy 0.09144 0.87376)
						(xy 0.11684 0.85344) (xy 0.13716 0.82804) (xy 0.1524 0.8001) (xy 0.16256 0.76835) (xy 0.1651 0.7366)
						(xy 0.1651 0.11938) (xy 0.17272 0.11176) (xy 0.19812 0.0762) (xy 0.2032 0.06604) (xy 0.20701 0.05715)
						(xy 0.21209 0.04699) (xy 0.2159 0.03683) (xy 0.21844 0.02667) (xy 0.22225 0.01524) (xy 0.22352 0.00508)
						(xy 0.22606 -0.00508) (xy 0.22733 -0.01651) (xy 0.22733 -0.02667) (xy 0.2286 -0.0381) (xy 0.22733 -0.04953)
						(xy 0.22733 -0.05969) (xy 0.22606 -0.07112) (xy 0.22352 -0.08128) (xy 0.22225 -0.09144) (xy 0.21844 -0.10287)
						(xy 0.2159 -0.11303) (xy 0.21209 -0.12319) (xy 0.20701 -0.13335) (xy 0.2032 -0.14224) (xy 0.19812 -0.1524)
						(xy 0.17272 -0.18796) (xy 0.1651 -0.19558) (xy 0.1651 -0.7366) (xy 0.16256 -0.76835) (xy 0.1524 -0.8001)
						(xy 0.13716 -0.82804) (xy 0.11684 -0.85344) (xy 0.09144 -0.87376) (xy 0.0635 -0.889) (xy 0.03175 -0.89916)
					)
					(width 0)
					(fill yes)
				)
			)
		)
		(pad "24" smd custom
			(at -24.750014 4.100068)
			(size 0.1143 0.1143)
			(layers "B.Cu" "B.Mask" "B.Paste")
			(net "M_A_DQ13")
			(options
				(clearance outline)
				(anchor circle)
			)
			(primitives
				(gr_poly
					(pts
						(xy 0 -0.9017) (xy -0.03175 -0.89916) (xy -0.0635 -0.889) (xy -0.09144 -0.87376) (xy -0.11684 -0.85344)
						(xy -0.13716 -0.82804) (xy -0.1524 -0.8001) (xy -0.16256 -0.76835) (xy -0.1651 -0.7366) (xy -0.1651 -0.11938)
						(xy -0.17272 -0.11176) (xy -0.19812 -0.0762) (xy -0.2032 -0.06604) (xy -0.20701 -0.05715) (xy -0.21209 -0.04699)
						(xy -0.2159 -0.03683) (xy -0.21844 -0.02667) (xy -0.22225 -0.01524) (xy -0.22352 -0.00508) (xy -0.22606 0.00508)
						(xy -0.22733 0.01651) (xy -0.22733 0.02667) (xy -0.2286 0.0381) (xy -0.22733 0.04953) (xy -0.22733 0.05969)
						(xy -0.22606 0.07112) (xy -0.22352 0.08128) (xy -0.22225 0.09144) (xy -0.21844 0.10287) (xy -0.2159 0.11303)
						(xy -0.21209 0.12319) (xy -0.20701 0.13335) (xy -0.2032 0.14224) (xy -0.19812 0.1524) (xy -0.17272 0.18796)
						(xy -0.1651 0.19558) (xy -0.1651 0.7366) (xy -0.16256 0.76835) (xy -0.1524 0.8001) (xy -0.13716 0.82804)
						(xy -0.11684 0.85344) (xy -0.09144 0.87376) (xy -0.0635 0.889) (xy -0.03175 0.89916) (xy 0 0.9017)
						(xy 0.03175 0.89916) (xy 0.0635 0.889) (xy 0.09144 0.87376) (xy 0.11684 0.85344) (xy 0.13716 0.82804)
						(xy 0.1524 0.8001) (xy 0.16256 0.76835) (xy 0.1651 0.7366) (xy 0.1651 0.19685) (xy 0.17272 0.18923)
						(xy 0.17907 0.18034) (xy 0.18669 0.17145) (xy 0.19177 0.16256) (xy 0.19812 0.15367) (xy 0.20828 0.13335)
						(xy 0.21971 0.10287) (xy 0.22225 0.09271) (xy 0.22479 0.08128) (xy 0.22606 0.07112) (xy 0.2286 0.05969)
						(xy 0.2286 0.01651) (xy 0.22606 0.00508) (xy 0.22479 -0.00508) (xy 0.22225 -0.01651) (xy 0.21971 -0.02667)
						(xy 0.20828 -0.05715) (xy 0.19812 -0.07747) (xy 0.19177 -0.08636) (xy 0.18669 -0.09525) (xy 0.17907 -0.10414)
						(xy 0.17272 -0.11303) (xy 0.1651 -0.12065) (xy 0.1651 -0.7366) (xy 0.16256 -0.76835) (xy 0.1524 -0.8001)
						(xy 0.13716 -0.82804) (xy 0.11684 -0.85344) (xy 0.09144 -0.87376) (xy 0.0635 -0.889) (xy 0.03175 -0.89916)
					)
					(width 0)
					(fill yes)
				)
			)
		)
		(pad "25" smd custom
			(at -24.45004 -4.100068)
			(size 0.1143 0.1143)
			(layers "B.Cu" "B.Mask" "B.Paste")
			(net "M_A_DQS_DN1")
			(options
				(clearance outline)
				(anchor circle)
			)
			(primitives
				(gr_poly
					(pts
						(xy 0 -0.9017) (xy -0.03175 -0.89916) (xy -0.0635 -0.889) (xy -0.09144 -0.87376) (xy -0.11684 -0.85344)
						(xy -0.13716 -0.82804) (xy -0.1524 -0.8001) (xy -0.16256 -0.76835) (xy -0.1651 -0.7366) (xy -0.1651 -0.44958)
						(xy -0.17272 -0.44196) (xy -0.19812 -0.4064) (xy -0.2032 -0.39624) (xy -0.20701 -0.38735) (xy -0.21209 -0.37719)
						(xy -0.2159 -0.36703) (xy -0.21844 -0.35687) (xy -0.22225 -0.34544) (xy -0.22352 -0.33528) (xy -0.22606 -0.32512)
						(xy -0.22733 -0.31369) (xy -0.22733 -0.30353) (xy -0.2286 -0.2921) (xy -0.22733 -0.28067) (xy -0.22733 -0.27051)
						(xy -0.22606 -0.25908) (xy -0.22352 -0.24892) (xy -0.22225 -0.23876) (xy -0.21844 -0.22733) (xy -0.2159 -0.21717)
						(xy -0.21209 -0.20701) (xy -0.20701 -0.19685) (xy -0.2032 -0.18796) (xy -0.19812 -0.1778) (xy -0.17272 -0.14224)
						(xy -0.1651 -0.13462) (xy -0.1651 0.7366) (xy -0.16256 0.76835) (xy -0.1524 0.8001) (xy -0.13716 0.82804)
						(xy -0.11684 0.85344) (xy -0.09144 0.87376) (xy -0.0635 0.889) (xy -0.03175 0.89916) (xy 0 0.9017)
						(xy 0.03175 0.89916) (xy 0.0635 0.889) (xy 0.09144 0.87376) (xy 0.11684 0.85344) (xy 0.13716 0.82804)
						(xy 0.1524 0.8001) (xy 0.16256 0.76835) (xy 0.1651 0.7366) (xy 0.1651 -0.13462) (xy 0.17272 -0.14224)
						(xy 0.19812 -0.1778) (xy 0.2032 -0.18796) (xy 0.20701 -0.19685) (xy 0.21209 -0.20701) (xy 0.2159 -0.21717)
						(xy 0.21844 -0.22733) (xy 0.22225 -0.23876) (xy 0.22352 -0.24892) (xy 0.22606 -0.25908) (xy 0.22733 -0.27051)
						(xy 0.22733 -0.28067) (xy 0.2286 -0.2921) (xy 0.22733 -0.30353) (xy 0.22733 -0.31369) (xy 0.22606 -0.32512)
						(xy 0.22352 -0.33528) (xy 0.22225 -0.34544) (xy 0.21844 -0.35687) (xy 0.2159 -0.36703) (xy 0.21209 -0.37719)
						(xy 0.20701 -0.38735) (xy 0.2032 -0.39624) (xy 0.19812 -0.4064) (xy 0.17272 -0.44196) (xy 0.1651 -0.44958)
						(xy 0.1651 -0.7366) (xy 0.16256 -0.76835) (xy 0.1524 -0.8001) (xy 0.13716 -0.82804) (xy 0.11684 -0.85344)
						(xy 0.09144 -0.87376) (xy 0.0635 -0.889) (xy 0.03175 -0.89916)
					)
					(width 0)
					(fill yes)
				)
			)
		)
		(pad "26" smd custom
			(at -24.150066 4.100068)
			(size 0.1143 0.1143)
			(layers "B.Cu" "B.Mask" "B.Paste")
			(net "GND")
			(options
				(clearance outline)
				(anchor circle)
			)
			(primitives
				(gr_poly
					(pts
						(xy 0 -0.9017) (xy -0.03175 -0.89916) (xy -0.0635 -0.889) (xy -0.09144 -0.87376) (xy -0.11684 -0.85344)
						(xy -0.13716 -0.82804) (xy -0.1524 -0.8001) (xy -0.16256 -0.76835) (xy -0.1651 -0.7366) (xy -0.1651 0.13462)
						(xy -0.17272 0.14224) (xy -0.19812 0.1778) (xy -0.2032 0.18796) (xy -0.20701 0.19685) (xy -0.21209 0.20701)
						(xy -0.2159 0.21717) (xy -0.21844 0.22733) (xy -0.22225 0.23876) (xy -0.22352 0.24892) (xy -0.22606 0.25908)
						(xy -0.22733 0.27051) (xy -0.22733 0.28067) (xy -0.2286 0.2921) (xy -0.22733 0.30353) (xy -0.22733 0.31369)
						(xy -0.22606 0.32512) (xy -0.22352 0.33528) (xy -0.22225 0.34544) (xy -0.21844 0.35687) (xy -0.2159 0.36703)
						(xy -0.21209 0.37719) (xy -0.20701 0.38735) (xy -0.2032 0.39624) (xy -0.19812 0.4064) (xy -0.17272 0.44196)
						(xy -0.1651 0.44958) (xy -0.1651 0.7366) (xy -0.16256 0.76835) (xy -0.1524 0.8001) (xy -0.13716 0.82804)
						(xy -0.11684 0.85344) (xy -0.09144 0.87376) (xy -0.0635 0.889) (xy -0.03175 0.89916) (xy 0 0.9017)
						(xy 0.03175 0.89916) (xy 0.0635 0.889) (xy 0.09144 0.87376) (xy 0.11684 0.85344) (xy 0.13716 0.82804)
						(xy 0.1524 0.8001) (xy 0.16256 0.76835) (xy 0.1651 0.7366) (xy 0.1651 0.44958) (xy 0.17272 0.44196)
						(xy 0.19812 0.4064) (xy 0.2032 0.39624) (xy 0.20701 0.38735) (xy 0.21209 0.37719) (xy 0.2159 0.36703)
						(xy 0.21844 0.35687) (xy 0.22225 0.34544) (xy 0.22352 0.33528) (xy 0.22606 0.32512) (xy 0.22733 0.31369)
						(xy 0.22733 0.30353) (xy 0.2286 0.2921) (xy 0.22733 0.28067) (xy 0.22733 0.27051) (xy 0.22606 0.25908)
						(xy 0.22352 0.24892) (xy 0.22225 0.23876) (xy 0.21844 0.22733) (xy 0.2159 0.21717) (xy 0.21209 0.20701)
						(xy 0.20701 0.19685) (xy 0.2032 0.18796) (xy 0.19812 0.1778) (xy 0.17272 0.14224) (xy 0.1651 0.13462)
						(xy 0.1651 -0.7366) (xy 0.16256 -0.76835) (xy 0.1524 -0.8001) (xy 0.13716 -0.82804) (xy 0.11684 -0.85344)
						(xy 0.09144 -0.87376) (xy 0.0635 -0.889) (xy 0.03175 -0.89916)
					)
					(width 0)
					(fill yes)
				)
			)
		)
		(pad "27" smd custom
			(at -23.850092 -4.100068)
			(size 0.1143 0.1143)
			(layers "B.Cu" "B.Mask" "B.Paste")
			(net "M_A_DQS_DP1")
			(options
				(clearance outline)
				(anchor circle)
			)
			(primitives
				(gr_poly
					(pts
						(xy 0 -0.9017) (xy -0.03175 -0.89916) (xy -0.0635 -0.889) (xy -0.09144 -0.87376) (xy -0.11684 -0.85344)
						(xy -0.13716 -0.82804) (xy -0.1524 -0.8001) (xy -0.16256 -0.76835) (xy -0.1651 -0.7366) (xy -0.1651 -0.19685)
						(xy -0.17272 -0.18923) (xy -0.17907 -0.18034) (xy -0.18669 -0.17145) (xy -0.19177 -0.16256) (xy -0.19812 -0.15367)
						(xy -0.20828 -0.13335) (xy -0.21971 -0.10287) (xy -0.22225 -0.09271) (xy -0.22479 -0.08128) (xy -0.22606 -0.07112)
						(xy -0.2286 -0.05969) (xy -0.2286 -0.01651) (xy -0.22606 -0.00508) (xy -0.22479 0.00508) (xy -0.22225 0.01651)
						(xy -0.21971 0.02667) (xy -0.20828 0.05715) (xy -0.19812 0.07747) (xy -0.19177 0.08636) (xy -0.18669 0.09525)
						(xy -0.17907 0.10414) (xy -0.17272 0.11303) (xy -0.1651 0.12065) (xy -0.1651 0.7366) (xy -0.16256 0.76835)
						(xy -0.1524 0.8001) (xy -0.13716 0.82804) (xy -0.11684 0.85344) (xy -0.09144 0.87376) (xy -0.0635 0.889)
						(xy -0.03175 0.89916) (xy 0 0.9017) (xy 0.03175 0.89916) (xy 0.0635 0.889) (xy 0.09144 0.87376)
						(xy 0.11684 0.85344) (xy 0.13716 0.82804) (xy 0.1524 0.8001) (xy 0.16256 0.76835) (xy 0.1651 0.7366)
						(xy 0.1651 0.11938) (xy 0.17272 0.11176) (xy 0.19812 0.0762) (xy 0.2032 0.06604) (xy 0.20701 0.05715)
						(xy 0.21209 0.04699) (xy 0.2159 0.03683) (xy 0.21844 0.02667) (xy 0.22225 0.01524) (xy 0.22352 0.00508)
						(xy 0.22606 -0.00508) (xy 0.22733 -0.01651) (xy 0.22733 -0.02667) (xy 0.2286 -0.0381) (xy 0.22733 -0.04953)
						(xy 0.22733 -0.05969) (xy 0.22606 -0.07112) (xy 0.22352 -0.08128) (xy 0.22225 -0.09144) (xy 0.21844 -0.10287)
						(xy 0.2159 -0.11303) (xy 0.21209 -0.12319) (xy 0.20701 -0.13335) (xy 0.2032 -0.14224) (xy 0.19812 -0.1524)
						(xy 0.17272 -0.18796) (xy 0.1651 -0.19558) (xy 0.1651 -0.7366) (xy 0.16256 -0.76835) (xy 0.1524 -0.8001)
						(xy 0.13716 -0.82804) (xy 0.11684 -0.85344) (xy 0.09144 -0.87376) (xy 0.0635 -0.889) (xy 0.03175 -0.89916)
					)
					(width 0)
					(fill yes)
				)
			)
		)
		(pad "28" smd custom
			(at -23.550118 4.100068)
			(size 0.1143 0.1143)
			(layers "B.Cu" "B.Mask" "B.Paste")
			(net "GND")
			(options
				(clearance outline)
				(anchor circle)
			)
			(primitives
				(gr_poly
					(pts
						(xy 0 -0.9017) (xy -0.03175 -0.89916) (xy -0.0635 -0.889) (xy -0.09144 -0.87376) (xy -0.11684 -0.85344)
						(xy -0.13716 -0.82804) (xy -0.1524 -0.8001) (xy -0.16256 -0.76835) (xy -0.1651 -0.7366) (xy -0.1651 -0.11938)
						(xy -0.17272 -0.11176) (xy -0.19812 -0.0762) (xy -0.2032 -0.06604) (xy -0.20701 -0.05715) (xy -0.21209 -0.04699)
						(xy -0.2159 -0.03683) (xy -0.21844 -0.02667) (xy -0.22225 -0.01524) (xy -0.22352 -0.00508) (xy -0.22606 0.00508)
						(xy -0.22733 0.01651) (xy -0.22733 0.02667) (xy -0.2286 0.0381) (xy -0.22733 0.04953) (xy -0.22733 0.05969)
						(xy -0.22606 0.07112) (xy -0.22352 0.08128) (xy -0.22225 0.09144) (xy -0.21844 0.10287) (xy -0.2159 0.11303)
						(xy -0.21209 0.12319) (xy -0.20701 0.13335) (xy -0.2032 0.14224) (xy -0.19812 0.1524) (xy -0.17272 0.18796)
						(xy -0.1651 0.19558) (xy -0.1651 0.7366) (xy -0.16256 0.76835) (xy -0.1524 0.8001) (xy -0.13716 0.82804)
						(xy -0.11684 0.85344) (xy -0.09144 0.87376) (xy -0.0635 0.889) (xy -0.03175 0.89916) (xy 0 0.9017)
						(xy 0.03175 0.89916) (xy 0.0635 0.889) (xy 0.09144 0.87376) (xy 0.11684 0.85344) (xy 0.13716 0.82804)
						(xy 0.1524 0.8001) (xy 0.16256 0.76835) (xy 0.1651 0.7366) (xy 0.1651 0.19685) (xy 0.17272 0.18923)
						(xy 0.17907 0.18034) (xy 0.18669 0.17145) (xy 0.19177 0.16256) (xy 0.19812 0.15367) (xy 0.20828 0.13335)
						(xy 0.21971 0.10287) (xy 0.22225 0.09271) (xy 0.22479 0.08128) (xy 0.22606 0.07112) (xy 0.2286 0.05969)
						(xy 0.2286 0.01651) (xy 0.22606 0.00508) (xy 0.22479 -0.00508) (xy 0.22225 -0.01651) (xy 0.21971 -0.02667)
						(xy 0.20828 -0.05715) (xy 0.19812 -0.07747) (xy 0.19177 -0.08636) (xy 0.18669 -0.09525) (xy 0.17907 -0.10414)
						(xy 0.17272 -0.11303) (xy 0.1651 -0.12065) (xy 0.1651 -0.7366) (xy 0.16256 -0.76835) (xy 0.1524 -0.8001)
						(xy 0.13716 -0.82804) (xy 0.11684 -0.85344) (xy 0.09144 -0.87376) (xy 0.0635 -0.889) (xy 0.03175 -0.89916)
					)
					(width 0)
					(fill yes)
				)
			)
		)
		(pad "29" smd custom
			(at -23.24989 -4.100068)
			(size 0.1143 0.1143)
			(layers "B.Cu" "B.Mask" "B.Paste")
			(net "GND")
			(options
				(clearance outline)
				(anchor circle)
			)
			(primitives
				(gr_poly
					(pts
						(xy 0 -0.9017) (xy -0.03175 -0.89916) (xy -0.0635 -0.889) (xy -0.09144 -0.87376) (xy -0.11684 -0.85344)
						(xy -0.13716 -0.82804) (xy -0.1524 -0.8001) (xy -0.16256 -0.76835) (xy -0.1651 -0.7366) (xy -0.1651 -0.44958)
						(xy -0.17272 -0.44196) (xy -0.19812 -0.4064) (xy -0.2032 -0.39624) (xy -0.20701 -0.38735) (xy -0.21209 -0.37719)
						(xy -0.2159 -0.36703) (xy -0.21844 -0.35687) (xy -0.22225 -0.34544) (xy -0.22352 -0.33528) (xy -0.22606 -0.32512)
						(xy -0.22733 -0.31369) (xy -0.22733 -0.30353) (xy -0.2286 -0.2921) (xy -0.22733 -0.28067) (xy -0.22733 -0.27051)
						(xy -0.22606 -0.25908) (xy -0.22352 -0.24892) (xy -0.22225 -0.23876) (xy -0.21844 -0.22733) (xy -0.2159 -0.21717)
						(xy -0.21209 -0.20701) (xy -0.20701 -0.19685) (xy -0.2032 -0.18796) (xy -0.19812 -0.1778) (xy -0.17272 -0.14224)
						(xy -0.1651 -0.13462) (xy -0.1651 0.7366) (xy -0.16256 0.76835) (xy -0.1524 0.8001) (xy -0.13716 0.82804)
						(xy -0.11684 0.85344) (xy -0.09144 0.87376) (xy -0.0635 0.889) (xy -0.03175 0.89916) (xy 0 0.9017)
						(xy 0.03175 0.89916) (xy 0.0635 0.889) (xy 0.09144 0.87376) (xy 0.11684 0.85344) (xy 0.13716 0.82804)
						(xy 0.1524 0.8001) (xy 0.16256 0.76835) (xy 0.1651 0.7366) (xy 0.1651 -0.13462) (xy 0.17272 -0.14224)
						(xy 0.19812 -0.1778) (xy 0.2032 -0.18796) (xy 0.20701 -0.19685) (xy 0.21209 -0.20701) (xy 0.2159 -0.21717)
						(xy 0.21844 -0.22733) (xy 0.22225 -0.23876) (xy 0.22352 -0.24892) (xy 0.22606 -0.25908) (xy 0.22733 -0.27051)
						(xy 0.22733 -0.28067) (xy 0.2286 -0.2921) (xy 0.22733 -0.30353) (xy 0.22733 -0.31369) (xy 0.22606 -0.32512)
						(xy 0.22352 -0.33528) (xy 0.22225 -0.34544) (xy 0.21844 -0.35687) (xy 0.2159 -0.36703) (xy 0.21209 -0.37719)
						(xy 0.20701 -0.38735) (xy 0.2032 -0.39624) (xy 0.19812 -0.4064) (xy 0.17272 -0.44196) (xy 0.1651 -0.44958)
						(xy 0.1651 -0.7366) (xy 0.16256 -0.76835) (xy 0.1524 -0.8001) (xy 0.13716 -0.82804) (xy 0.11684 -0.85344)
						(xy 0.09144 -0.87376) (xy 0.0635 -0.889) (xy 0.03175 -0.89916)
					)
					(width 0)
					(fill yes)
				)
			)
		)
		(pad "30" smd custom
			(at -22.949916 4.100068)
			(size 0.1143 0.1143)
			(layers "B.Cu" "B.Mask" "B.Paste")
			(net "M_A_RESET#")
			(options
				(clearance outline)
				(anchor circle)
			)
			(primitives
				(gr_poly
					(pts
						(xy 0 -0.9017) (xy -0.03175 -0.89916) (xy -0.0635 -0.889) (xy -0.09144 -0.87376) (xy -0.11684 -0.85344)
						(xy -0.13716 -0.82804) (xy -0.1524 -0.8001) (xy -0.16256 -0.76835) (xy -0.1651 -0.7366) (xy -0.1651 0.13462)
						(xy -0.17272 0.14224) (xy -0.19812 0.1778) (xy -0.2032 0.18796) (xy -0.20701 0.19685) (xy -0.21209 0.20701)
						(xy -0.2159 0.21717) (xy -0.21844 0.22733) (xy -0.22225 0.23876) (xy -0.22352 0.24892) (xy -0.22606 0.25908)
						(xy -0.22733 0.27051) (xy -0.22733 0.28067) (xy -0.2286 0.2921) (xy -0.22733 0.30353) (xy -0.22733 0.31369)
						(xy -0.22606 0.32512) (xy -0.22352 0.33528) (xy -0.22225 0.34544) (xy -0.21844 0.35687) (xy -0.2159 0.36703)
						(xy -0.21209 0.37719) (xy -0.20701 0.38735) (xy -0.2032 0.39624) (xy -0.19812 0.4064) (xy -0.17272 0.44196)
						(xy -0.1651 0.44958) (xy -0.1651 0.7366) (xy -0.16256 0.76835) (xy -0.1524 0.8001) (xy -0.13716 0.82804)
						(xy -0.11684 0.85344) (xy -0.09144 0.87376) (xy -0.0635 0.889) (xy -0.03175 0.89916) (xy 0 0.9017)
						(xy 0.03175 0.89916) (xy 0.0635 0.889) (xy 0.09144 0.87376) (xy 0.11684 0.85344) (xy 0.13716 0.82804)
						(xy 0.1524 0.8001) (xy 0.16256 0.76835) (xy 0.1651 0.7366) (xy 0.1651 0.44958) (xy 0.17272 0.44196)
						(xy 0.19812 0.4064) (xy 0.2032 0.39624) (xy 0.20701 0.38735) (xy 0.21209 0.37719) (xy 0.2159 0.36703)
						(xy 0.21844 0.35687) (xy 0.22225 0.34544) (xy 0.22352 0.33528) (xy 0.22606 0.32512) (xy 0.22733 0.31369)
						(xy 0.22733 0.30353) (xy 0.2286 0.2921) (xy 0.22733 0.28067) (xy 0.22733 0.27051) (xy 0.22606 0.25908)
						(xy 0.22352 0.24892) (xy 0.22225 0.23876) (xy 0.21844 0.22733) (xy 0.2159 0.21717) (xy 0.21209 0.20701)
						(xy 0.20701 0.19685) (xy 0.2032 0.18796) (xy 0.19812 0.1778) (xy 0.17272 0.14224) (xy 0.1651 0.13462)
						(xy 0.1651 -0.7366) (xy 0.16256 -0.76835) (xy 0.1524 -0.8001) (xy 0.13716 -0.82804) (xy 0.11684 -0.85344)
						(xy 0.09144 -0.87376) (xy 0.0635 -0.889) (xy 0.03175 -0.89916)
					)
					(width 0)
					(fill yes)
				)
			)
		)
		(pad "31" smd custom
			(at -22.649942 -4.100068)
			(size 0.1143 0.1143)
			(layers "B.Cu" "B.Mask" "B.Paste")
			(net "M_A_DQ10")
			(options
				(clearance outline)
				(anchor circle)
			)
			(primitives
				(gr_poly
					(pts
						(xy 0 -0.9017) (xy -0.03175 -0.89916) (xy -0.0635 -0.889) (xy -0.09144 -0.87376) (xy -0.11684 -0.85344)
						(xy -0.13716 -0.82804) (xy -0.1524 -0.8001) (xy -0.16256 -0.76835) (xy -0.1651 -0.7366) (xy -0.1651 -0.19685)
						(xy -0.17272 -0.18923) (xy -0.17907 -0.18034) (xy -0.18669 -0.17145) (xy -0.19177 -0.16256) (xy -0.19812 -0.15367)
						(xy -0.20828 -0.13335) (xy -0.21971 -0.10287) (xy -0.22225 -0.09271) (xy -0.22479 -0.08128) (xy -0.22606 -0.07112)
						(xy -0.2286 -0.05969) (xy -0.2286 -0.01651) (xy -0.22606 -0.00508) (xy -0.22479 0.00508) (xy -0.22225 0.01651)
						(xy -0.21971 0.02667) (xy -0.20828 0.05715) (xy -0.19812 0.07747) (xy -0.19177 0.08636) (xy -0.18669 0.09525)
						(xy -0.17907 0.10414) (xy -0.17272 0.11303) (xy -0.1651 0.12065) (xy -0.1651 0.7366) (xy -0.16256 0.76835)
						(xy -0.1524 0.8001) (xy -0.13716 0.82804) (xy -0.11684 0.85344) (xy -0.09144 0.87376) (xy -0.0635 0.889)
						(xy -0.03175 0.89916) (xy 0 0.9017) (xy 0.03175 0.89916) (xy 0.0635 0.889) (xy 0.09144 0.87376)
						(xy 0.11684 0.85344) (xy 0.13716 0.82804) (xy 0.1524 0.8001) (xy 0.16256 0.76835) (xy 0.1651 0.7366)
						(xy 0.1651 0.11938) (xy 0.17272 0.11176) (xy 0.19812 0.0762) (xy 0.2032 0.06604) (xy 0.20701 0.05715)
						(xy 0.21209 0.04699) (xy 0.2159 0.03683) (xy 0.21844 0.02667) (xy 0.22225 0.01524) (xy 0.22352 0.00508)
						(xy 0.22606 -0.00508) (xy 0.22733 -0.01651) (xy 0.22733 -0.02667) (xy 0.2286 -0.0381) (xy 0.22733 -0.04953)
						(xy 0.22733 -0.05969) (xy 0.22606 -0.07112) (xy 0.22352 -0.08128) (xy 0.22225 -0.09144) (xy 0.21844 -0.10287)
						(xy 0.2159 -0.11303) (xy 0.21209 -0.12319) (xy 0.20701 -0.13335) (xy 0.2032 -0.14224) (xy 0.19812 -0.1524)
						(xy 0.17272 -0.18796) (xy 0.1651 -0.19558) (xy 0.1651 -0.7366) (xy 0.16256 -0.76835) (xy 0.1524 -0.8001)
						(xy 0.13716 -0.82804) (xy 0.11684 -0.85344) (xy 0.09144 -0.87376) (xy 0.0635 -0.889) (xy 0.03175 -0.89916)
					)
					(width 0)
					(fill yes)
				)
			)
		)
		(pad "32" smd custom
			(at -22.349968 4.100068)
			(size 0.1143 0.1143)
			(layers "B.Cu" "B.Mask" "B.Paste")
			(net "GND")
			(options
				(clearance outline)
				(anchor circle)
			)
			(primitives
				(gr_poly
					(pts
						(xy 0 -0.9017) (xy -0.03175 -0.89916) (xy -0.0635 -0.889) (xy -0.09144 -0.87376) (xy -0.11684 -0.85344)
						(xy -0.13716 -0.82804) (xy -0.1524 -0.8001) (xy -0.16256 -0.76835) (xy -0.1651 -0.7366) (xy -0.1651 -0.11938)
						(xy -0.17272 -0.11176) (xy -0.19812 -0.0762) (xy -0.2032 -0.06604) (xy -0.20701 -0.05715) (xy -0.21209 -0.04699)
						(xy -0.2159 -0.03683) (xy -0.21844 -0.02667) (xy -0.22225 -0.01524) (xy -0.22352 -0.00508) (xy -0.22606 0.00508)
						(xy -0.22733 0.01651) (xy -0.22733 0.02667) (xy -0.2286 0.0381) (xy -0.22733 0.04953) (xy -0.22733 0.05969)
						(xy -0.22606 0.07112) (xy -0.22352 0.08128) (xy -0.22225 0.09144) (xy -0.21844 0.10287) (xy -0.2159 0.11303)
						(xy -0.21209 0.12319) (xy -0.20701 0.13335) (xy -0.2032 0.14224) (xy -0.19812 0.1524) (xy -0.17272 0.18796)
						(xy -0.1651 0.19558) (xy -0.1651 0.7366) (xy -0.16256 0.76835) (xy -0.1524 0.8001) (xy -0.13716 0.82804)
						(xy -0.11684 0.85344) (xy -0.09144 0.87376) (xy -0.0635 0.889) (xy -0.03175 0.89916) (xy 0 0.9017)
						(xy 0.03175 0.89916) (xy 0.0635 0.889) (xy 0.09144 0.87376) (xy 0.11684 0.85344) (xy 0.13716 0.82804)
						(xy 0.1524 0.8001) (xy 0.16256 0.76835) (xy 0.1651 0.7366) (xy 0.1651 0.19685) (xy 0.17272 0.18923)
						(xy 0.17907 0.18034) (xy 0.18669 0.17145) (xy 0.19177 0.16256) (xy 0.19812 0.15367) (xy 0.20828 0.13335)
						(xy 0.21971 0.10287) (xy 0.22225 0.09271) (xy 0.22479 0.08128) (xy 0.22606 0.07112) (xy 0.2286 0.05969)
						(xy 0.2286 0.01651) (xy 0.22606 0.00508) (xy 0.22479 -0.00508) (xy 0.22225 -0.01651) (xy 0.21971 -0.02667)
						(xy 0.20828 -0.05715) (xy 0.19812 -0.07747) (xy 0.19177 -0.08636) (xy 0.18669 -0.09525) (xy 0.17907 -0.10414)
						(xy 0.17272 -0.11303) (xy 0.1651 -0.12065) (xy 0.1651 -0.7366) (xy 0.16256 -0.76835) (xy 0.1524 -0.8001)
						(xy 0.13716 -0.82804) (xy 0.11684 -0.85344) (xy 0.09144 -0.87376) (xy 0.0635 -0.889) (xy 0.03175 -0.89916)
					)
					(width 0)
					(fill yes)
				)
			)
		)
		(pad "33" smd custom
			(at -22.049994 -4.100068)
			(size 0.1143 0.1143)
			(layers "B.Cu" "B.Mask" "B.Paste")
			(net "M_A_DQ11")
			(options
				(clearance outline)
				(anchor circle)
			)
			(primitives
				(gr_poly
					(pts
						(xy 0 -0.9017) (xy -0.03175 -0.89916) (xy -0.0635 -0.889) (xy -0.09144 -0.87376) (xy -0.11684 -0.85344)
						(xy -0.13716 -0.82804) (xy -0.1524 -0.8001) (xy -0.16256 -0.76835) (xy -0.1651 -0.7366) (xy -0.1651 -0.44958)
						(xy -0.17272 -0.44196) (xy -0.19812 -0.4064) (xy -0.2032 -0.39624) (xy -0.20701 -0.38735) (xy -0.21209 -0.37719)
						(xy -0.2159 -0.36703) (xy -0.21844 -0.35687) (xy -0.22225 -0.34544) (xy -0.22352 -0.33528) (xy -0.22606 -0.32512)
						(xy -0.22733 -0.31369) (xy -0.22733 -0.30353) (xy -0.2286 -0.2921) (xy -0.22733 -0.28067) (xy -0.22733 -0.27051)
						(xy -0.22606 -0.25908) (xy -0.22352 -0.24892) (xy -0.22225 -0.23876) (xy -0.21844 -0.22733) (xy -0.2159 -0.21717)
						(xy -0.21209 -0.20701) (xy -0.20701 -0.19685) (xy -0.2032 -0.18796) (xy -0.19812 -0.1778) (xy -0.17272 -0.14224)
						(xy -0.1651 -0.13462) (xy -0.1651 0.7366) (xy -0.16256 0.76835) (xy -0.1524 0.8001) (xy -0.13716 0.82804)
						(xy -0.11684 0.85344) (xy -0.09144 0.87376) (xy -0.0635 0.889) (xy -0.03175 0.89916) (xy 0 0.9017)
						(xy 0.03175 0.89916) (xy 0.0635 0.889) (xy 0.09144 0.87376) (xy 0.11684 0.85344) (xy 0.13716 0.82804)
						(xy 0.1524 0.8001) (xy 0.16256 0.76835) (xy 0.1651 0.7366) (xy 0.1651 -0.13462) (xy 0.17272 -0.14224)
						(xy 0.19812 -0.1778) (xy 0.2032 -0.18796) (xy 0.20701 -0.19685) (xy 0.21209 -0.20701) (xy 0.2159 -0.21717)
						(xy 0.21844 -0.22733) (xy 0.22225 -0.23876) (xy 0.22352 -0.24892) (xy 0.22606 -0.25908) (xy 0.22733 -0.27051)
						(xy 0.22733 -0.28067) (xy 0.2286 -0.2921) (xy 0.22733 -0.30353) (xy 0.22733 -0.31369) (xy 0.22606 -0.32512)
						(xy 0.22352 -0.33528) (xy 0.22225 -0.34544) (xy 0.21844 -0.35687) (xy 0.2159 -0.36703) (xy 0.21209 -0.37719)
						(xy 0.20701 -0.38735) (xy 0.2032 -0.39624) (xy 0.19812 -0.4064) (xy 0.17272 -0.44196) (xy 0.1651 -0.44958)
						(xy 0.1651 -0.7366) (xy 0.16256 -0.76835) (xy 0.1524 -0.8001) (xy 0.13716 -0.82804) (xy 0.11684 -0.85344)
						(xy 0.09144 -0.87376) (xy 0.0635 -0.889) (xy 0.03175 -0.89916)
					)
					(width 0)
					(fill yes)
				)
			)
		)
		(pad "34" smd custom
			(at -21.75002 4.100068)
			(size 0.1143 0.1143)
			(layers "B.Cu" "B.Mask" "B.Paste")
			(net "M_A_DQ14")
			(options
				(clearance outline)
				(anchor circle)
			)
			(primitives
				(gr_poly
					(pts
						(xy 0 -0.9017) (xy -0.03175 -0.89916) (xy -0.0635 -0.889) (xy -0.09144 -0.87376) (xy -0.11684 -0.85344)
						(xy -0.13716 -0.82804) (xy -0.1524 -0.8001) (xy -0.16256 -0.76835) (xy -0.1651 -0.7366) (xy -0.1651 0.13462)
						(xy -0.17272 0.14224) (xy -0.19812 0.1778) (xy -0.2032 0.18796) (xy -0.20701 0.19685) (xy -0.21209 0.20701)
						(xy -0.2159 0.21717) (xy -0.21844 0.22733) (xy -0.22225 0.23876) (xy -0.22352 0.24892) (xy -0.22606 0.25908)
						(xy -0.22733 0.27051) (xy -0.22733 0.28067) (xy -0.2286 0.2921) (xy -0.22733 0.30353) (xy -0.22733 0.31369)
						(xy -0.22606 0.32512) (xy -0.22352 0.33528) (xy -0.22225 0.34544) (xy -0.21844 0.35687) (xy -0.2159 0.36703)
						(xy -0.21209 0.37719) (xy -0.20701 0.38735) (xy -0.2032 0.39624) (xy -0.19812 0.4064) (xy -0.17272 0.44196)
						(xy -0.1651 0.44958) (xy -0.1651 0.7366) (xy -0.16256 0.76835) (xy -0.1524 0.8001) (xy -0.13716 0.82804)
						(xy -0.11684 0.85344) (xy -0.09144 0.87376) (xy -0.0635 0.889) (xy -0.03175 0.89916) (xy 0 0.9017)
						(xy 0.03175 0.89916) (xy 0.0635 0.889) (xy 0.09144 0.87376) (xy 0.11684 0.85344) (xy 0.13716 0.82804)
						(xy 0.1524 0.8001) (xy 0.16256 0.76835) (xy 0.1651 0.7366) (xy 0.1651 0.44958) (xy 0.17272 0.44196)
						(xy 0.19812 0.4064) (xy 0.2032 0.39624) (xy 0.20701 0.38735) (xy 0.21209 0.37719) (xy 0.2159 0.36703)
						(xy 0.21844 0.35687) (xy 0.22225 0.34544) (xy 0.22352 0.33528) (xy 0.22606 0.32512) (xy 0.22733 0.31369)
						(xy 0.22733 0.30353) (xy 0.2286 0.2921) (xy 0.22733 0.28067) (xy 0.22733 0.27051) (xy 0.22606 0.25908)
						(xy 0.22352 0.24892) (xy 0.22225 0.23876) (xy 0.21844 0.22733) (xy 0.2159 0.21717) (xy 0.21209 0.20701)
						(xy 0.20701 0.19685) (xy 0.2032 0.18796) (xy 0.19812 0.1778) (xy 0.17272 0.14224) (xy 0.1651 0.13462)
						(xy 0.1651 -0.7366) (xy 0.16256 -0.76835) (xy 0.1524 -0.8001) (xy 0.13716 -0.82804) (xy 0.11684 -0.85344)
						(xy 0.09144 -0.87376) (xy 0.0635 -0.889) (xy 0.03175 -0.89916)
					)
					(width 0)
					(fill yes)
				)
			)
		)
		(pad "35" smd custom
			(at -21.450046 -4.100068)
			(size 0.1143 0.1143)
			(layers "B.Cu" "B.Mask" "B.Paste")
			(net "GND")
			(options
				(clearance outline)
				(anchor circle)
			)
			(primitives
				(gr_poly
					(pts
						(xy 0 -0.9017) (xy -0.03175 -0.89916) (xy -0.0635 -0.889) (xy -0.09144 -0.87376) (xy -0.11684 -0.85344)
						(xy -0.13716 -0.82804) (xy -0.1524 -0.8001) (xy -0.16256 -0.76835) (xy -0.1651 -0.7366) (xy -0.1651 -0.19685)
						(xy -0.17272 -0.18923) (xy -0.17907 -0.18034) (xy -0.18669 -0.17145) (xy -0.19177 -0.16256) (xy -0.19812 -0.15367)
						(xy -0.20828 -0.13335) (xy -0.21971 -0.10287) (xy -0.22225 -0.09271) (xy -0.22479 -0.08128) (xy -0.22606 -0.07112)
						(xy -0.2286 -0.05969) (xy -0.2286 -0.01651) (xy -0.22606 -0.00508) (xy -0.22479 0.00508) (xy -0.22225 0.01651)
						(xy -0.21971 0.02667) (xy -0.20828 0.05715) (xy -0.19812 0.07747) (xy -0.19177 0.08636) (xy -0.18669 0.09525)
						(xy -0.17907 0.10414) (xy -0.17272 0.11303) (xy -0.1651 0.12065) (xy -0.1651 0.7366) (xy -0.16256 0.76835)
						(xy -0.1524 0.8001) (xy -0.13716 0.82804) (xy -0.11684 0.85344) (xy -0.09144 0.87376) (xy -0.0635 0.889)
						(xy -0.03175 0.89916) (xy 0 0.9017) (xy 0.03175 0.89916) (xy 0.0635 0.889) (xy 0.09144 0.87376)
						(xy 0.11684 0.85344) (xy 0.13716 0.82804) (xy 0.1524 0.8001) (xy 0.16256 0.76835) (xy 0.1651 0.7366)
						(xy 0.1651 0.11938) (xy 0.17272 0.11176) (xy 0.19812 0.0762) (xy 0.2032 0.06604) (xy 0.20701 0.05715)
						(xy 0.21209 0.04699) (xy 0.2159 0.03683) (xy 0.21844 0.02667) (xy 0.22225 0.01524) (xy 0.22352 0.00508)
						(xy 0.22606 -0.00508) (xy 0.22733 -0.01651) (xy 0.22733 -0.02667) (xy 0.2286 -0.0381) (xy 0.22733 -0.04953)
						(xy 0.22733 -0.05969) (xy 0.22606 -0.07112) (xy 0.22352 -0.08128) (xy 0.22225 -0.09144) (xy 0.21844 -0.10287)
						(xy 0.2159 -0.11303) (xy 0.21209 -0.12319) (xy 0.20701 -0.13335) (xy 0.2032 -0.14224) (xy 0.19812 -0.1524)
						(xy 0.17272 -0.18796) (xy 0.1651 -0.19558) (xy 0.1651 -0.7366) (xy 0.16256 -0.76835) (xy 0.1524 -0.8001)
						(xy 0.13716 -0.82804) (xy 0.11684 -0.85344) (xy 0.09144 -0.87376) (xy 0.0635 -0.889) (xy 0.03175 -0.89916)
					)
					(width 0)
					(fill yes)
				)
			)
		)
		(pad "36" smd custom
			(at -21.150072 4.100068)
			(size 0.1143 0.1143)
			(layers "B.Cu" "B.Mask" "B.Paste")
			(net "M_A_DQ15")
			(options
				(clearance outline)
				(anchor circle)
			)
			(primitives
				(gr_poly
					(pts
						(xy 0 -0.9017) (xy -0.03175 -0.89916) (xy -0.0635 -0.889) (xy -0.09144 -0.87376) (xy -0.11684 -0.85344)
						(xy -0.13716 -0.82804) (xy -0.1524 -0.8001) (xy -0.16256 -0.76835) (xy -0.1651 -0.7366) (xy -0.1651 -0.11938)
						(xy -0.17272 -0.11176) (xy -0.19812 -0.0762) (xy -0.2032 -0.06604) (xy -0.20701 -0.05715) (xy -0.21209 -0.04699)
						(xy -0.2159 -0.03683) (xy -0.21844 -0.02667) (xy -0.22225 -0.01524) (xy -0.22352 -0.00508) (xy -0.22606 0.00508)
						(xy -0.22733 0.01651) (xy -0.22733 0.02667) (xy -0.2286 0.0381) (xy -0.22733 0.04953) (xy -0.22733 0.05969)
						(xy -0.22606 0.07112) (xy -0.22352 0.08128) (xy -0.22225 0.09144) (xy -0.21844 0.10287) (xy -0.2159 0.11303)
						(xy -0.21209 0.12319) (xy -0.20701 0.13335) (xy -0.2032 0.14224) (xy -0.19812 0.1524) (xy -0.17272 0.18796)
						(xy -0.1651 0.19558) (xy -0.1651 0.7366) (xy -0.16256 0.76835) (xy -0.1524 0.8001) (xy -0.13716 0.82804)
						(xy -0.11684 0.85344) (xy -0.09144 0.87376) (xy -0.0635 0.889) (xy -0.03175 0.89916) (xy 0 0.9017)
						(xy 0.03175 0.89916) (xy 0.0635 0.889) (xy 0.09144 0.87376) (xy 0.11684 0.85344) (xy 0.13716 0.82804)
						(xy 0.1524 0.8001) (xy 0.16256 0.76835) (xy 0.1651 0.7366) (xy 0.1651 0.19685) (xy 0.17272 0.18923)
						(xy 0.17907 0.18034) (xy 0.18669 0.17145) (xy 0.19177 0.16256) (xy 0.19812 0.15367) (xy 0.20828 0.13335)
						(xy 0.21971 0.10287) (xy 0.22225 0.09271) (xy 0.22479 0.08128) (xy 0.22606 0.07112) (xy 0.2286 0.05969)
						(xy 0.2286 0.01651) (xy 0.22606 0.00508) (xy 0.22479 -0.00508) (xy 0.22225 -0.01651) (xy 0.21971 -0.02667)
						(xy 0.20828 -0.05715) (xy 0.19812 -0.07747) (xy 0.19177 -0.08636) (xy 0.18669 -0.09525) (xy 0.17907 -0.10414)
						(xy 0.17272 -0.11303) (xy 0.1651 -0.12065) (xy 0.1651 -0.7366) (xy 0.16256 -0.76835) (xy 0.1524 -0.8001)
						(xy 0.13716 -0.82804) (xy 0.11684 -0.85344) (xy 0.09144 -0.87376) (xy 0.0635 -0.889) (xy 0.03175 -0.89916)
					)
					(width 0)
					(fill yes)
				)
			)
		)
		(pad "37" smd custom
			(at -20.850098 -4.100068)
			(size 0.1143 0.1143)
			(layers "B.Cu" "B.Mask" "B.Paste")
			(net "M_A_DQ16")
			(options
				(clearance outline)
				(anchor circle)
			)
			(primitives
				(gr_poly
					(pts
						(xy 0 -0.9017) (xy -0.03175 -0.89916) (xy -0.0635 -0.889) (xy -0.09144 -0.87376) (xy -0.11684 -0.85344)
						(xy -0.13716 -0.82804) (xy -0.1524 -0.8001) (xy -0.16256 -0.76835) (xy -0.1651 -0.7366) (xy -0.1651 -0.44958)
						(xy -0.17272 -0.44196) (xy -0.19812 -0.4064) (xy -0.2032 -0.39624) (xy -0.20701 -0.38735) (xy -0.21209 -0.37719)
						(xy -0.2159 -0.36703) (xy -0.21844 -0.35687) (xy -0.22225 -0.34544) (xy -0.22352 -0.33528) (xy -0.22606 -0.32512)
						(xy -0.22733 -0.31369) (xy -0.22733 -0.30353) (xy -0.2286 -0.2921) (xy -0.22733 -0.28067) (xy -0.22733 -0.27051)
						(xy -0.22606 -0.25908) (xy -0.22352 -0.24892) (xy -0.22225 -0.23876) (xy -0.21844 -0.22733) (xy -0.2159 -0.21717)
						(xy -0.21209 -0.20701) (xy -0.20701 -0.19685) (xy -0.2032 -0.18796) (xy -0.19812 -0.1778) (xy -0.17272 -0.14224)
						(xy -0.1651 -0.13462) (xy -0.1651 0.7366) (xy -0.16256 0.76835) (xy -0.1524 0.8001) (xy -0.13716 0.82804)
						(xy -0.11684 0.85344) (xy -0.09144 0.87376) (xy -0.0635 0.889) (xy -0.03175 0.89916) (xy 0 0.9017)
						(xy 0.03175 0.89916) (xy 0.0635 0.889) (xy 0.09144 0.87376) (xy 0.11684 0.85344) (xy 0.13716 0.82804)
						(xy 0.1524 0.8001) (xy 0.16256 0.76835) (xy 0.1651 0.7366) (xy 0.1651 -0.13462) (xy 0.17272 -0.14224)
						(xy 0.19812 -0.1778) (xy 0.2032 -0.18796) (xy 0.20701 -0.19685) (xy 0.21209 -0.20701) (xy 0.2159 -0.21717)
						(xy 0.21844 -0.22733) (xy 0.22225 -0.23876) (xy 0.22352 -0.24892) (xy 0.22606 -0.25908) (xy 0.22733 -0.27051)
						(xy 0.22733 -0.28067) (xy 0.2286 -0.2921) (xy 0.22733 -0.30353) (xy 0.22733 -0.31369) (xy 0.22606 -0.32512)
						(xy 0.22352 -0.33528) (xy 0.22225 -0.34544) (xy 0.21844 -0.35687) (xy 0.2159 -0.36703) (xy 0.21209 -0.37719)
						(xy 0.20701 -0.38735) (xy 0.2032 -0.39624) (xy 0.19812 -0.4064) (xy 0.17272 -0.44196) (xy 0.1651 -0.44958)
						(xy 0.1651 -0.7366) (xy 0.16256 -0.76835) (xy 0.1524 -0.8001) (xy 0.13716 -0.82804) (xy 0.11684 -0.85344)
						(xy 0.09144 -0.87376) (xy 0.0635 -0.889) (xy 0.03175 -0.89916)
					)
					(width 0)
					(fill yes)
				)
			)
		)
		(pad "38" smd custom
			(at -20.550124 4.100068)
			(size 0.1143 0.1143)
			(layers "B.Cu" "B.Mask" "B.Paste")
			(net "GND")
			(options
				(clearance outline)
				(anchor circle)
			)
			(primitives
				(gr_poly
					(pts
						(xy 0 -0.9017) (xy -0.03175 -0.89916) (xy -0.0635 -0.889) (xy -0.09144 -0.87376) (xy -0.11684 -0.85344)
						(xy -0.13716 -0.82804) (xy -0.1524 -0.8001) (xy -0.16256 -0.76835) (xy -0.1651 -0.7366) (xy -0.1651 0.13462)
						(xy -0.17272 0.14224) (xy -0.19812 0.1778) (xy -0.2032 0.18796) (xy -0.20701 0.19685) (xy -0.21209 0.20701)
						(xy -0.2159 0.21717) (xy -0.21844 0.22733) (xy -0.22225 0.23876) (xy -0.22352 0.24892) (xy -0.22606 0.25908)
						(xy -0.22733 0.27051) (xy -0.22733 0.28067) (xy -0.2286 0.2921) (xy -0.22733 0.30353) (xy -0.22733 0.31369)
						(xy -0.22606 0.32512) (xy -0.22352 0.33528) (xy -0.22225 0.34544) (xy -0.21844 0.35687) (xy -0.2159 0.36703)
						(xy -0.21209 0.37719) (xy -0.20701 0.38735) (xy -0.2032 0.39624) (xy -0.19812 0.4064) (xy -0.17272 0.44196)
						(xy -0.1651 0.44958) (xy -0.1651 0.7366) (xy -0.16256 0.76835) (xy -0.1524 0.8001) (xy -0.13716 0.82804)
						(xy -0.11684 0.85344) (xy -0.09144 0.87376) (xy -0.0635 0.889) (xy -0.03175 0.89916) (xy 0 0.9017)
						(xy 0.03175 0.89916) (xy 0.0635 0.889) (xy 0.09144 0.87376) (xy 0.11684 0.85344) (xy 0.13716 0.82804)
						(xy 0.1524 0.8001) (xy 0.16256 0.76835) (xy 0.1651 0.7366) (xy 0.1651 0.44958) (xy 0.17272 0.44196)
						(xy 0.19812 0.4064) (xy 0.2032 0.39624) (xy 0.20701 0.38735) (xy 0.21209 0.37719) (xy 0.2159 0.36703)
						(xy 0.21844 0.35687) (xy 0.22225 0.34544) (xy 0.22352 0.33528) (xy 0.22606 0.32512) (xy 0.22733 0.31369)
						(xy 0.22733 0.30353) (xy 0.2286 0.2921) (xy 0.22733 0.28067) (xy 0.22733 0.27051) (xy 0.22606 0.25908)
						(xy 0.22352 0.24892) (xy 0.22225 0.23876) (xy 0.21844 0.22733) (xy 0.2159 0.21717) (xy 0.21209 0.20701)
						(xy 0.20701 0.19685) (xy 0.2032 0.18796) (xy 0.19812 0.1778) (xy 0.17272 0.14224) (xy 0.1651 0.13462)
						(xy 0.1651 -0.7366) (xy 0.16256 -0.76835) (xy 0.1524 -0.8001) (xy 0.13716 -0.82804) (xy 0.11684 -0.85344)
						(xy 0.09144 -0.87376) (xy 0.0635 -0.889) (xy 0.03175 -0.89916)
					)
					(width 0)
					(fill yes)
				)
			)
		)
		(pad "39" smd custom
			(at -20.249896 -4.100068)
			(size 0.1143 0.1143)
			(layers "B.Cu" "B.Mask" "B.Paste")
			(net "M_A_DQ17")
			(options
				(clearance outline)
				(anchor circle)
			)
			(primitives
				(gr_poly
					(pts
						(xy 0 -0.9017) (xy -0.03175 -0.89916) (xy -0.0635 -0.889) (xy -0.09144 -0.87376) (xy -0.11684 -0.85344)
						(xy -0.13716 -0.82804) (xy -0.1524 -0.8001) (xy -0.16256 -0.76835) (xy -0.1651 -0.7366) (xy -0.1651 -0.19685)
						(xy -0.17272 -0.18923) (xy -0.17907 -0.18034) (xy -0.18669 -0.17145) (xy -0.19177 -0.16256) (xy -0.19812 -0.15367)
						(xy -0.20828 -0.13335) (xy -0.21971 -0.10287) (xy -0.22225 -0.09271) (xy -0.22479 -0.08128) (xy -0.22606 -0.07112)
						(xy -0.2286 -0.05969) (xy -0.2286 -0.01651) (xy -0.22606 -0.00508) (xy -0.22479 0.00508) (xy -0.22225 0.01651)
						(xy -0.21971 0.02667) (xy -0.20828 0.05715) (xy -0.19812 0.07747) (xy -0.19177 0.08636) (xy -0.18669 0.09525)
						(xy -0.17907 0.10414) (xy -0.17272 0.11303) (xy -0.1651 0.12065) (xy -0.1651 0.7366) (xy -0.16256 0.76835)
						(xy -0.1524 0.8001) (xy -0.13716 0.82804) (xy -0.11684 0.85344) (xy -0.09144 0.87376) (xy -0.0635 0.889)
						(xy -0.03175 0.89916) (xy 0 0.9017) (xy 0.03175 0.89916) (xy 0.0635 0.889) (xy 0.09144 0.87376)
						(xy 0.11684 0.85344) (xy 0.13716 0.82804) (xy 0.1524 0.8001) (xy 0.16256 0.76835) (xy 0.1651 0.7366)
						(xy 0.1651 0.11938) (xy 0.17272 0.11176) (xy 0.19812 0.0762) (xy 0.2032 0.06604) (xy 0.20701 0.05715)
						(xy 0.21209 0.04699) (xy 0.2159 0.03683) (xy 0.21844 0.02667) (xy 0.22225 0.01524) (xy 0.22352 0.00508)
						(xy 0.22606 -0.00508) (xy 0.22733 -0.01651) (xy 0.22733 -0.02667) (xy 0.2286 -0.0381) (xy 0.22733 -0.04953)
						(xy 0.22733 -0.05969) (xy 0.22606 -0.07112) (xy 0.22352 -0.08128) (xy 0.22225 -0.09144) (xy 0.21844 -0.10287)
						(xy 0.2159 -0.11303) (xy 0.21209 -0.12319) (xy 0.20701 -0.13335) (xy 0.2032 -0.14224) (xy 0.19812 -0.1524)
						(xy 0.17272 -0.18796) (xy 0.1651 -0.19558) (xy 0.1651 -0.7366) (xy 0.16256 -0.76835) (xy 0.1524 -0.8001)
						(xy 0.13716 -0.82804) (xy 0.11684 -0.85344) (xy 0.09144 -0.87376) (xy 0.0635 -0.889) (xy 0.03175 -0.89916)
					)
					(width 0)
					(fill yes)
				)
			)
		)
		(pad "40" smd custom
			(at -19.949922 4.100068)
			(size 0.1143 0.1143)
			(layers "B.Cu" "B.Mask" "B.Paste")
			(net "M_A_DQ20")
			(options
				(clearance outline)
				(anchor circle)
			)
			(primitives
				(gr_poly
					(pts
						(xy 0 -0.9017) (xy -0.03175 -0.89916) (xy -0.0635 -0.889) (xy -0.09144 -0.87376) (xy -0.11684 -0.85344)
						(xy -0.13716 -0.82804) (xy -0.1524 -0.8001) (xy -0.16256 -0.76835) (xy -0.1651 -0.7366) (xy -0.1651 -0.11938)
						(xy -0.17272 -0.11176) (xy -0.19812 -0.0762) (xy -0.2032 -0.06604) (xy -0.20701 -0.05715) (xy -0.21209 -0.04699)
						(xy -0.2159 -0.03683) (xy -0.21844 -0.02667) (xy -0.22225 -0.01524) (xy -0.22352 -0.00508) (xy -0.22606 0.00508)
						(xy -0.22733 0.01651) (xy -0.22733 0.02667) (xy -0.2286 0.0381) (xy -0.22733 0.04953) (xy -0.22733 0.05969)
						(xy -0.22606 0.07112) (xy -0.22352 0.08128) (xy -0.22225 0.09144) (xy -0.21844 0.10287) (xy -0.2159 0.11303)
						(xy -0.21209 0.12319) (xy -0.20701 0.13335) (xy -0.2032 0.14224) (xy -0.19812 0.1524) (xy -0.17272 0.18796)
						(xy -0.1651 0.19558) (xy -0.1651 0.7366) (xy -0.16256 0.76835) (xy -0.1524 0.8001) (xy -0.13716 0.82804)
						(xy -0.11684 0.85344) (xy -0.09144 0.87376) (xy -0.0635 0.889) (xy -0.03175 0.89916) (xy 0 0.9017)
						(xy 0.03175 0.89916) (xy 0.0635 0.889) (xy 0.09144 0.87376) (xy 0.11684 0.85344) (xy 0.13716 0.82804)
						(xy 0.1524 0.8001) (xy 0.16256 0.76835) (xy 0.1651 0.7366) (xy 0.1651 0.19685) (xy 0.17272 0.18923)
						(xy 0.17907 0.18034) (xy 0.18669 0.17145) (xy 0.19177 0.16256) (xy 0.19812 0.15367) (xy 0.20828 0.13335)
						(xy 0.21971 0.10287) (xy 0.22225 0.09271) (xy 0.22479 0.08128) (xy 0.22606 0.07112) (xy 0.2286 0.05969)
						(xy 0.2286 0.01651) (xy 0.22606 0.00508) (xy 0.22479 -0.00508) (xy 0.22225 -0.01651) (xy 0.21971 -0.02667)
						(xy 0.20828 -0.05715) (xy 0.19812 -0.07747) (xy 0.19177 -0.08636) (xy 0.18669 -0.09525) (xy 0.17907 -0.10414)
						(xy 0.17272 -0.11303) (xy 0.1651 -0.12065) (xy 0.1651 -0.7366) (xy 0.16256 -0.76835) (xy 0.1524 -0.8001)
						(xy 0.13716 -0.82804) (xy 0.11684 -0.85344) (xy 0.09144 -0.87376) (xy 0.0635 -0.889) (xy 0.03175 -0.89916)
					)
					(width 0)
					(fill yes)
				)
			)
		)
		(pad "41" smd custom
			(at -19.649948 -4.100068)
			(size 0.1143 0.1143)
			(layers "B.Cu" "B.Mask" "B.Paste")
			(net "GND")
			(options
				(clearance outline)
				(anchor circle)
			)
			(primitives
				(gr_poly
					(pts
						(xy 0 -0.9017) (xy -0.03175 -0.89916) (xy -0.0635 -0.889) (xy -0.09144 -0.87376) (xy -0.11684 -0.85344)
						(xy -0.13716 -0.82804) (xy -0.1524 -0.8001) (xy -0.16256 -0.76835) (xy -0.1651 -0.7366) (xy -0.1651 -0.44958)
						(xy -0.17272 -0.44196) (xy -0.19812 -0.4064) (xy -0.2032 -0.39624) (xy -0.20701 -0.38735) (xy -0.21209 -0.37719)
						(xy -0.2159 -0.36703) (xy -0.21844 -0.35687) (xy -0.22225 -0.34544) (xy -0.22352 -0.33528) (xy -0.22606 -0.32512)
						(xy -0.22733 -0.31369) (xy -0.22733 -0.30353) (xy -0.2286 -0.2921) (xy -0.22733 -0.28067) (xy -0.22733 -0.27051)
						(xy -0.22606 -0.25908) (xy -0.22352 -0.24892) (xy -0.22225 -0.23876) (xy -0.21844 -0.22733) (xy -0.2159 -0.21717)
						(xy -0.21209 -0.20701) (xy -0.20701 -0.19685) (xy -0.2032 -0.18796) (xy -0.19812 -0.1778) (xy -0.17272 -0.14224)
						(xy -0.1651 -0.13462) (xy -0.1651 0.7366) (xy -0.16256 0.76835) (xy -0.1524 0.8001) (xy -0.13716 0.82804)
						(xy -0.11684 0.85344) (xy -0.09144 0.87376) (xy -0.0635 0.889) (xy -0.03175 0.89916) (xy 0 0.9017)
						(xy 0.03175 0.89916) (xy 0.0635 0.889) (xy 0.09144 0.87376) (xy 0.11684 0.85344) (xy 0.13716 0.82804)
						(xy 0.1524 0.8001) (xy 0.16256 0.76835) (xy 0.1651 0.7366) (xy 0.1651 -0.13462) (xy 0.17272 -0.14224)
						(xy 0.19812 -0.1778) (xy 0.2032 -0.18796) (xy 0.20701 -0.19685) (xy 0.21209 -0.20701) (xy 0.2159 -0.21717)
						(xy 0.21844 -0.22733) (xy 0.22225 -0.23876) (xy 0.22352 -0.24892) (xy 0.22606 -0.25908) (xy 0.22733 -0.27051)
						(xy 0.22733 -0.28067) (xy 0.2286 -0.2921) (xy 0.22733 -0.30353) (xy 0.22733 -0.31369) (xy 0.22606 -0.32512)
						(xy 0.22352 -0.33528) (xy 0.22225 -0.34544) (xy 0.21844 -0.35687) (xy 0.2159 -0.36703) (xy 0.21209 -0.37719)
						(xy 0.20701 -0.38735) (xy 0.2032 -0.39624) (xy 0.19812 -0.4064) (xy 0.17272 -0.44196) (xy 0.1651 -0.44958)
						(xy 0.1651 -0.7366) (xy 0.16256 -0.76835) (xy 0.1524 -0.8001) (xy 0.13716 -0.82804) (xy 0.11684 -0.85344)
						(xy 0.09144 -0.87376) (xy 0.0635 -0.889) (xy 0.03175 -0.89916)
					)
					(width 0)
					(fill yes)
				)
			)
		)
		(pad "42" smd custom
			(at -19.349974 4.100068)
			(size 0.1143 0.1143)
			(layers "B.Cu" "B.Mask" "B.Paste")
			(net "M_A_DQ21")
			(options
				(clearance outline)
				(anchor circle)
			)
			(primitives
				(gr_poly
					(pts
						(xy 0 -0.9017) (xy -0.03175 -0.89916) (xy -0.0635 -0.889) (xy -0.09144 -0.87376) (xy -0.11684 -0.85344)
						(xy -0.13716 -0.82804) (xy -0.1524 -0.8001) (xy -0.16256 -0.76835) (xy -0.1651 -0.7366) (xy -0.1651 0.13462)
						(xy -0.17272 0.14224) (xy -0.19812 0.1778) (xy -0.2032 0.18796) (xy -0.20701 0.19685) (xy -0.21209 0.20701)
						(xy -0.2159 0.21717) (xy -0.21844 0.22733) (xy -0.22225 0.23876) (xy -0.22352 0.24892) (xy -0.22606 0.25908)
						(xy -0.22733 0.27051) (xy -0.22733 0.28067) (xy -0.2286 0.2921) (xy -0.22733 0.30353) (xy -0.22733 0.31369)
						(xy -0.22606 0.32512) (xy -0.22352 0.33528) (xy -0.22225 0.34544) (xy -0.21844 0.35687) (xy -0.2159 0.36703)
						(xy -0.21209 0.37719) (xy -0.20701 0.38735) (xy -0.2032 0.39624) (xy -0.19812 0.4064) (xy -0.17272 0.44196)
						(xy -0.1651 0.44958) (xy -0.1651 0.7366) (xy -0.16256 0.76835) (xy -0.1524 0.8001) (xy -0.13716 0.82804)
						(xy -0.11684 0.85344) (xy -0.09144 0.87376) (xy -0.0635 0.889) (xy -0.03175 0.89916) (xy 0 0.9017)
						(xy 0.03175 0.89916) (xy 0.0635 0.889) (xy 0.09144 0.87376) (xy 0.11684 0.85344) (xy 0.13716 0.82804)
						(xy 0.1524 0.8001) (xy 0.16256 0.76835) (xy 0.1651 0.7366) (xy 0.1651 0.44958) (xy 0.17272 0.44196)
						(xy 0.19812 0.4064) (xy 0.2032 0.39624) (xy 0.20701 0.38735) (xy 0.21209 0.37719) (xy 0.2159 0.36703)
						(xy 0.21844 0.35687) (xy 0.22225 0.34544) (xy 0.22352 0.33528) (xy 0.22606 0.32512) (xy 0.22733 0.31369)
						(xy 0.22733 0.30353) (xy 0.2286 0.2921) (xy 0.22733 0.28067) (xy 0.22733 0.27051) (xy 0.22606 0.25908)
						(xy 0.22352 0.24892) (xy 0.22225 0.23876) (xy 0.21844 0.22733) (xy 0.2159 0.21717) (xy 0.21209 0.20701)
						(xy 0.20701 0.19685) (xy 0.2032 0.18796) (xy 0.19812 0.1778) (xy 0.17272 0.14224) (xy 0.1651 0.13462)
						(xy 0.1651 -0.7366) (xy 0.16256 -0.76835) (xy 0.1524 -0.8001) (xy 0.13716 -0.82804) (xy 0.11684 -0.85344)
						(xy 0.09144 -0.87376) (xy 0.0635 -0.889) (xy 0.03175 -0.89916)
					)
					(width 0)
					(fill yes)
				)
			)
		)
		(pad "43" smd custom
			(at -19.05 -4.100068)
			(size 0.1143 0.1143)
			(layers "B.Cu" "B.Mask" "B.Paste")
			(net "M_A_DQS_DN2")
			(options
				(clearance outline)
				(anchor circle)
			)
			(primitives
				(gr_poly
					(pts
						(xy 0 -0.9017) (xy -0.03175 -0.89916) (xy -0.0635 -0.889) (xy -0.09144 -0.87376) (xy -0.11684 -0.85344)
						(xy -0.13716 -0.82804) (xy -0.1524 -0.8001) (xy -0.16256 -0.76835) (xy -0.1651 -0.7366) (xy -0.1651 -0.19685)
						(xy -0.17272 -0.18923) (xy -0.17907 -0.18034) (xy -0.18669 -0.17145) (xy -0.19177 -0.16256) (xy -0.19812 -0.15367)
						(xy -0.20828 -0.13335) (xy -0.21971 -0.10287) (xy -0.22225 -0.09271) (xy -0.22479 -0.08128) (xy -0.22606 -0.07112)
						(xy -0.2286 -0.05969) (xy -0.2286 -0.01651) (xy -0.22606 -0.00508) (xy -0.22479 0.00508) (xy -0.22225 0.01651)
						(xy -0.21971 0.02667) (xy -0.20828 0.05715) (xy -0.19812 0.07747) (xy -0.19177 0.08636) (xy -0.18669 0.09525)
						(xy -0.17907 0.10414) (xy -0.17272 0.11303) (xy -0.1651 0.12065) (xy -0.1651 0.7366) (xy -0.16256 0.76835)
						(xy -0.1524 0.8001) (xy -0.13716 0.82804) (xy -0.11684 0.85344) (xy -0.09144 0.87376) (xy -0.0635 0.889)
						(xy -0.03175 0.89916) (xy 0 0.9017) (xy 0.03175 0.89916) (xy 0.0635 0.889) (xy 0.09144 0.87376)
						(xy 0.11684 0.85344) (xy 0.13716 0.82804) (xy 0.1524 0.8001) (xy 0.16256 0.76835) (xy 0.1651 0.7366)
						(xy 0.1651 0.11938) (xy 0.17272 0.11176) (xy 0.19812 0.0762) (xy 0.2032 0.06604) (xy 0.20701 0.05715)
						(xy 0.21209 0.04699) (xy 0.2159 0.03683) (xy 0.21844 0.02667) (xy 0.22225 0.01524) (xy 0.22352 0.00508)
						(xy 0.22606 -0.00508) (xy 0.22733 -0.01651) (xy 0.22733 -0.02667) (xy 0.2286 -0.0381) (xy 0.22733 -0.04953)
						(xy 0.22733 -0.05969) (xy 0.22606 -0.07112) (xy 0.22352 -0.08128) (xy 0.22225 -0.09144) (xy 0.21844 -0.10287)
						(xy 0.2159 -0.11303) (xy 0.21209 -0.12319) (xy 0.20701 -0.13335) (xy 0.2032 -0.14224) (xy 0.19812 -0.1524)
						(xy 0.17272 -0.18796) (xy 0.1651 -0.19558) (xy 0.1651 -0.7366) (xy 0.16256 -0.76835) (xy 0.1524 -0.8001)
						(xy 0.13716 -0.82804) (xy 0.11684 -0.85344) (xy 0.09144 -0.87376) (xy 0.0635 -0.889) (xy 0.03175 -0.89916)
					)
					(width 0)
					(fill yes)
				)
			)
		)
		(pad "44" smd custom
			(at -18.750026 4.100068)
			(size 0.1143 0.1143)
			(layers "B.Cu" "B.Mask" "B.Paste")
			(net "GND")
			(options
				(clearance outline)
				(anchor circle)
			)
			(primitives
				(gr_poly
					(pts
						(xy 0 -0.9017) (xy -0.03175 -0.89916) (xy -0.0635 -0.889) (xy -0.09144 -0.87376) (xy -0.11684 -0.85344)
						(xy -0.13716 -0.82804) (xy -0.1524 -0.8001) (xy -0.16256 -0.76835) (xy -0.1651 -0.7366) (xy -0.1651 -0.11938)
						(xy -0.17272 -0.11176) (xy -0.19812 -0.0762) (xy -0.2032 -0.06604) (xy -0.20701 -0.05715) (xy -0.21209 -0.04699)
						(xy -0.2159 -0.03683) (xy -0.21844 -0.02667) (xy -0.22225 -0.01524) (xy -0.22352 -0.00508) (xy -0.22606 0.00508)
						(xy -0.22733 0.01651) (xy -0.22733 0.02667) (xy -0.2286 0.0381) (xy -0.22733 0.04953) (xy -0.22733 0.05969)
						(xy -0.22606 0.07112) (xy -0.22352 0.08128) (xy -0.22225 0.09144) (xy -0.21844 0.10287) (xy -0.2159 0.11303)
						(xy -0.21209 0.12319) (xy -0.20701 0.13335) (xy -0.2032 0.14224) (xy -0.19812 0.1524) (xy -0.17272 0.18796)
						(xy -0.1651 0.19558) (xy -0.1651 0.7366) (xy -0.16256 0.76835) (xy -0.1524 0.8001) (xy -0.13716 0.82804)
						(xy -0.11684 0.85344) (xy -0.09144 0.87376) (xy -0.0635 0.889) (xy -0.03175 0.89916) (xy 0 0.9017)
						(xy 0.03175 0.89916) (xy 0.0635 0.889) (xy 0.09144 0.87376) (xy 0.11684 0.85344) (xy 0.13716 0.82804)
						(xy 0.1524 0.8001) (xy 0.16256 0.76835) (xy 0.1651 0.7366) (xy 0.1651 0.19685) (xy 0.17272 0.18923)
						(xy 0.17907 0.18034) (xy 0.18669 0.17145) (xy 0.19177 0.16256) (xy 0.19812 0.15367) (xy 0.20828 0.13335)
						(xy 0.21971 0.10287) (xy 0.22225 0.09271) (xy 0.22479 0.08128) (xy 0.22606 0.07112) (xy 0.2286 0.05969)
						(xy 0.2286 0.01651) (xy 0.22606 0.00508) (xy 0.22479 -0.00508) (xy 0.22225 -0.01651) (xy 0.21971 -0.02667)
						(xy 0.20828 -0.05715) (xy 0.19812 -0.07747) (xy 0.19177 -0.08636) (xy 0.18669 -0.09525) (xy 0.17907 -0.10414)
						(xy 0.17272 -0.11303) (xy 0.1651 -0.12065) (xy 0.1651 -0.7366) (xy 0.16256 -0.76835) (xy 0.1524 -0.8001)
						(xy 0.13716 -0.82804) (xy 0.11684 -0.85344) (xy 0.09144 -0.87376) (xy 0.0635 -0.889) (xy 0.03175 -0.89916)
					)
					(width 0)
					(fill yes)
				)
			)
		)
		(pad "45" smd custom
			(at -18.450052 -4.100068)
			(size 0.1143 0.1143)
			(layers "B.Cu" "B.Mask" "B.Paste")
			(net "M_A_DQS_DP2")
			(options
				(clearance outline)
				(anchor circle)
			)
			(primitives
				(gr_poly
					(pts
						(xy 0 -0.9017) (xy -0.03175 -0.89916) (xy -0.0635 -0.889) (xy -0.09144 -0.87376) (xy -0.11684 -0.85344)
						(xy -0.13716 -0.82804) (xy -0.1524 -0.8001) (xy -0.16256 -0.76835) (xy -0.1651 -0.7366) (xy -0.1651 -0.44958)
						(xy -0.17272 -0.44196) (xy -0.19812 -0.4064) (xy -0.2032 -0.39624) (xy -0.20701 -0.38735) (xy -0.21209 -0.37719)
						(xy -0.2159 -0.36703) (xy -0.21844 -0.35687) (xy -0.22225 -0.34544) (xy -0.22352 -0.33528) (xy -0.22606 -0.32512)
						(xy -0.22733 -0.31369) (xy -0.22733 -0.30353) (xy -0.2286 -0.2921) (xy -0.22733 -0.28067) (xy -0.22733 -0.27051)
						(xy -0.22606 -0.25908) (xy -0.22352 -0.24892) (xy -0.22225 -0.23876) (xy -0.21844 -0.22733) (xy -0.2159 -0.21717)
						(xy -0.21209 -0.20701) (xy -0.20701 -0.19685) (xy -0.2032 -0.18796) (xy -0.19812 -0.1778) (xy -0.17272 -0.14224)
						(xy -0.1651 -0.13462) (xy -0.1651 0.7366) (xy -0.16256 0.76835) (xy -0.1524 0.8001) (xy -0.13716 0.82804)
						(xy -0.11684 0.85344) (xy -0.09144 0.87376) (xy -0.0635 0.889) (xy -0.03175 0.89916) (xy 0 0.9017)
						(xy 0.03175 0.89916) (xy 0.0635 0.889) (xy 0.09144 0.87376) (xy 0.11684 0.85344) (xy 0.13716 0.82804)
						(xy 0.1524 0.8001) (xy 0.16256 0.76835) (xy 0.1651 0.7366) (xy 0.1651 -0.13462) (xy 0.17272 -0.14224)
						(xy 0.19812 -0.1778) (xy 0.2032 -0.18796) (xy 0.20701 -0.19685) (xy 0.21209 -0.20701) (xy 0.2159 -0.21717)
						(xy 0.21844 -0.22733) (xy 0.22225 -0.23876) (xy 0.22352 -0.24892) (xy 0.22606 -0.25908) (xy 0.22733 -0.27051)
						(xy 0.22733 -0.28067) (xy 0.2286 -0.2921) (xy 0.22733 -0.30353) (xy 0.22733 -0.31369) (xy 0.22606 -0.32512)
						(xy 0.22352 -0.33528) (xy 0.22225 -0.34544) (xy 0.21844 -0.35687) (xy 0.2159 -0.36703) (xy 0.21209 -0.37719)
						(xy 0.20701 -0.38735) (xy 0.2032 -0.39624) (xy 0.19812 -0.4064) (xy 0.17272 -0.44196) (xy 0.1651 -0.44958)
						(xy 0.1651 -0.7366) (xy 0.16256 -0.76835) (xy 0.1524 -0.8001) (xy 0.13716 -0.82804) (xy 0.11684 -0.85344)
						(xy 0.09144 -0.87376) (xy 0.0635 -0.889) (xy 0.03175 -0.89916)
					)
					(width 0)
					(fill yes)
				)
			)
		)
		(pad "46" smd custom
			(at -18.150078 4.100068)
			(size 0.1143 0.1143)
			(layers "B.Cu" "B.Mask" "B.Paste")
			(net "GND")
			(options
				(clearance outline)
				(anchor circle)
			)
			(primitives
				(gr_poly
					(pts
						(xy 0 -0.9017) (xy -0.03175 -0.89916) (xy -0.0635 -0.889) (xy -0.09144 -0.87376) (xy -0.11684 -0.85344)
						(xy -0.13716 -0.82804) (xy -0.1524 -0.8001) (xy -0.16256 -0.76835) (xy -0.1651 -0.7366) (xy -0.1651 0.13462)
						(xy -0.17272 0.14224) (xy -0.19812 0.1778) (xy -0.2032 0.18796) (xy -0.20701 0.19685) (xy -0.21209 0.20701)
						(xy -0.2159 0.21717) (xy -0.21844 0.22733) (xy -0.22225 0.23876) (xy -0.22352 0.24892) (xy -0.22606 0.25908)
						(xy -0.22733 0.27051) (xy -0.22733 0.28067) (xy -0.2286 0.2921) (xy -0.22733 0.30353) (xy -0.22733 0.31369)
						(xy -0.22606 0.32512) (xy -0.22352 0.33528) (xy -0.22225 0.34544) (xy -0.21844 0.35687) (xy -0.2159 0.36703)
						(xy -0.21209 0.37719) (xy -0.20701 0.38735) (xy -0.2032 0.39624) (xy -0.19812 0.4064) (xy -0.17272 0.44196)
						(xy -0.1651 0.44958) (xy -0.1651 0.7366) (xy -0.16256 0.76835) (xy -0.1524 0.8001) (xy -0.13716 0.82804)
						(xy -0.11684 0.85344) (xy -0.09144 0.87376) (xy -0.0635 0.889) (xy -0.03175 0.89916) (xy 0 0.9017)
						(xy 0.03175 0.89916) (xy 0.0635 0.889) (xy 0.09144 0.87376) (xy 0.11684 0.85344) (xy 0.13716 0.82804)
						(xy 0.1524 0.8001) (xy 0.16256 0.76835) (xy 0.1651 0.7366) (xy 0.1651 0.44958) (xy 0.17272 0.44196)
						(xy 0.19812 0.4064) (xy 0.2032 0.39624) (xy 0.20701 0.38735) (xy 0.21209 0.37719) (xy 0.2159 0.36703)
						(xy 0.21844 0.35687) (xy 0.22225 0.34544) (xy 0.22352 0.33528) (xy 0.22606 0.32512) (xy 0.22733 0.31369)
						(xy 0.22733 0.30353) (xy 0.2286 0.2921) (xy 0.22733 0.28067) (xy 0.22733 0.27051) (xy 0.22606 0.25908)
						(xy 0.22352 0.24892) (xy 0.22225 0.23876) (xy 0.21844 0.22733) (xy 0.2159 0.21717) (xy 0.21209 0.20701)
						(xy 0.20701 0.19685) (xy 0.2032 0.18796) (xy 0.19812 0.1778) (xy 0.17272 0.14224) (xy 0.1651 0.13462)
						(xy 0.1651 -0.7366) (xy 0.16256 -0.76835) (xy 0.1524 -0.8001) (xy 0.13716 -0.82804) (xy 0.11684 -0.85344)
						(xy 0.09144 -0.87376) (xy 0.0635 -0.889) (xy 0.03175 -0.89916)
					)
					(width 0)
					(fill yes)
				)
			)
		)
		(pad "47" smd custom
			(at -17.850104 -4.100068)
			(size 0.1143 0.1143)
			(layers "B.Cu" "B.Mask" "B.Paste")
			(net "GND")
			(options
				(clearance outline)
				(anchor circle)
			)
			(primitives
				(gr_poly
					(pts
						(xy 0 -0.9017) (xy -0.03175 -0.89916) (xy -0.0635 -0.889) (xy -0.09144 -0.87376) (xy -0.11684 -0.85344)
						(xy -0.13716 -0.82804) (xy -0.1524 -0.8001) (xy -0.16256 -0.76835) (xy -0.1651 -0.7366) (xy -0.1651 -0.19685)
						(xy -0.17272 -0.18923) (xy -0.17907 -0.18034) (xy -0.18669 -0.17145) (xy -0.19177 -0.16256) (xy -0.19812 -0.15367)
						(xy -0.20828 -0.13335) (xy -0.21971 -0.10287) (xy -0.22225 -0.09271) (xy -0.22479 -0.08128) (xy -0.22606 -0.07112)
						(xy -0.2286 -0.05969) (xy -0.2286 -0.01651) (xy -0.22606 -0.00508) (xy -0.22479 0.00508) (xy -0.22225 0.01651)
						(xy -0.21971 0.02667) (xy -0.20828 0.05715) (xy -0.19812 0.07747) (xy -0.19177 0.08636) (xy -0.18669 0.09525)
						(xy -0.17907 0.10414) (xy -0.17272 0.11303) (xy -0.1651 0.12065) (xy -0.1651 0.7366) (xy -0.16256 0.76835)
						(xy -0.1524 0.8001) (xy -0.13716 0.82804) (xy -0.11684 0.85344) (xy -0.09144 0.87376) (xy -0.0635 0.889)
						(xy -0.03175 0.89916) (xy 0 0.9017) (xy 0.03175 0.89916) (xy 0.0635 0.889) (xy 0.09144 0.87376)
						(xy 0.11684 0.85344) (xy 0.13716 0.82804) (xy 0.1524 0.8001) (xy 0.16256 0.76835) (xy 0.1651 0.7366)
						(xy 0.1651 0.11938) (xy 0.17272 0.11176) (xy 0.19812 0.0762) (xy 0.2032 0.06604) (xy 0.20701 0.05715)
						(xy 0.21209 0.04699) (xy 0.2159 0.03683) (xy 0.21844 0.02667) (xy 0.22225 0.01524) (xy 0.22352 0.00508)
						(xy 0.22606 -0.00508) (xy 0.22733 -0.01651) (xy 0.22733 -0.02667) (xy 0.2286 -0.0381) (xy 0.22733 -0.04953)
						(xy 0.22733 -0.05969) (xy 0.22606 -0.07112) (xy 0.22352 -0.08128) (xy 0.22225 -0.09144) (xy 0.21844 -0.10287)
						(xy 0.2159 -0.11303) (xy 0.21209 -0.12319) (xy 0.20701 -0.13335) (xy 0.2032 -0.14224) (xy 0.19812 -0.1524)
						(xy 0.17272 -0.18796) (xy 0.1651 -0.19558) (xy 0.1651 -0.7366) (xy 0.16256 -0.76835) (xy 0.1524 -0.8001)
						(xy 0.13716 -0.82804) (xy 0.11684 -0.85344) (xy 0.09144 -0.87376) (xy 0.0635 -0.889) (xy 0.03175 -0.89916)
					)
					(width 0)
					(fill yes)
				)
			)
		)
		(pad "48" smd custom
			(at -17.549876 4.100068)
			(size 0.1143 0.1143)
			(layers "B.Cu" "B.Mask" "B.Paste")
			(net "M_A_DQ22")
			(options
				(clearance outline)
				(anchor circle)
			)
			(primitives
				(gr_poly
					(pts
						(xy 0 -0.9017) (xy -0.03175 -0.89916) (xy -0.0635 -0.889) (xy -0.09144 -0.87376) (xy -0.11684 -0.85344)
						(xy -0.13716 -0.82804) (xy -0.1524 -0.8001) (xy -0.16256 -0.76835) (xy -0.1651 -0.7366) (xy -0.1651 -0.11938)
						(xy -0.17272 -0.11176) (xy -0.19812 -0.0762) (xy -0.2032 -0.06604) (xy -0.20701 -0.05715) (xy -0.21209 -0.04699)
						(xy -0.2159 -0.03683) (xy -0.21844 -0.02667) (xy -0.22225 -0.01524) (xy -0.22352 -0.00508) (xy -0.22606 0.00508)
						(xy -0.22733 0.01651) (xy -0.22733 0.02667) (xy -0.2286 0.0381) (xy -0.22733 0.04953) (xy -0.22733 0.05969)
						(xy -0.22606 0.07112) (xy -0.22352 0.08128) (xy -0.22225 0.09144) (xy -0.21844 0.10287) (xy -0.2159 0.11303)
						(xy -0.21209 0.12319) (xy -0.20701 0.13335) (xy -0.2032 0.14224) (xy -0.19812 0.1524) (xy -0.17272 0.18796)
						(xy -0.1651 0.19558) (xy -0.1651 0.7366) (xy -0.16256 0.76835) (xy -0.1524 0.8001) (xy -0.13716 0.82804)
						(xy -0.11684 0.85344) (xy -0.09144 0.87376) (xy -0.0635 0.889) (xy -0.03175 0.89916) (xy 0 0.9017)
						(xy 0.03175 0.89916) (xy 0.0635 0.889) (xy 0.09144 0.87376) (xy 0.11684 0.85344) (xy 0.13716 0.82804)
						(xy 0.1524 0.8001) (xy 0.16256 0.76835) (xy 0.1651 0.7366) (xy 0.1651 0.19685) (xy 0.17272 0.18923)
						(xy 0.17907 0.18034) (xy 0.18669 0.17145) (xy 0.19177 0.16256) (xy 0.19812 0.15367) (xy 0.20828 0.13335)
						(xy 0.21971 0.10287) (xy 0.22225 0.09271) (xy 0.22479 0.08128) (xy 0.22606 0.07112) (xy 0.2286 0.05969)
						(xy 0.2286 0.01651) (xy 0.22606 0.00508) (xy 0.22479 -0.00508) (xy 0.22225 -0.01651) (xy 0.21971 -0.02667)
						(xy 0.20828 -0.05715) (xy 0.19812 -0.07747) (xy 0.19177 -0.08636) (xy 0.18669 -0.09525) (xy 0.17907 -0.10414)
						(xy 0.17272 -0.11303) (xy 0.1651 -0.12065) (xy 0.1651 -0.7366) (xy 0.16256 -0.76835) (xy 0.1524 -0.8001)
						(xy 0.13716 -0.82804) (xy 0.11684 -0.85344) (xy 0.09144 -0.87376) (xy 0.0635 -0.889) (xy 0.03175 -0.89916)
					)
					(width 0)
					(fill yes)
				)
			)
		)
		(pad "49" smd custom
			(at -17.249902 -4.100068)
			(size 0.1143 0.1143)
			(layers "B.Cu" "B.Mask" "B.Paste")
			(net "M_A_DQ18")
			(options
				(clearance outline)
				(anchor circle)
			)
			(primitives
				(gr_poly
					(pts
						(xy 0 -0.9017) (xy -0.03175 -0.89916) (xy -0.0635 -0.889) (xy -0.09144 -0.87376) (xy -0.11684 -0.85344)
						(xy -0.13716 -0.82804) (xy -0.1524 -0.8001) (xy -0.16256 -0.76835) (xy -0.1651 -0.7366) (xy -0.1651 -0.44958)
						(xy -0.17272 -0.44196) (xy -0.19812 -0.4064) (xy -0.2032 -0.39624) (xy -0.20701 -0.38735) (xy -0.21209 -0.37719)
						(xy -0.2159 -0.36703) (xy -0.21844 -0.35687) (xy -0.22225 -0.34544) (xy -0.22352 -0.33528) (xy -0.22606 -0.32512)
						(xy -0.22733 -0.31369) (xy -0.22733 -0.30353) (xy -0.2286 -0.2921) (xy -0.22733 -0.28067) (xy -0.22733 -0.27051)
						(xy -0.22606 -0.25908) (xy -0.22352 -0.24892) (xy -0.22225 -0.23876) (xy -0.21844 -0.22733) (xy -0.2159 -0.21717)
						(xy -0.21209 -0.20701) (xy -0.20701 -0.19685) (xy -0.2032 -0.18796) (xy -0.19812 -0.1778) (xy -0.17272 -0.14224)
						(xy -0.1651 -0.13462) (xy -0.1651 0.7366) (xy -0.16256 0.76835) (xy -0.1524 0.8001) (xy -0.13716 0.82804)
						(xy -0.11684 0.85344) (xy -0.09144 0.87376) (xy -0.0635 0.889) (xy -0.03175 0.89916) (xy 0 0.9017)
						(xy 0.03175 0.89916) (xy 0.0635 0.889) (xy 0.09144 0.87376) (xy 0.11684 0.85344) (xy 0.13716 0.82804)
						(xy 0.1524 0.8001) (xy 0.16256 0.76835) (xy 0.1651 0.7366) (xy 0.1651 -0.13462) (xy 0.17272 -0.14224)
						(xy 0.19812 -0.1778) (xy 0.2032 -0.18796) (xy 0.20701 -0.19685) (xy 0.21209 -0.20701) (xy 0.2159 -0.21717)
						(xy 0.21844 -0.22733) (xy 0.22225 -0.23876) (xy 0.22352 -0.24892) (xy 0.22606 -0.25908) (xy 0.22733 -0.27051)
						(xy 0.22733 -0.28067) (xy 0.2286 -0.2921) (xy 0.22733 -0.30353) (xy 0.22733 -0.31369) (xy 0.22606 -0.32512)
						(xy 0.22352 -0.33528) (xy 0.22225 -0.34544) (xy 0.21844 -0.35687) (xy 0.2159 -0.36703) (xy 0.21209 -0.37719)
						(xy 0.20701 -0.38735) (xy 0.2032 -0.39624) (xy 0.19812 -0.4064) (xy 0.17272 -0.44196) (xy 0.1651 -0.44958)
						(xy 0.1651 -0.7366) (xy 0.16256 -0.76835) (xy 0.1524 -0.8001) (xy 0.13716 -0.82804) (xy 0.11684 -0.85344)
						(xy 0.09144 -0.87376) (xy 0.0635 -0.889) (xy 0.03175 -0.89916)
					)
					(width 0)
					(fill yes)
				)
			)
		)
		(pad "50" smd custom
			(at -16.949928 4.100068)
			(size 0.1143 0.1143)
			(layers "B.Cu" "B.Mask" "B.Paste")
			(net "M_A_DQ23")
			(options
				(clearance outline)
				(anchor circle)
			)
			(primitives
				(gr_poly
					(pts
						(xy 0 -0.9017) (xy -0.03175 -0.89916) (xy -0.0635 -0.889) (xy -0.09144 -0.87376) (xy -0.11684 -0.85344)
						(xy -0.13716 -0.82804) (xy -0.1524 -0.8001) (xy -0.16256 -0.76835) (xy -0.1651 -0.7366) (xy -0.1651 0.13462)
						(xy -0.17272 0.14224) (xy -0.19812 0.1778) (xy -0.2032 0.18796) (xy -0.20701 0.19685) (xy -0.21209 0.20701)
						(xy -0.2159 0.21717) (xy -0.21844 0.22733) (xy -0.22225 0.23876) (xy -0.22352 0.24892) (xy -0.22606 0.25908)
						(xy -0.22733 0.27051) (xy -0.22733 0.28067) (xy -0.2286 0.2921) (xy -0.22733 0.30353) (xy -0.22733 0.31369)
						(xy -0.22606 0.32512) (xy -0.22352 0.33528) (xy -0.22225 0.34544) (xy -0.21844 0.35687) (xy -0.2159 0.36703)
						(xy -0.21209 0.37719) (xy -0.20701 0.38735) (xy -0.2032 0.39624) (xy -0.19812 0.4064) (xy -0.17272 0.44196)
						(xy -0.1651 0.44958) (xy -0.1651 0.7366) (xy -0.16256 0.76835) (xy -0.1524 0.8001) (xy -0.13716 0.82804)
						(xy -0.11684 0.85344) (xy -0.09144 0.87376) (xy -0.0635 0.889) (xy -0.03175 0.89916) (xy 0 0.9017)
						(xy 0.03175 0.89916) (xy 0.0635 0.889) (xy 0.09144 0.87376) (xy 0.11684 0.85344) (xy 0.13716 0.82804)
						(xy 0.1524 0.8001) (xy 0.16256 0.76835) (xy 0.1651 0.7366) (xy 0.1651 0.44958) (xy 0.17272 0.44196)
						(xy 0.19812 0.4064) (xy 0.2032 0.39624) (xy 0.20701 0.38735) (xy 0.21209 0.37719) (xy 0.2159 0.36703)
						(xy 0.21844 0.35687) (xy 0.22225 0.34544) (xy 0.22352 0.33528) (xy 0.22606 0.32512) (xy 0.22733 0.31369)
						(xy 0.22733 0.30353) (xy 0.2286 0.2921) (xy 0.22733 0.28067) (xy 0.22733 0.27051) (xy 0.22606 0.25908)
						(xy 0.22352 0.24892) (xy 0.22225 0.23876) (xy 0.21844 0.22733) (xy 0.2159 0.21717) (xy 0.21209 0.20701)
						(xy 0.20701 0.19685) (xy 0.2032 0.18796) (xy 0.19812 0.1778) (xy 0.17272 0.14224) (xy 0.1651 0.13462)
						(xy 0.1651 -0.7366) (xy 0.16256 -0.76835) (xy 0.1524 -0.8001) (xy 0.13716 -0.82804) (xy 0.11684 -0.85344)
						(xy 0.09144 -0.87376) (xy 0.0635 -0.889) (xy 0.03175 -0.89916)
					)
					(width 0)
					(fill yes)
				)
			)
		)
		(pad "51" smd custom
			(at -16.649954 -4.100068)
			(size 0.1143 0.1143)
			(layers "B.Cu" "B.Mask" "B.Paste")
			(net "M_A_DQ19")
			(options
				(clearance outline)
				(anchor circle)
			)
			(primitives
				(gr_poly
					(pts
						(xy 0 -0.9017) (xy -0.03175 -0.89916) (xy -0.0635 -0.889) (xy -0.09144 -0.87376) (xy -0.11684 -0.85344)
						(xy -0.13716 -0.82804) (xy -0.1524 -0.8001) (xy -0.16256 -0.76835) (xy -0.1651 -0.7366) (xy -0.1651 -0.19685)
						(xy -0.17272 -0.18923) (xy -0.17907 -0.18034) (xy -0.18669 -0.17145) (xy -0.19177 -0.16256) (xy -0.19812 -0.15367)
						(xy -0.20828 -0.13335) (xy -0.21971 -0.10287) (xy -0.22225 -0.09271) (xy -0.22479 -0.08128) (xy -0.22606 -0.07112)
						(xy -0.2286 -0.05969) (xy -0.2286 -0.01651) (xy -0.22606 -0.00508) (xy -0.22479 0.00508) (xy -0.22225 0.01651)
						(xy -0.21971 0.02667) (xy -0.20828 0.05715) (xy -0.19812 0.07747) (xy -0.19177 0.08636) (xy -0.18669 0.09525)
						(xy -0.17907 0.10414) (xy -0.17272 0.11303) (xy -0.1651 0.12065) (xy -0.1651 0.7366) (xy -0.16256 0.76835)
						(xy -0.1524 0.8001) (xy -0.13716 0.82804) (xy -0.11684 0.85344) (xy -0.09144 0.87376) (xy -0.0635 0.889)
						(xy -0.03175 0.89916) (xy 0 0.9017) (xy 0.03175 0.89916) (xy 0.0635 0.889) (xy 0.09144 0.87376)
						(xy 0.11684 0.85344) (xy 0.13716 0.82804) (xy 0.1524 0.8001) (xy 0.16256 0.76835) (xy 0.1651 0.7366)
						(xy 0.1651 0.11938) (xy 0.17272 0.11176) (xy 0.19812 0.0762) (xy 0.2032 0.06604) (xy 0.20701 0.05715)
						(xy 0.21209 0.04699) (xy 0.2159 0.03683) (xy 0.21844 0.02667) (xy 0.22225 0.01524) (xy 0.22352 0.00508)
						(xy 0.22606 -0.00508) (xy 0.22733 -0.01651) (xy 0.22733 -0.02667) (xy 0.2286 -0.0381) (xy 0.22733 -0.04953)
						(xy 0.22733 -0.05969) (xy 0.22606 -0.07112) (xy 0.22352 -0.08128) (xy 0.22225 -0.09144) (xy 0.21844 -0.10287)
						(xy 0.2159 -0.11303) (xy 0.21209 -0.12319) (xy 0.20701 -0.13335) (xy 0.2032 -0.14224) (xy 0.19812 -0.1524)
						(xy 0.17272 -0.18796) (xy 0.1651 -0.19558) (xy 0.1651 -0.7366) (xy 0.16256 -0.76835) (xy 0.1524 -0.8001)
						(xy 0.13716 -0.82804) (xy 0.11684 -0.85344) (xy 0.09144 -0.87376) (xy 0.0635 -0.889) (xy 0.03175 -0.89916)
					)
					(width 0)
					(fill yes)
				)
			)
		)
		(pad "52" smd custom
			(at -16.34998 4.100068)
			(size 0.1143 0.1143)
			(layers "B.Cu" "B.Mask" "B.Paste")
			(net "GND")
			(options
				(clearance outline)
				(anchor circle)
			)
			(primitives
				(gr_poly
					(pts
						(xy 0 -0.9017) (xy -0.03175 -0.89916) (xy -0.0635 -0.889) (xy -0.09144 -0.87376) (xy -0.11684 -0.85344)
						(xy -0.13716 -0.82804) (xy -0.1524 -0.8001) (xy -0.16256 -0.76835) (xy -0.1651 -0.7366) (xy -0.1651 -0.11938)
						(xy -0.17272 -0.11176) (xy -0.19812 -0.0762) (xy -0.2032 -0.06604) (xy -0.20701 -0.05715) (xy -0.21209 -0.04699)
						(xy -0.2159 -0.03683) (xy -0.21844 -0.02667) (xy -0.22225 -0.01524) (xy -0.22352 -0.00508) (xy -0.22606 0.00508)
						(xy -0.22733 0.01651) (xy -0.22733 0.02667) (xy -0.2286 0.0381) (xy -0.22733 0.04953) (xy -0.22733 0.05969)
						(xy -0.22606 0.07112) (xy -0.22352 0.08128) (xy -0.22225 0.09144) (xy -0.21844 0.10287) (xy -0.2159 0.11303)
						(xy -0.21209 0.12319) (xy -0.20701 0.13335) (xy -0.2032 0.14224) (xy -0.19812 0.1524) (xy -0.17272 0.18796)
						(xy -0.1651 0.19558) (xy -0.1651 0.7366) (xy -0.16256 0.76835) (xy -0.1524 0.8001) (xy -0.13716 0.82804)
						(xy -0.11684 0.85344) (xy -0.09144 0.87376) (xy -0.0635 0.889) (xy -0.03175 0.89916) (xy 0 0.9017)
						(xy 0.03175 0.89916) (xy 0.0635 0.889) (xy 0.09144 0.87376) (xy 0.11684 0.85344) (xy 0.13716 0.82804)
						(xy 0.1524 0.8001) (xy 0.16256 0.76835) (xy 0.1651 0.7366) (xy 0.1651 0.19685) (xy 0.17272 0.18923)
						(xy 0.17907 0.18034) (xy 0.18669 0.17145) (xy 0.19177 0.16256) (xy 0.19812 0.15367) (xy 0.20828 0.13335)
						(xy 0.21971 0.10287) (xy 0.22225 0.09271) (xy 0.22479 0.08128) (xy 0.22606 0.07112) (xy 0.2286 0.05969)
						(xy 0.2286 0.01651) (xy 0.22606 0.00508) (xy 0.22479 -0.00508) (xy 0.22225 -0.01651) (xy 0.21971 -0.02667)
						(xy 0.20828 -0.05715) (xy 0.19812 -0.07747) (xy 0.19177 -0.08636) (xy 0.18669 -0.09525) (xy 0.17907 -0.10414)
						(xy 0.17272 -0.11303) (xy 0.1651 -0.12065) (xy 0.1651 -0.7366) (xy 0.16256 -0.76835) (xy 0.1524 -0.8001)
						(xy 0.13716 -0.82804) (xy 0.11684 -0.85344) (xy 0.09144 -0.87376) (xy 0.0635 -0.889) (xy 0.03175 -0.89916)
					)
					(width 0)
					(fill yes)
				)
			)
		)
		(pad "53" smd custom
			(at -16.050006 -4.100068)
			(size 0.1143 0.1143)
			(layers "B.Cu" "B.Mask" "B.Paste")
			(net "GND")
			(options
				(clearance outline)
				(anchor circle)
			)
			(primitives
				(gr_poly
					(pts
						(xy 0 -0.9017) (xy -0.03175 -0.89916) (xy -0.0635 -0.889) (xy -0.09144 -0.87376) (xy -0.11684 -0.85344)
						(xy -0.13716 -0.82804) (xy -0.1524 -0.8001) (xy -0.16256 -0.76835) (xy -0.1651 -0.7366) (xy -0.1651 -0.44958)
						(xy -0.17272 -0.44196) (xy -0.19812 -0.4064) (xy -0.2032 -0.39624) (xy -0.20701 -0.38735) (xy -0.21209 -0.37719)
						(xy -0.2159 -0.36703) (xy -0.21844 -0.35687) (xy -0.22225 -0.34544) (xy -0.22352 -0.33528) (xy -0.22606 -0.32512)
						(xy -0.22733 -0.31369) (xy -0.22733 -0.30353) (xy -0.2286 -0.2921) (xy -0.22733 -0.28067) (xy -0.22733 -0.27051)
						(xy -0.22606 -0.25908) (xy -0.22352 -0.24892) (xy -0.22225 -0.23876) (xy -0.21844 -0.22733) (xy -0.2159 -0.21717)
						(xy -0.21209 -0.20701) (xy -0.20701 -0.19685) (xy -0.2032 -0.18796) (xy -0.19812 -0.1778) (xy -0.17272 -0.14224)
						(xy -0.1651 -0.13462) (xy -0.1651 0.7366) (xy -0.16256 0.76835) (xy -0.1524 0.8001) (xy -0.13716 0.82804)
						(xy -0.11684 0.85344) (xy -0.09144 0.87376) (xy -0.0635 0.889) (xy -0.03175 0.89916) (xy 0 0.9017)
						(xy 0.03175 0.89916) (xy 0.0635 0.889) (xy 0.09144 0.87376) (xy 0.11684 0.85344) (xy 0.13716 0.82804)
						(xy 0.1524 0.8001) (xy 0.16256 0.76835) (xy 0.1651 0.7366) (xy 0.1651 -0.13462) (xy 0.17272 -0.14224)
						(xy 0.19812 -0.1778) (xy 0.2032 -0.18796) (xy 0.20701 -0.19685) (xy 0.21209 -0.20701) (xy 0.2159 -0.21717)
						(xy 0.21844 -0.22733) (xy 0.22225 -0.23876) (xy 0.22352 -0.24892) (xy 0.22606 -0.25908) (xy 0.22733 -0.27051)
						(xy 0.22733 -0.28067) (xy 0.2286 -0.2921) (xy 0.22733 -0.30353) (xy 0.22733 -0.31369) (xy 0.22606 -0.32512)
						(xy 0.22352 -0.33528) (xy 0.22225 -0.34544) (xy 0.21844 -0.35687) (xy 0.2159 -0.36703) (xy 0.21209 -0.37719)
						(xy 0.20701 -0.38735) (xy 0.2032 -0.39624) (xy 0.19812 -0.4064) (xy 0.17272 -0.44196) (xy 0.1651 -0.44958)
						(xy 0.1651 -0.7366) (xy 0.16256 -0.76835) (xy 0.1524 -0.8001) (xy 0.13716 -0.82804) (xy 0.11684 -0.85344)
						(xy 0.09144 -0.87376) (xy 0.0635 -0.889) (xy 0.03175 -0.89916)
					)
					(width 0)
					(fill yes)
				)
			)
		)
		(pad "54" smd custom
			(at -15.750032 4.100068)
			(size 0.1143 0.1143)
			(layers "B.Cu" "B.Mask" "B.Paste")
			(net "M_A_DQ28")
			(options
				(clearance outline)
				(anchor circle)
			)
			(primitives
				(gr_poly
					(pts
						(xy 0 -0.9017) (xy -0.03175 -0.89916) (xy -0.0635 -0.889) (xy -0.09144 -0.87376) (xy -0.11684 -0.85344)
						(xy -0.13716 -0.82804) (xy -0.1524 -0.8001) (xy -0.16256 -0.76835) (xy -0.1651 -0.7366) (xy -0.1651 0.13462)
						(xy -0.17272 0.14224) (xy -0.19812 0.1778) (xy -0.2032 0.18796) (xy -0.20701 0.19685) (xy -0.21209 0.20701)
						(xy -0.2159 0.21717) (xy -0.21844 0.22733) (xy -0.22225 0.23876) (xy -0.22352 0.24892) (xy -0.22606 0.25908)
						(xy -0.22733 0.27051) (xy -0.22733 0.28067) (xy -0.2286 0.2921) (xy -0.22733 0.30353) (xy -0.22733 0.31369)
						(xy -0.22606 0.32512) (xy -0.22352 0.33528) (xy -0.22225 0.34544) (xy -0.21844 0.35687) (xy -0.2159 0.36703)
						(xy -0.21209 0.37719) (xy -0.20701 0.38735) (xy -0.2032 0.39624) (xy -0.19812 0.4064) (xy -0.17272 0.44196)
						(xy -0.1651 0.44958) (xy -0.1651 0.7366) (xy -0.16256 0.76835) (xy -0.1524 0.8001) (xy -0.13716 0.82804)
						(xy -0.11684 0.85344) (xy -0.09144 0.87376) (xy -0.0635 0.889) (xy -0.03175 0.89916) (xy 0 0.9017)
						(xy 0.03175 0.89916) (xy 0.0635 0.889) (xy 0.09144 0.87376) (xy 0.11684 0.85344) (xy 0.13716 0.82804)
						(xy 0.1524 0.8001) (xy 0.16256 0.76835) (xy 0.1651 0.7366) (xy 0.1651 0.44958) (xy 0.17272 0.44196)
						(xy 0.19812 0.4064) (xy 0.2032 0.39624) (xy 0.20701 0.38735) (xy 0.21209 0.37719) (xy 0.2159 0.36703)
						(xy 0.21844 0.35687) (xy 0.22225 0.34544) (xy 0.22352 0.33528) (xy 0.22606 0.32512) (xy 0.22733 0.31369)
						(xy 0.22733 0.30353) (xy 0.2286 0.2921) (xy 0.22733 0.28067) (xy 0.22733 0.27051) (xy 0.22606 0.25908)
						(xy 0.22352 0.24892) (xy 0.22225 0.23876) (xy 0.21844 0.22733) (xy 0.2159 0.21717) (xy 0.21209 0.20701)
						(xy 0.20701 0.19685) (xy 0.2032 0.18796) (xy 0.19812 0.1778) (xy 0.17272 0.14224) (xy 0.1651 0.13462)
						(xy 0.1651 -0.7366) (xy 0.16256 -0.76835) (xy 0.1524 -0.8001) (xy 0.13716 -0.82804) (xy 0.11684 -0.85344)
						(xy 0.09144 -0.87376) (xy 0.0635 -0.889) (xy 0.03175 -0.89916)
					)
					(width 0)
					(fill yes)
				)
			)
		)
		(pad "55" smd custom
			(at -15.450058 -4.100068)
			(size 0.1143 0.1143)
			(layers "B.Cu" "B.Mask" "B.Paste")
			(net "M_A_DQ24")
			(options
				(clearance outline)
				(anchor circle)
			)
			(primitives
				(gr_poly
					(pts
						(xy 0 -0.9017) (xy -0.03175 -0.89916) (xy -0.0635 -0.889) (xy -0.09144 -0.87376) (xy -0.11684 -0.85344)
						(xy -0.13716 -0.82804) (xy -0.1524 -0.8001) (xy -0.16256 -0.76835) (xy -0.1651 -0.7366) (xy -0.1651 -0.19685)
						(xy -0.17272 -0.18923) (xy -0.17907 -0.18034) (xy -0.18669 -0.17145) (xy -0.19177 -0.16256) (xy -0.19812 -0.15367)
						(xy -0.20828 -0.13335) (xy -0.21971 -0.10287) (xy -0.22225 -0.09271) (xy -0.22479 -0.08128) (xy -0.22606 -0.07112)
						(xy -0.2286 -0.05969) (xy -0.2286 -0.01651) (xy -0.22606 -0.00508) (xy -0.22479 0.00508) (xy -0.22225 0.01651)
						(xy -0.21971 0.02667) (xy -0.20828 0.05715) (xy -0.19812 0.07747) (xy -0.19177 0.08636) (xy -0.18669 0.09525)
						(xy -0.17907 0.10414) (xy -0.17272 0.11303) (xy -0.1651 0.12065) (xy -0.1651 0.7366) (xy -0.16256 0.76835)
						(xy -0.1524 0.8001) (xy -0.13716 0.82804) (xy -0.11684 0.85344) (xy -0.09144 0.87376) (xy -0.0635 0.889)
						(xy -0.03175 0.89916) (xy 0 0.9017) (xy 0.03175 0.89916) (xy 0.0635 0.889) (xy 0.09144 0.87376)
						(xy 0.11684 0.85344) (xy 0.13716 0.82804) (xy 0.1524 0.8001) (xy 0.16256 0.76835) (xy 0.1651 0.7366)
						(xy 0.1651 0.11938) (xy 0.17272 0.11176) (xy 0.19812 0.0762) (xy 0.2032 0.06604) (xy 0.20701 0.05715)
						(xy 0.21209 0.04699) (xy 0.2159 0.03683) (xy 0.21844 0.02667) (xy 0.22225 0.01524) (xy 0.22352 0.00508)
						(xy 0.22606 -0.00508) (xy 0.22733 -0.01651) (xy 0.22733 -0.02667) (xy 0.2286 -0.0381) (xy 0.22733 -0.04953)
						(xy 0.22733 -0.05969) (xy 0.22606 -0.07112) (xy 0.22352 -0.08128) (xy 0.22225 -0.09144) (xy 0.21844 -0.10287)
						(xy 0.2159 -0.11303) (xy 0.21209 -0.12319) (xy 0.20701 -0.13335) (xy 0.2032 -0.14224) (xy 0.19812 -0.1524)
						(xy 0.17272 -0.18796) (xy 0.1651 -0.19558) (xy 0.1651 -0.7366) (xy 0.16256 -0.76835) (xy 0.1524 -0.8001)
						(xy 0.13716 -0.82804) (xy 0.11684 -0.85344) (xy 0.09144 -0.87376) (xy 0.0635 -0.889) (xy 0.03175 -0.89916)
					)
					(width 0)
					(fill yes)
				)
			)
		)
		(pad "56" smd custom
			(at -15.150084 4.100068)
			(size 0.1143 0.1143)
			(layers "B.Cu" "B.Mask" "B.Paste")
			(net "M_A_DQ29")
			(options
				(clearance outline)
				(anchor circle)
			)
			(primitives
				(gr_poly
					(pts
						(xy 0 -0.9017) (xy -0.03175 -0.89916) (xy -0.0635 -0.889) (xy -0.09144 -0.87376) (xy -0.11684 -0.85344)
						(xy -0.13716 -0.82804) (xy -0.1524 -0.8001) (xy -0.16256 -0.76835) (xy -0.1651 -0.7366) (xy -0.1651 -0.11938)
						(xy -0.17272 -0.11176) (xy -0.19812 -0.0762) (xy -0.2032 -0.06604) (xy -0.20701 -0.05715) (xy -0.21209 -0.04699)
						(xy -0.2159 -0.03683) (xy -0.21844 -0.02667) (xy -0.22225 -0.01524) (xy -0.22352 -0.00508) (xy -0.22606 0.00508)
						(xy -0.22733 0.01651) (xy -0.22733 0.02667) (xy -0.2286 0.0381) (xy -0.22733 0.04953) (xy -0.22733 0.05969)
						(xy -0.22606 0.07112) (xy -0.22352 0.08128) (xy -0.22225 0.09144) (xy -0.21844 0.10287) (xy -0.2159 0.11303)
						(xy -0.21209 0.12319) (xy -0.20701 0.13335) (xy -0.2032 0.14224) (xy -0.19812 0.1524) (xy -0.17272 0.18796)
						(xy -0.1651 0.19558) (xy -0.1651 0.7366) (xy -0.16256 0.76835) (xy -0.1524 0.8001) (xy -0.13716 0.82804)
						(xy -0.11684 0.85344) (xy -0.09144 0.87376) (xy -0.0635 0.889) (xy -0.03175 0.89916) (xy 0 0.9017)
						(xy 0.03175 0.89916) (xy 0.0635 0.889) (xy 0.09144 0.87376) (xy 0.11684 0.85344) (xy 0.13716 0.82804)
						(xy 0.1524 0.8001) (xy 0.16256 0.76835) (xy 0.1651 0.7366) (xy 0.1651 0.19685) (xy 0.17272 0.18923)
						(xy 0.17907 0.18034) (xy 0.18669 0.17145) (xy 0.19177 0.16256) (xy 0.19812 0.15367) (xy 0.20828 0.13335)
						(xy 0.21971 0.10287) (xy 0.22225 0.09271) (xy 0.22479 0.08128) (xy 0.22606 0.07112) (xy 0.2286 0.05969)
						(xy 0.2286 0.01651) (xy 0.22606 0.00508) (xy 0.22479 -0.00508) (xy 0.22225 -0.01651) (xy 0.21971 -0.02667)
						(xy 0.20828 -0.05715) (xy 0.19812 -0.07747) (xy 0.19177 -0.08636) (xy 0.18669 -0.09525) (xy 0.17907 -0.10414)
						(xy 0.17272 -0.11303) (xy 0.1651 -0.12065) (xy 0.1651 -0.7366) (xy 0.16256 -0.76835) (xy 0.1524 -0.8001)
						(xy 0.13716 -0.82804) (xy 0.11684 -0.85344) (xy 0.09144 -0.87376) (xy 0.0635 -0.889) (xy 0.03175 -0.89916)
					)
					(width 0)
					(fill yes)
				)
			)
		)
		(pad "57" smd custom
			(at -14.85011 -4.100068)
			(size 0.1143 0.1143)
			(layers "B.Cu" "B.Mask" "B.Paste")
			(net "M_A_DQ25")
			(options
				(clearance outline)
				(anchor circle)
			)
			(primitives
				(gr_poly
					(pts
						(xy 0 -0.9017) (xy -0.03175 -0.89916) (xy -0.0635 -0.889) (xy -0.09144 -0.87376) (xy -0.11684 -0.85344)
						(xy -0.13716 -0.82804) (xy -0.1524 -0.8001) (xy -0.16256 -0.76835) (xy -0.1651 -0.7366) (xy -0.1651 -0.44958)
						(xy -0.17272 -0.44196) (xy -0.19812 -0.4064) (xy -0.2032 -0.39624) (xy -0.20701 -0.38735) (xy -0.21209 -0.37719)
						(xy -0.2159 -0.36703) (xy -0.21844 -0.35687) (xy -0.22225 -0.34544) (xy -0.22352 -0.33528) (xy -0.22606 -0.32512)
						(xy -0.22733 -0.31369) (xy -0.22733 -0.30353) (xy -0.2286 -0.2921) (xy -0.22733 -0.28067) (xy -0.22733 -0.27051)
						(xy -0.22606 -0.25908) (xy -0.22352 -0.24892) (xy -0.22225 -0.23876) (xy -0.21844 -0.22733) (xy -0.2159 -0.21717)
						(xy -0.21209 -0.20701) (xy -0.20701 -0.19685) (xy -0.2032 -0.18796) (xy -0.19812 -0.1778) (xy -0.17272 -0.14224)
						(xy -0.1651 -0.13462) (xy -0.1651 0.7366) (xy -0.16256 0.76835) (xy -0.1524 0.8001) (xy -0.13716 0.82804)
						(xy -0.11684 0.85344) (xy -0.09144 0.87376) (xy -0.0635 0.889) (xy -0.03175 0.89916) (xy 0 0.9017)
						(xy 0.03175 0.89916) (xy 0.0635 0.889) (xy 0.09144 0.87376) (xy 0.11684 0.85344) (xy 0.13716 0.82804)
						(xy 0.1524 0.8001) (xy 0.16256 0.76835) (xy 0.1651 0.7366) (xy 0.1651 -0.13462) (xy 0.17272 -0.14224)
						(xy 0.19812 -0.1778) (xy 0.2032 -0.18796) (xy 0.20701 -0.19685) (xy 0.21209 -0.20701) (xy 0.2159 -0.21717)
						(xy 0.21844 -0.22733) (xy 0.22225 -0.23876) (xy 0.22352 -0.24892) (xy 0.22606 -0.25908) (xy 0.22733 -0.27051)
						(xy 0.22733 -0.28067) (xy 0.2286 -0.2921) (xy 0.22733 -0.30353) (xy 0.22733 -0.31369) (xy 0.22606 -0.32512)
						(xy 0.22352 -0.33528) (xy 0.22225 -0.34544) (xy 0.21844 -0.35687) (xy 0.2159 -0.36703) (xy 0.21209 -0.37719)
						(xy 0.20701 -0.38735) (xy 0.2032 -0.39624) (xy 0.19812 -0.4064) (xy 0.17272 -0.44196) (xy 0.1651 -0.44958)
						(xy 0.1651 -0.7366) (xy 0.16256 -0.76835) (xy 0.1524 -0.8001) (xy 0.13716 -0.82804) (xy 0.11684 -0.85344)
						(xy 0.09144 -0.87376) (xy 0.0635 -0.889) (xy 0.03175 -0.89916)
					)
					(width 0)
					(fill yes)
				)
			)
		)
		(pad "58" smd custom
			(at -14.549882 4.100068)
			(size 0.1143 0.1143)
			(layers "B.Cu" "B.Mask" "B.Paste")
			(net "GND")
			(options
				(clearance outline)
				(anchor circle)
			)
			(primitives
				(gr_poly
					(pts
						(xy 0 -0.9017) (xy -0.03175 -0.89916) (xy -0.0635 -0.889) (xy -0.09144 -0.87376) (xy -0.11684 -0.85344)
						(xy -0.13716 -0.82804) (xy -0.1524 -0.8001) (xy -0.16256 -0.76835) (xy -0.1651 -0.7366) (xy -0.1651 0.13462)
						(xy -0.17272 0.14224) (xy -0.19812 0.1778) (xy -0.2032 0.18796) (xy -0.20701 0.19685) (xy -0.21209 0.20701)
						(xy -0.2159 0.21717) (xy -0.21844 0.22733) (xy -0.22225 0.23876) (xy -0.22352 0.24892) (xy -0.22606 0.25908)
						(xy -0.22733 0.27051) (xy -0.22733 0.28067) (xy -0.2286 0.2921) (xy -0.22733 0.30353) (xy -0.22733 0.31369)
						(xy -0.22606 0.32512) (xy -0.22352 0.33528) (xy -0.22225 0.34544) (xy -0.21844 0.35687) (xy -0.2159 0.36703)
						(xy -0.21209 0.37719) (xy -0.20701 0.38735) (xy -0.2032 0.39624) (xy -0.19812 0.4064) (xy -0.17272 0.44196)
						(xy -0.1651 0.44958) (xy -0.1651 0.7366) (xy -0.16256 0.76835) (xy -0.1524 0.8001) (xy -0.13716 0.82804)
						(xy -0.11684 0.85344) (xy -0.09144 0.87376) (xy -0.0635 0.889) (xy -0.03175 0.89916) (xy 0 0.9017)
						(xy 0.03175 0.89916) (xy 0.0635 0.889) (xy 0.09144 0.87376) (xy 0.11684 0.85344) (xy 0.13716 0.82804)
						(xy 0.1524 0.8001) (xy 0.16256 0.76835) (xy 0.1651 0.7366) (xy 0.1651 0.44958) (xy 0.17272 0.44196)
						(xy 0.19812 0.4064) (xy 0.2032 0.39624) (xy 0.20701 0.38735) (xy 0.21209 0.37719) (xy 0.2159 0.36703)
						(xy 0.21844 0.35687) (xy 0.22225 0.34544) (xy 0.22352 0.33528) (xy 0.22606 0.32512) (xy 0.22733 0.31369)
						(xy 0.22733 0.30353) (xy 0.2286 0.2921) (xy 0.22733 0.28067) (xy 0.22733 0.27051) (xy 0.22606 0.25908)
						(xy 0.22352 0.24892) (xy 0.22225 0.23876) (xy 0.21844 0.22733) (xy 0.2159 0.21717) (xy 0.21209 0.20701)
						(xy 0.20701 0.19685) (xy 0.2032 0.18796) (xy 0.19812 0.1778) (xy 0.17272 0.14224) (xy 0.1651 0.13462)
						(xy 0.1651 -0.7366) (xy 0.16256 -0.76835) (xy 0.1524 -0.8001) (xy 0.13716 -0.82804) (xy 0.11684 -0.85344)
						(xy 0.09144 -0.87376) (xy 0.0635 -0.889) (xy 0.03175 -0.89916)
					)
					(width 0)
					(fill yes)
				)
			)
		)
		(pad "59" smd custom
			(at -14.249908 -4.100068)
			(size 0.1143 0.1143)
			(layers "B.Cu" "B.Mask" "B.Paste")
			(net "GND")
			(options
				(clearance outline)
				(anchor circle)
			)
			(primitives
				(gr_poly
					(pts
						(xy 0 -0.9017) (xy -0.03175 -0.89916) (xy -0.0635 -0.889) (xy -0.09144 -0.87376) (xy -0.11684 -0.85344)
						(xy -0.13716 -0.82804) (xy -0.1524 -0.8001) (xy -0.16256 -0.76835) (xy -0.1651 -0.7366) (xy -0.1651 -0.19685)
						(xy -0.17272 -0.18923) (xy -0.17907 -0.18034) (xy -0.18669 -0.17145) (xy -0.19177 -0.16256) (xy -0.19812 -0.15367)
						(xy -0.20828 -0.13335) (xy -0.21971 -0.10287) (xy -0.22225 -0.09271) (xy -0.22479 -0.08128) (xy -0.22606 -0.07112)
						(xy -0.2286 -0.05969) (xy -0.2286 -0.01651) (xy -0.22606 -0.00508) (xy -0.22479 0.00508) (xy -0.22225 0.01651)
						(xy -0.21971 0.02667) (xy -0.20828 0.05715) (xy -0.19812 0.07747) (xy -0.19177 0.08636) (xy -0.18669 0.09525)
						(xy -0.17907 0.10414) (xy -0.17272 0.11303) (xy -0.1651 0.12065) (xy -0.1651 0.7366) (xy -0.16256 0.76835)
						(xy -0.1524 0.8001) (xy -0.13716 0.82804) (xy -0.11684 0.85344) (xy -0.09144 0.87376) (xy -0.0635 0.889)
						(xy -0.03175 0.89916) (xy 0 0.9017) (xy 0.03175 0.89916) (xy 0.0635 0.889) (xy 0.09144 0.87376)
						(xy 0.11684 0.85344) (xy 0.13716 0.82804) (xy 0.1524 0.8001) (xy 0.16256 0.76835) (xy 0.1651 0.7366)
						(xy 0.1651 0.11938) (xy 0.17272 0.11176) (xy 0.19812 0.0762) (xy 0.2032 0.06604) (xy 0.20701 0.05715)
						(xy 0.21209 0.04699) (xy 0.2159 0.03683) (xy 0.21844 0.02667) (xy 0.22225 0.01524) (xy 0.22352 0.00508)
						(xy 0.22606 -0.00508) (xy 0.22733 -0.01651) (xy 0.22733 -0.02667) (xy 0.2286 -0.0381) (xy 0.22733 -0.04953)
						(xy 0.22733 -0.05969) (xy 0.22606 -0.07112) (xy 0.22352 -0.08128) (xy 0.22225 -0.09144) (xy 0.21844 -0.10287)
						(xy 0.2159 -0.11303) (xy 0.21209 -0.12319) (xy 0.20701 -0.13335) (xy 0.2032 -0.14224) (xy 0.19812 -0.1524)
						(xy 0.17272 -0.18796) (xy 0.1651 -0.19558) (xy 0.1651 -0.7366) (xy 0.16256 -0.76835) (xy 0.1524 -0.8001)
						(xy 0.13716 -0.82804) (xy 0.11684 -0.85344) (xy 0.09144 -0.87376) (xy 0.0635 -0.889) (xy 0.03175 -0.89916)
					)
					(width 0)
					(fill yes)
				)
			)
		)
		(pad "60" smd custom
			(at -13.949934 4.100068)
			(size 0.1143 0.1143)
			(layers "B.Cu" "B.Mask" "B.Paste")
			(net "M_A_DQS_DN3")
			(options
				(clearance outline)
				(anchor circle)
			)
			(primitives
				(gr_poly
					(pts
						(xy 0 -0.9017) (xy -0.03175 -0.89916) (xy -0.0635 -0.889) (xy -0.09144 -0.87376) (xy -0.11684 -0.85344)
						(xy -0.13716 -0.82804) (xy -0.1524 -0.8001) (xy -0.16256 -0.76835) (xy -0.1651 -0.7366) (xy -0.1651 -0.11938)
						(xy -0.17272 -0.11176) (xy -0.19812 -0.0762) (xy -0.2032 -0.06604) (xy -0.20701 -0.05715) (xy -0.21209 -0.04699)
						(xy -0.2159 -0.03683) (xy -0.21844 -0.02667) (xy -0.22225 -0.01524) (xy -0.22352 -0.00508) (xy -0.22606 0.00508)
						(xy -0.22733 0.01651) (xy -0.22733 0.02667) (xy -0.2286 0.0381) (xy -0.22733 0.04953) (xy -0.22733 0.05969)
						(xy -0.22606 0.07112) (xy -0.22352 0.08128) (xy -0.22225 0.09144) (xy -0.21844 0.10287) (xy -0.2159 0.11303)
						(xy -0.21209 0.12319) (xy -0.20701 0.13335) (xy -0.2032 0.14224) (xy -0.19812 0.1524) (xy -0.17272 0.18796)
						(xy -0.1651 0.19558) (xy -0.1651 0.7366) (xy -0.16256 0.76835) (xy -0.1524 0.8001) (xy -0.13716 0.82804)
						(xy -0.11684 0.85344) (xy -0.09144 0.87376) (xy -0.0635 0.889) (xy -0.03175 0.89916) (xy 0 0.9017)
						(xy 0.03175 0.89916) (xy 0.0635 0.889) (xy 0.09144 0.87376) (xy 0.11684 0.85344) (xy 0.13716 0.82804)
						(xy 0.1524 0.8001) (xy 0.16256 0.76835) (xy 0.1651 0.7366) (xy 0.1651 0.19685) (xy 0.17272 0.18923)
						(xy 0.17907 0.18034) (xy 0.18669 0.17145) (xy 0.19177 0.16256) (xy 0.19812 0.15367) (xy 0.20828 0.13335)
						(xy 0.21971 0.10287) (xy 0.22225 0.09271) (xy 0.22479 0.08128) (xy 0.22606 0.07112) (xy 0.2286 0.05969)
						(xy 0.2286 0.01651) (xy 0.22606 0.00508) (xy 0.22479 -0.00508) (xy 0.22225 -0.01651) (xy 0.21971 -0.02667)
						(xy 0.20828 -0.05715) (xy 0.19812 -0.07747) (xy 0.19177 -0.08636) (xy 0.18669 -0.09525) (xy 0.17907 -0.10414)
						(xy 0.17272 -0.11303) (xy 0.1651 -0.12065) (xy 0.1651 -0.7366) (xy 0.16256 -0.76835) (xy 0.1524 -0.8001)
						(xy 0.13716 -0.82804) (xy 0.11684 -0.85344) (xy 0.09144 -0.87376) (xy 0.0635 -0.889) (xy 0.03175 -0.89916)
					)
					(width 0)
					(fill yes)
				)
			)
		)
		(pad "61" smd custom
			(at -13.64996 -4.100068)
			(size 0.1143 0.1143)
			(layers "B.Cu" "B.Mask" "B.Paste")
			(net "GND")
			(options
				(clearance outline)
				(anchor circle)
			)
			(primitives
				(gr_poly
					(pts
						(xy 0 -0.9017) (xy -0.03175 -0.89916) (xy -0.0635 -0.889) (xy -0.09144 -0.87376) (xy -0.11684 -0.85344)
						(xy -0.13716 -0.82804) (xy -0.1524 -0.8001) (xy -0.16256 -0.76835) (xy -0.1651 -0.7366) (xy -0.1651 -0.44958)
						(xy -0.17272 -0.44196) (xy -0.19812 -0.4064) (xy -0.2032 -0.39624) (xy -0.20701 -0.38735) (xy -0.21209 -0.37719)
						(xy -0.2159 -0.36703) (xy -0.21844 -0.35687) (xy -0.22225 -0.34544) (xy -0.22352 -0.33528) (xy -0.22606 -0.32512)
						(xy -0.22733 -0.31369) (xy -0.22733 -0.30353) (xy -0.2286 -0.2921) (xy -0.22733 -0.28067) (xy -0.22733 -0.27051)
						(xy -0.22606 -0.25908) (xy -0.22352 -0.24892) (xy -0.22225 -0.23876) (xy -0.21844 -0.22733) (xy -0.2159 -0.21717)
						(xy -0.21209 -0.20701) (xy -0.20701 -0.19685) (xy -0.2032 -0.18796) (xy -0.19812 -0.1778) (xy -0.17272 -0.14224)
						(xy -0.1651 -0.13462) (xy -0.1651 0.7366) (xy -0.16256 0.76835) (xy -0.1524 0.8001) (xy -0.13716 0.82804)
						(xy -0.11684 0.85344) (xy -0.09144 0.87376) (xy -0.0635 0.889) (xy -0.03175 0.89916) (xy 0 0.9017)
						(xy 0.03175 0.89916) (xy 0.0635 0.889) (xy 0.09144 0.87376) (xy 0.11684 0.85344) (xy 0.13716 0.82804)
						(xy 0.1524 0.8001) (xy 0.16256 0.76835) (xy 0.1651 0.7366) (xy 0.1651 -0.13462) (xy 0.17272 -0.14224)
						(xy 0.19812 -0.1778) (xy 0.2032 -0.18796) (xy 0.20701 -0.19685) (xy 0.21209 -0.20701) (xy 0.2159 -0.21717)
						(xy 0.21844 -0.22733) (xy 0.22225 -0.23876) (xy 0.22352 -0.24892) (xy 0.22606 -0.25908) (xy 0.22733 -0.27051)
						(xy 0.22733 -0.28067) (xy 0.2286 -0.2921) (xy 0.22733 -0.30353) (xy 0.22733 -0.31369) (xy 0.22606 -0.32512)
						(xy 0.22352 -0.33528) (xy 0.22225 -0.34544) (xy 0.21844 -0.35687) (xy 0.2159 -0.36703) (xy 0.21209 -0.37719)
						(xy 0.20701 -0.38735) (xy 0.2032 -0.39624) (xy 0.19812 -0.4064) (xy 0.17272 -0.44196) (xy 0.1651 -0.44958)
						(xy 0.1651 -0.7366) (xy 0.16256 -0.76835) (xy 0.1524 -0.8001) (xy 0.13716 -0.82804) (xy 0.11684 -0.85344)
						(xy 0.09144 -0.87376) (xy 0.0635 -0.889) (xy 0.03175 -0.89916)
					)
					(width 0)
					(fill yes)
				)
			)
		)
		(pad "62" smd custom
			(at -13.349986 4.100068)
			(size 0.1143 0.1143)
			(layers "B.Cu" "B.Mask" "B.Paste")
			(net "M_A_DQS_DP3")
			(options
				(clearance outline)
				(anchor circle)
			)
			(primitives
				(gr_poly
					(pts
						(xy 0 -0.9017) (xy -0.03175 -0.89916) (xy -0.0635 -0.889) (xy -0.09144 -0.87376) (xy -0.11684 -0.85344)
						(xy -0.13716 -0.82804) (xy -0.1524 -0.8001) (xy -0.16256 -0.76835) (xy -0.1651 -0.7366) (xy -0.1651 0.13462)
						(xy -0.17272 0.14224) (xy -0.19812 0.1778) (xy -0.2032 0.18796) (xy -0.20701 0.19685) (xy -0.21209 0.20701)
						(xy -0.2159 0.21717) (xy -0.21844 0.22733) (xy -0.22225 0.23876) (xy -0.22352 0.24892) (xy -0.22606 0.25908)
						(xy -0.22733 0.27051) (xy -0.22733 0.28067) (xy -0.2286 0.2921) (xy -0.22733 0.30353) (xy -0.22733 0.31369)
						(xy -0.22606 0.32512) (xy -0.22352 0.33528) (xy -0.22225 0.34544) (xy -0.21844 0.35687) (xy -0.2159 0.36703)
						(xy -0.21209 0.37719) (xy -0.20701 0.38735) (xy -0.2032 0.39624) (xy -0.19812 0.4064) (xy -0.17272 0.44196)
						(xy -0.1651 0.44958) (xy -0.1651 0.7366) (xy -0.16256 0.76835) (xy -0.1524 0.8001) (xy -0.13716 0.82804)
						(xy -0.11684 0.85344) (xy -0.09144 0.87376) (xy -0.0635 0.889) (xy -0.03175 0.89916) (xy 0 0.9017)
						(xy 0.03175 0.89916) (xy 0.0635 0.889) (xy 0.09144 0.87376) (xy 0.11684 0.85344) (xy 0.13716 0.82804)
						(xy 0.1524 0.8001) (xy 0.16256 0.76835) (xy 0.1651 0.7366) (xy 0.1651 0.44958) (xy 0.17272 0.44196)
						(xy 0.19812 0.4064) (xy 0.2032 0.39624) (xy 0.20701 0.38735) (xy 0.21209 0.37719) (xy 0.2159 0.36703)
						(xy 0.21844 0.35687) (xy 0.22225 0.34544) (xy 0.22352 0.33528) (xy 0.22606 0.32512) (xy 0.22733 0.31369)
						(xy 0.22733 0.30353) (xy 0.2286 0.2921) (xy 0.22733 0.28067) (xy 0.22733 0.27051) (xy 0.22606 0.25908)
						(xy 0.22352 0.24892) (xy 0.22225 0.23876) (xy 0.21844 0.22733) (xy 0.2159 0.21717) (xy 0.21209 0.20701)
						(xy 0.20701 0.19685) (xy 0.2032 0.18796) (xy 0.19812 0.1778) (xy 0.17272 0.14224) (xy 0.1651 0.13462)
						(xy 0.1651 -0.7366) (xy 0.16256 -0.76835) (xy 0.1524 -0.8001) (xy 0.13716 -0.82804) (xy 0.11684 -0.85344)
						(xy 0.09144 -0.87376) (xy 0.0635 -0.889) (xy 0.03175 -0.89916)
					)
					(width 0)
					(fill yes)
				)
			)
		)
		(pad "63" smd custom
			(at -13.050012 -4.100068)
			(size 0.1143 0.1143)
			(layers "B.Cu" "B.Mask" "B.Paste")
			(net "M_A_DQ26")
			(options
				(clearance outline)
				(anchor circle)
			)
			(primitives
				(gr_poly
					(pts
						(xy 0 -0.9017) (xy -0.03175 -0.89916) (xy -0.0635 -0.889) (xy -0.09144 -0.87376) (xy -0.11684 -0.85344)
						(xy -0.13716 -0.82804) (xy -0.1524 -0.8001) (xy -0.16256 -0.76835) (xy -0.1651 -0.7366) (xy -0.1651 -0.19685)
						(xy -0.17272 -0.18923) (xy -0.17907 -0.18034) (xy -0.18669 -0.17145) (xy -0.19177 -0.16256) (xy -0.19812 -0.15367)
						(xy -0.20828 -0.13335) (xy -0.21971 -0.10287) (xy -0.22225 -0.09271) (xy -0.22479 -0.08128) (xy -0.22606 -0.07112)
						(xy -0.2286 -0.05969) (xy -0.2286 -0.01651) (xy -0.22606 -0.00508) (xy -0.22479 0.00508) (xy -0.22225 0.01651)
						(xy -0.21971 0.02667) (xy -0.20828 0.05715) (xy -0.19812 0.07747) (xy -0.19177 0.08636) (xy -0.18669 0.09525)
						(xy -0.17907 0.10414) (xy -0.17272 0.11303) (xy -0.1651 0.12065) (xy -0.1651 0.7366) (xy -0.16256 0.76835)
						(xy -0.1524 0.8001) (xy -0.13716 0.82804) (xy -0.11684 0.85344) (xy -0.09144 0.87376) (xy -0.0635 0.889)
						(xy -0.03175 0.89916) (xy 0 0.9017) (xy 0.03175 0.89916) (xy 0.0635 0.889) (xy 0.09144 0.87376)
						(xy 0.11684 0.85344) (xy 0.13716 0.82804) (xy 0.1524 0.8001) (xy 0.16256 0.76835) (xy 0.1651 0.7366)
						(xy 0.1651 0.11938) (xy 0.17272 0.11176) (xy 0.19812 0.0762) (xy 0.2032 0.06604) (xy 0.20701 0.05715)
						(xy 0.21209 0.04699) (xy 0.2159 0.03683) (xy 0.21844 0.02667) (xy 0.22225 0.01524) (xy 0.22352 0.00508)
						(xy 0.22606 -0.00508) (xy 0.22733 -0.01651) (xy 0.22733 -0.02667) (xy 0.2286 -0.0381) (xy 0.22733 -0.04953)
						(xy 0.22733 -0.05969) (xy 0.22606 -0.07112) (xy 0.22352 -0.08128) (xy 0.22225 -0.09144) (xy 0.21844 -0.10287)
						(xy 0.2159 -0.11303) (xy 0.21209 -0.12319) (xy 0.20701 -0.13335) (xy 0.2032 -0.14224) (xy 0.19812 -0.1524)
						(xy 0.17272 -0.18796) (xy 0.1651 -0.19558) (xy 0.1651 -0.7366) (xy 0.16256 -0.76835) (xy 0.1524 -0.8001)
						(xy 0.13716 -0.82804) (xy 0.11684 -0.85344) (xy 0.09144 -0.87376) (xy 0.0635 -0.889) (xy 0.03175 -0.89916)
					)
					(width 0)
					(fill yes)
				)
			)
		)
		(pad "64" smd custom
			(at -12.750038 4.100068)
			(size 0.1143 0.1143)
			(layers "B.Cu" "B.Mask" "B.Paste")
			(net "GND")
			(options
				(clearance outline)
				(anchor circle)
			)
			(primitives
				(gr_poly
					(pts
						(xy 0 -0.9017) (xy -0.03175 -0.89916) (xy -0.0635 -0.889) (xy -0.09144 -0.87376) (xy -0.11684 -0.85344)
						(xy -0.13716 -0.82804) (xy -0.1524 -0.8001) (xy -0.16256 -0.76835) (xy -0.1651 -0.7366) (xy -0.1651 -0.11938)
						(xy -0.17272 -0.11176) (xy -0.19812 -0.0762) (xy -0.2032 -0.06604) (xy -0.20701 -0.05715) (xy -0.21209 -0.04699)
						(xy -0.2159 -0.03683) (xy -0.21844 -0.02667) (xy -0.22225 -0.01524) (xy -0.22352 -0.00508) (xy -0.22606 0.00508)
						(xy -0.22733 0.01651) (xy -0.22733 0.02667) (xy -0.2286 0.0381) (xy -0.22733 0.04953) (xy -0.22733 0.05969)
						(xy -0.22606 0.07112) (xy -0.22352 0.08128) (xy -0.22225 0.09144) (xy -0.21844 0.10287) (xy -0.2159 0.11303)
						(xy -0.21209 0.12319) (xy -0.20701 0.13335) (xy -0.2032 0.14224) (xy -0.19812 0.1524) (xy -0.17272 0.18796)
						(xy -0.1651 0.19558) (xy -0.1651 0.7366) (xy -0.16256 0.76835) (xy -0.1524 0.8001) (xy -0.13716 0.82804)
						(xy -0.11684 0.85344) (xy -0.09144 0.87376) (xy -0.0635 0.889) (xy -0.03175 0.89916) (xy 0 0.9017)
						(xy 0.03175 0.89916) (xy 0.0635 0.889) (xy 0.09144 0.87376) (xy 0.11684 0.85344) (xy 0.13716 0.82804)
						(xy 0.1524 0.8001) (xy 0.16256 0.76835) (xy 0.1651 0.7366) (xy 0.1651 0.19685) (xy 0.17272 0.18923)
						(xy 0.17907 0.18034) (xy 0.18669 0.17145) (xy 0.19177 0.16256) (xy 0.19812 0.15367) (xy 0.20828 0.13335)
						(xy 0.21971 0.10287) (xy 0.22225 0.09271) (xy 0.22479 0.08128) (xy 0.22606 0.07112) (xy 0.2286 0.05969)
						(xy 0.2286 0.01651) (xy 0.22606 0.00508) (xy 0.22479 -0.00508) (xy 0.22225 -0.01651) (xy 0.21971 -0.02667)
						(xy 0.20828 -0.05715) (xy 0.19812 -0.07747) (xy 0.19177 -0.08636) (xy 0.18669 -0.09525) (xy 0.17907 -0.10414)
						(xy 0.17272 -0.11303) (xy 0.1651 -0.12065) (xy 0.1651 -0.7366) (xy 0.16256 -0.76835) (xy 0.1524 -0.8001)
						(xy 0.13716 -0.82804) (xy 0.11684 -0.85344) (xy 0.09144 -0.87376) (xy 0.0635 -0.889) (xy 0.03175 -0.89916)
					)
					(width 0)
					(fill yes)
				)
			)
		)
		(pad "65" smd custom
			(at -12.450064 -4.100068)
			(size 0.1143 0.1143)
			(layers "B.Cu" "B.Mask" "B.Paste")
			(net "M_A_DQ27")
			(options
				(clearance outline)
				(anchor circle)
			)
			(primitives
				(gr_poly
					(pts
						(xy 0 -0.9017) (xy -0.03175 -0.89916) (xy -0.0635 -0.889) (xy -0.09144 -0.87376) (xy -0.11684 -0.85344)
						(xy -0.13716 -0.82804) (xy -0.1524 -0.8001) (xy -0.16256 -0.76835) (xy -0.1651 -0.7366) (xy -0.1651 -0.44958)
						(xy -0.17272 -0.44196) (xy -0.19812 -0.4064) (xy -0.2032 -0.39624) (xy -0.20701 -0.38735) (xy -0.21209 -0.37719)
						(xy -0.2159 -0.36703) (xy -0.21844 -0.35687) (xy -0.22225 -0.34544) (xy -0.22352 -0.33528) (xy -0.22606 -0.32512)
						(xy -0.22733 -0.31369) (xy -0.22733 -0.30353) (xy -0.2286 -0.2921) (xy -0.22733 -0.28067) (xy -0.22733 -0.27051)
						(xy -0.22606 -0.25908) (xy -0.22352 -0.24892) (xy -0.22225 -0.23876) (xy -0.21844 -0.22733) (xy -0.2159 -0.21717)
						(xy -0.21209 -0.20701) (xy -0.20701 -0.19685) (xy -0.2032 -0.18796) (xy -0.19812 -0.1778) (xy -0.17272 -0.14224)
						(xy -0.1651 -0.13462) (xy -0.1651 0.7366) (xy -0.16256 0.76835) (xy -0.1524 0.8001) (xy -0.13716 0.82804)
						(xy -0.11684 0.85344) (xy -0.09144 0.87376) (xy -0.0635 0.889) (xy -0.03175 0.89916) (xy 0 0.9017)
						(xy 0.03175 0.89916) (xy 0.0635 0.889) (xy 0.09144 0.87376) (xy 0.11684 0.85344) (xy 0.13716 0.82804)
						(xy 0.1524 0.8001) (xy 0.16256 0.76835) (xy 0.1651 0.7366) (xy 0.1651 -0.13462) (xy 0.17272 -0.14224)
						(xy 0.19812 -0.1778) (xy 0.2032 -0.18796) (xy 0.20701 -0.19685) (xy 0.21209 -0.20701) (xy 0.2159 -0.21717)
						(xy 0.21844 -0.22733) (xy 0.22225 -0.23876) (xy 0.22352 -0.24892) (xy 0.22606 -0.25908) (xy 0.22733 -0.27051)
						(xy 0.22733 -0.28067) (xy 0.2286 -0.2921) (xy 0.22733 -0.30353) (xy 0.22733 -0.31369) (xy 0.22606 -0.32512)
						(xy 0.22352 -0.33528) (xy 0.22225 -0.34544) (xy 0.21844 -0.35687) (xy 0.2159 -0.36703) (xy 0.21209 -0.37719)
						(xy 0.20701 -0.38735) (xy 0.2032 -0.39624) (xy 0.19812 -0.4064) (xy 0.17272 -0.44196) (xy 0.1651 -0.44958)
						(xy 0.1651 -0.7366) (xy 0.16256 -0.76835) (xy 0.1524 -0.8001) (xy 0.13716 -0.82804) (xy 0.11684 -0.85344)
						(xy 0.09144 -0.87376) (xy 0.0635 -0.889) (xy 0.03175 -0.89916)
					)
					(width 0)
					(fill yes)
				)
			)
		)
		(pad "66" smd custom
			(at -12.15009 4.100068)
			(size 0.1143 0.1143)
			(layers "B.Cu" "B.Mask" "B.Paste")
			(net "M_A_DQ30")
			(options
				(clearance outline)
				(anchor circle)
			)
			(primitives
				(gr_poly
					(pts
						(xy 0 -0.9017) (xy -0.03175 -0.89916) (xy -0.0635 -0.889) (xy -0.09144 -0.87376) (xy -0.11684 -0.85344)
						(xy -0.13716 -0.82804) (xy -0.1524 -0.8001) (xy -0.16256 -0.76835) (xy -0.1651 -0.7366) (xy -0.1651 0.13462)
						(xy -0.17272 0.14224) (xy -0.19812 0.1778) (xy -0.2032 0.18796) (xy -0.20701 0.19685) (xy -0.21209 0.20701)
						(xy -0.2159 0.21717) (xy -0.21844 0.22733) (xy -0.22225 0.23876) (xy -0.22352 0.24892) (xy -0.22606 0.25908)
						(xy -0.22733 0.27051) (xy -0.22733 0.28067) (xy -0.2286 0.2921) (xy -0.22733 0.30353) (xy -0.22733 0.31369)
						(xy -0.22606 0.32512) (xy -0.22352 0.33528) (xy -0.22225 0.34544) (xy -0.21844 0.35687) (xy -0.2159 0.36703)
						(xy -0.21209 0.37719) (xy -0.20701 0.38735) (xy -0.2032 0.39624) (xy -0.19812 0.4064) (xy -0.17272 0.44196)
						(xy -0.1651 0.44958) (xy -0.1651 0.7366) (xy -0.16256 0.76835) (xy -0.1524 0.8001) (xy -0.13716 0.82804)
						(xy -0.11684 0.85344) (xy -0.09144 0.87376) (xy -0.0635 0.889) (xy -0.03175 0.89916) (xy 0 0.9017)
						(xy 0.03175 0.89916) (xy 0.0635 0.889) (xy 0.09144 0.87376) (xy 0.11684 0.85344) (xy 0.13716 0.82804)
						(xy 0.1524 0.8001) (xy 0.16256 0.76835) (xy 0.1651 0.7366) (xy 0.1651 0.44958) (xy 0.17272 0.44196)
						(xy 0.19812 0.4064) (xy 0.2032 0.39624) (xy 0.20701 0.38735) (xy 0.21209 0.37719) (xy 0.2159 0.36703)
						(xy 0.21844 0.35687) (xy 0.22225 0.34544) (xy 0.22352 0.33528) (xy 0.22606 0.32512) (xy 0.22733 0.31369)
						(xy 0.22733 0.30353) (xy 0.2286 0.2921) (xy 0.22733 0.28067) (xy 0.22733 0.27051) (xy 0.22606 0.25908)
						(xy 0.22352 0.24892) (xy 0.22225 0.23876) (xy 0.21844 0.22733) (xy 0.2159 0.21717) (xy 0.21209 0.20701)
						(xy 0.20701 0.19685) (xy 0.2032 0.18796) (xy 0.19812 0.1778) (xy 0.17272 0.14224) (xy 0.1651 0.13462)
						(xy 0.1651 -0.7366) (xy 0.16256 -0.76835) (xy 0.1524 -0.8001) (xy 0.13716 -0.82804) (xy 0.11684 -0.85344)
						(xy 0.09144 -0.87376) (xy 0.0635 -0.889) (xy 0.03175 -0.89916)
					)
					(width 0)
					(fill yes)
				)
			)
		)
		(pad "67" smd custom
			(at -11.850116 -4.100068)
			(size 0.1143 0.1143)
			(layers "B.Cu" "B.Mask" "B.Paste")
			(net "GND")
			(options
				(clearance outline)
				(anchor circle)
			)
			(primitives
				(gr_poly
					(pts
						(xy 0 -0.9017) (xy -0.03175 -0.89916) (xy -0.0635 -0.889) (xy -0.09144 -0.87376) (xy -0.11684 -0.85344)
						(xy -0.13716 -0.82804) (xy -0.1524 -0.8001) (xy -0.16256 -0.76835) (xy -0.1651 -0.7366) (xy -0.1651 -0.19685)
						(xy -0.17272 -0.18923) (xy -0.17907 -0.18034) (xy -0.18669 -0.17145) (xy -0.19177 -0.16256) (xy -0.19812 -0.15367)
						(xy -0.20828 -0.13335) (xy -0.21971 -0.10287) (xy -0.22225 -0.09271) (xy -0.22479 -0.08128) (xy -0.22606 -0.07112)
						(xy -0.2286 -0.05969) (xy -0.2286 -0.01651) (xy -0.22606 -0.00508) (xy -0.22479 0.00508) (xy -0.22225 0.01651)
						(xy -0.21971 0.02667) (xy -0.20828 0.05715) (xy -0.19812 0.07747) (xy -0.19177 0.08636) (xy -0.18669 0.09525)
						(xy -0.17907 0.10414) (xy -0.17272 0.11303) (xy -0.1651 0.12065) (xy -0.1651 0.7366) (xy -0.16256 0.76835)
						(xy -0.1524 0.8001) (xy -0.13716 0.82804) (xy -0.11684 0.85344) (xy -0.09144 0.87376) (xy -0.0635 0.889)
						(xy -0.03175 0.89916) (xy 0 0.9017) (xy 0.03175 0.89916) (xy 0.0635 0.889) (xy 0.09144 0.87376)
						(xy 0.11684 0.85344) (xy 0.13716 0.82804) (xy 0.1524 0.8001) (xy 0.16256 0.76835) (xy 0.1651 0.7366)
						(xy 0.1651 0.11938) (xy 0.17272 0.11176) (xy 0.19812 0.0762) (xy 0.2032 0.06604) (xy 0.20701 0.05715)
						(xy 0.21209 0.04699) (xy 0.2159 0.03683) (xy 0.21844 0.02667) (xy 0.22225 0.01524) (xy 0.22352 0.00508)
						(xy 0.22606 -0.00508) (xy 0.22733 -0.01651) (xy 0.22733 -0.02667) (xy 0.2286 -0.0381) (xy 0.22733 -0.04953)
						(xy 0.22733 -0.05969) (xy 0.22606 -0.07112) (xy 0.22352 -0.08128) (xy 0.22225 -0.09144) (xy 0.21844 -0.10287)
						(xy 0.2159 -0.11303) (xy 0.21209 -0.12319) (xy 0.20701 -0.13335) (xy 0.2032 -0.14224) (xy 0.19812 -0.1524)
						(xy 0.17272 -0.18796) (xy 0.1651 -0.19558) (xy 0.1651 -0.7366) (xy 0.16256 -0.76835) (xy 0.1524 -0.8001)
						(xy 0.13716 -0.82804) (xy 0.11684 -0.85344) (xy 0.09144 -0.87376) (xy 0.0635 -0.889) (xy 0.03175 -0.89916)
					)
					(width 0)
					(fill yes)
				)
			)
		)
		(pad "68" smd custom
			(at -11.549888 4.100068)
			(size 0.1143 0.1143)
			(layers "B.Cu" "B.Mask" "B.Paste")
			(net "M_A_DQ31")
			(options
				(clearance outline)
				(anchor circle)
			)
			(primitives
				(gr_poly
					(pts
						(xy 0 -0.9017) (xy -0.03175 -0.89916) (xy -0.0635 -0.889) (xy -0.09144 -0.87376) (xy -0.11684 -0.85344)
						(xy -0.13716 -0.82804) (xy -0.1524 -0.8001) (xy -0.16256 -0.76835) (xy -0.1651 -0.7366) (xy -0.1651 -0.11938)
						(xy -0.17272 -0.11176) (xy -0.19812 -0.0762) (xy -0.2032 -0.06604) (xy -0.20701 -0.05715) (xy -0.21209 -0.04699)
						(xy -0.2159 -0.03683) (xy -0.21844 -0.02667) (xy -0.22225 -0.01524) (xy -0.22352 -0.00508) (xy -0.22606 0.00508)
						(xy -0.22733 0.01651) (xy -0.22733 0.02667) (xy -0.2286 0.0381) (xy -0.22733 0.04953) (xy -0.22733 0.05969)
						(xy -0.22606 0.07112) (xy -0.22352 0.08128) (xy -0.22225 0.09144) (xy -0.21844 0.10287) (xy -0.2159 0.11303)
						(xy -0.21209 0.12319) (xy -0.20701 0.13335) (xy -0.2032 0.14224) (xy -0.19812 0.1524) (xy -0.17272 0.18796)
						(xy -0.1651 0.19558) (xy -0.1651 0.7366) (xy -0.16256 0.76835) (xy -0.1524 0.8001) (xy -0.13716 0.82804)
						(xy -0.11684 0.85344) (xy -0.09144 0.87376) (xy -0.0635 0.889) (xy -0.03175 0.89916) (xy 0 0.9017)
						(xy 0.03175 0.89916) (xy 0.0635 0.889) (xy 0.09144 0.87376) (xy 0.11684 0.85344) (xy 0.13716 0.82804)
						(xy 0.1524 0.8001) (xy 0.16256 0.76835) (xy 0.1651 0.7366) (xy 0.1651 0.19685) (xy 0.17272 0.18923)
						(xy 0.17907 0.18034) (xy 0.18669 0.17145) (xy 0.19177 0.16256) (xy 0.19812 0.15367) (xy 0.20828 0.13335)
						(xy 0.21971 0.10287) (xy 0.22225 0.09271) (xy 0.22479 0.08128) (xy 0.22606 0.07112) (xy 0.2286 0.05969)
						(xy 0.2286 0.01651) (xy 0.22606 0.00508) (xy 0.22479 -0.00508) (xy 0.22225 -0.01651) (xy 0.21971 -0.02667)
						(xy 0.20828 -0.05715) (xy 0.19812 -0.07747) (xy 0.19177 -0.08636) (xy 0.18669 -0.09525) (xy 0.17907 -0.10414)
						(xy 0.17272 -0.11303) (xy 0.1651 -0.12065) (xy 0.1651 -0.7366) (xy 0.16256 -0.76835) (xy 0.1524 -0.8001)
						(xy 0.13716 -0.82804) (xy 0.11684 -0.85344) (xy 0.09144 -0.87376) (xy 0.0635 -0.889) (xy 0.03175 -0.89916)
					)
					(width 0)
					(fill yes)
				)
			)
		)
		(pad "69" smd custom
			(at -11.249914 -4.100068)
			(size 0.1143 0.1143)
			(layers "B.Cu" "B.Mask" "B.Paste")
			(net "M_A_ECC0")
			(options
				(clearance outline)
				(anchor circle)
			)
			(primitives
				(gr_poly
					(pts
						(xy 0 -0.9017) (xy -0.03175 -0.89916) (xy -0.0635 -0.889) (xy -0.09144 -0.87376) (xy -0.11684 -0.85344)
						(xy -0.13716 -0.82804) (xy -0.1524 -0.8001) (xy -0.16256 -0.76835) (xy -0.1651 -0.7366) (xy -0.1651 -0.44958)
						(xy -0.17272 -0.44196) (xy -0.19812 -0.4064) (xy -0.2032 -0.39624) (xy -0.20701 -0.38735) (xy -0.21209 -0.37719)
						(xy -0.2159 -0.36703) (xy -0.21844 -0.35687) (xy -0.22225 -0.34544) (xy -0.22352 -0.33528) (xy -0.22606 -0.32512)
						(xy -0.22733 -0.31369) (xy -0.22733 -0.30353) (xy -0.2286 -0.2921) (xy -0.22733 -0.28067) (xy -0.22733 -0.27051)
						(xy -0.22606 -0.25908) (xy -0.22352 -0.24892) (xy -0.22225 -0.23876) (xy -0.21844 -0.22733) (xy -0.2159 -0.21717)
						(xy -0.21209 -0.20701) (xy -0.20701 -0.19685) (xy -0.2032 -0.18796) (xy -0.19812 -0.1778) (xy -0.17272 -0.14224)
						(xy -0.1651 -0.13462) (xy -0.1651 0.7366) (xy -0.16256 0.76835) (xy -0.1524 0.8001) (xy -0.13716 0.82804)
						(xy -0.11684 0.85344) (xy -0.09144 0.87376) (xy -0.0635 0.889) (xy -0.03175 0.89916) (xy 0 0.9017)
						(xy 0.03175 0.89916) (xy 0.0635 0.889) (xy 0.09144 0.87376) (xy 0.11684 0.85344) (xy 0.13716 0.82804)
						(xy 0.1524 0.8001) (xy 0.16256 0.76835) (xy 0.1651 0.7366) (xy 0.1651 -0.13462) (xy 0.17272 -0.14224)
						(xy 0.19812 -0.1778) (xy 0.2032 -0.18796) (xy 0.20701 -0.19685) (xy 0.21209 -0.20701) (xy 0.2159 -0.21717)
						(xy 0.21844 -0.22733) (xy 0.22225 -0.23876) (xy 0.22352 -0.24892) (xy 0.22606 -0.25908) (xy 0.22733 -0.27051)
						(xy 0.22733 -0.28067) (xy 0.2286 -0.2921) (xy 0.22733 -0.30353) (xy 0.22733 -0.31369) (xy 0.22606 -0.32512)
						(xy 0.22352 -0.33528) (xy 0.22225 -0.34544) (xy 0.21844 -0.35687) (xy 0.2159 -0.36703) (xy 0.21209 -0.37719)
						(xy 0.20701 -0.38735) (xy 0.2032 -0.39624) (xy 0.19812 -0.4064) (xy 0.17272 -0.44196) (xy 0.1651 -0.44958)
						(xy 0.1651 -0.7366) (xy 0.16256 -0.76835) (xy 0.1524 -0.8001) (xy 0.13716 -0.82804) (xy 0.11684 -0.85344)
						(xy 0.09144 -0.87376) (xy 0.0635 -0.889) (xy 0.03175 -0.89916)
					)
					(width 0)
					(fill yes)
				)
			)
		)
		(pad "70" smd custom
			(at -10.94994 4.100068)
			(size 0.1143 0.1143)
			(layers "B.Cu" "B.Mask" "B.Paste")
			(net "GND")
			(options
				(clearance outline)
				(anchor circle)
			)
			(primitives
				(gr_poly
					(pts
						(xy 0 -0.9017) (xy -0.03175 -0.89916) (xy -0.0635 -0.889) (xy -0.09144 -0.87376) (xy -0.11684 -0.85344)
						(xy -0.13716 -0.82804) (xy -0.1524 -0.8001) (xy -0.16256 -0.76835) (xy -0.1651 -0.7366) (xy -0.1651 0.13462)
						(xy -0.17272 0.14224) (xy -0.19812 0.1778) (xy -0.2032 0.18796) (xy -0.20701 0.19685) (xy -0.21209 0.20701)
						(xy -0.2159 0.21717) (xy -0.21844 0.22733) (xy -0.22225 0.23876) (xy -0.22352 0.24892) (xy -0.22606 0.25908)
						(xy -0.22733 0.27051) (xy -0.22733 0.28067) (xy -0.2286 0.2921) (xy -0.22733 0.30353) (xy -0.22733 0.31369)
						(xy -0.22606 0.32512) (xy -0.22352 0.33528) (xy -0.22225 0.34544) (xy -0.21844 0.35687) (xy -0.2159 0.36703)
						(xy -0.21209 0.37719) (xy -0.20701 0.38735) (xy -0.2032 0.39624) (xy -0.19812 0.4064) (xy -0.17272 0.44196)
						(xy -0.1651 0.44958) (xy -0.1651 0.7366) (xy -0.16256 0.76835) (xy -0.1524 0.8001) (xy -0.13716 0.82804)
						(xy -0.11684 0.85344) (xy -0.09144 0.87376) (xy -0.0635 0.889) (xy -0.03175 0.89916) (xy 0 0.9017)
						(xy 0.03175 0.89916) (xy 0.0635 0.889) (xy 0.09144 0.87376) (xy 0.11684 0.85344) (xy 0.13716 0.82804)
						(xy 0.1524 0.8001) (xy 0.16256 0.76835) (xy 0.1651 0.7366) (xy 0.1651 0.44958) (xy 0.17272 0.44196)
						(xy 0.19812 0.4064) (xy 0.2032 0.39624) (xy 0.20701 0.38735) (xy 0.21209 0.37719) (xy 0.2159 0.36703)
						(xy 0.21844 0.35687) (xy 0.22225 0.34544) (xy 0.22352 0.33528) (xy 0.22606 0.32512) (xy 0.22733 0.31369)
						(xy 0.22733 0.30353) (xy 0.2286 0.2921) (xy 0.22733 0.28067) (xy 0.22733 0.27051) (xy 0.22606 0.25908)
						(xy 0.22352 0.24892) (xy 0.22225 0.23876) (xy 0.21844 0.22733) (xy 0.2159 0.21717) (xy 0.21209 0.20701)
						(xy 0.20701 0.19685) (xy 0.2032 0.18796) (xy 0.19812 0.1778) (xy 0.17272 0.14224) (xy 0.1651 0.13462)
						(xy 0.1651 -0.7366) (xy 0.16256 -0.76835) (xy 0.1524 -0.8001) (xy 0.13716 -0.82804) (xy 0.11684 -0.85344)
						(xy 0.09144 -0.87376) (xy 0.0635 -0.889) (xy 0.03175 -0.89916)
					)
					(width 0)
					(fill yes)
				)
			)
		)
		(pad "71" smd custom
			(at -10.649966 -4.100068)
			(size 0.1143 0.1143)
			(layers "B.Cu" "B.Mask" "B.Paste")
			(net "M_A_ECC1")
			(options
				(clearance outline)
				(anchor circle)
			)
			(primitives
				(gr_poly
					(pts
						(xy 0 -0.9017) (xy -0.03175 -0.89916) (xy -0.0635 -0.889) (xy -0.09144 -0.87376) (xy -0.11684 -0.85344)
						(xy -0.13716 -0.82804) (xy -0.1524 -0.8001) (xy -0.16256 -0.76835) (xy -0.1651 -0.7366) (xy -0.1651 -0.19685)
						(xy -0.17272 -0.18923) (xy -0.17907 -0.18034) (xy -0.18669 -0.17145) (xy -0.19177 -0.16256) (xy -0.19812 -0.15367)
						(xy -0.20828 -0.13335) (xy -0.21971 -0.10287) (xy -0.22225 -0.09271) (xy -0.22479 -0.08128) (xy -0.22606 -0.07112)
						(xy -0.2286 -0.05969) (xy -0.2286 -0.01651) (xy -0.22606 -0.00508) (xy -0.22479 0.00508) (xy -0.22225 0.01651)
						(xy -0.21971 0.02667) (xy -0.20828 0.05715) (xy -0.19812 0.07747) (xy -0.19177 0.08636) (xy -0.18669 0.09525)
						(xy -0.17907 0.10414) (xy -0.17272 0.11303) (xy -0.1651 0.12065) (xy -0.1651 0.7366) (xy -0.16256 0.76835)
						(xy -0.1524 0.8001) (xy -0.13716 0.82804) (xy -0.11684 0.85344) (xy -0.09144 0.87376) (xy -0.0635 0.889)
						(xy -0.03175 0.89916) (xy 0 0.9017) (xy 0.03175 0.89916) (xy 0.0635 0.889) (xy 0.09144 0.87376)
						(xy 0.11684 0.85344) (xy 0.13716 0.82804) (xy 0.1524 0.8001) (xy 0.16256 0.76835) (xy 0.1651 0.7366)
						(xy 0.1651 0.11938) (xy 0.17272 0.11176) (xy 0.19812 0.0762) (xy 0.2032 0.06604) (xy 0.20701 0.05715)
						(xy 0.21209 0.04699) (xy 0.2159 0.03683) (xy 0.21844 0.02667) (xy 0.22225 0.01524) (xy 0.22352 0.00508)
						(xy 0.22606 -0.00508) (xy 0.22733 -0.01651) (xy 0.22733 -0.02667) (xy 0.2286 -0.0381) (xy 0.22733 -0.04953)
						(xy 0.22733 -0.05969) (xy 0.22606 -0.07112) (xy 0.22352 -0.08128) (xy 0.22225 -0.09144) (xy 0.21844 -0.10287)
						(xy 0.2159 -0.11303) (xy 0.21209 -0.12319) (xy 0.20701 -0.13335) (xy 0.2032 -0.14224) (xy 0.19812 -0.1524)
						(xy 0.17272 -0.18796) (xy 0.1651 -0.19558) (xy 0.1651 -0.7366) (xy 0.16256 -0.76835) (xy 0.1524 -0.8001)
						(xy 0.13716 -0.82804) (xy 0.11684 -0.85344) (xy 0.09144 -0.87376) (xy 0.0635 -0.889) (xy 0.03175 -0.89916)
					)
					(width 0)
					(fill yes)
				)
			)
		)
		(pad "72" smd custom
			(at -10.349992 4.100068)
			(size 0.1143 0.1143)
			(layers "B.Cu" "B.Mask" "B.Paste")
			(net "M_A_ECC4")
			(options
				(clearance outline)
				(anchor circle)
			)
			(primitives
				(gr_poly
					(pts
						(xy 0 -0.9017) (xy -0.03175 -0.89916) (xy -0.0635 -0.889) (xy -0.09144 -0.87376) (xy -0.11684 -0.85344)
						(xy -0.13716 -0.82804) (xy -0.1524 -0.8001) (xy -0.16256 -0.76835) (xy -0.1651 -0.7366) (xy -0.1651 -0.11938)
						(xy -0.17272 -0.11176) (xy -0.19812 -0.0762) (xy -0.2032 -0.06604) (xy -0.20701 -0.05715) (xy -0.21209 -0.04699)
						(xy -0.2159 -0.03683) (xy -0.21844 -0.02667) (xy -0.22225 -0.01524) (xy -0.22352 -0.00508) (xy -0.22606 0.00508)
						(xy -0.22733 0.01651) (xy -0.22733 0.02667) (xy -0.2286 0.0381) (xy -0.22733 0.04953) (xy -0.22733 0.05969)
						(xy -0.22606 0.07112) (xy -0.22352 0.08128) (xy -0.22225 0.09144) (xy -0.21844 0.10287) (xy -0.2159 0.11303)
						(xy -0.21209 0.12319) (xy -0.20701 0.13335) (xy -0.2032 0.14224) (xy -0.19812 0.1524) (xy -0.17272 0.18796)
						(xy -0.1651 0.19558) (xy -0.1651 0.7366) (xy -0.16256 0.76835) (xy -0.1524 0.8001) (xy -0.13716 0.82804)
						(xy -0.11684 0.85344) (xy -0.09144 0.87376) (xy -0.0635 0.889) (xy -0.03175 0.89916) (xy 0 0.9017)
						(xy 0.03175 0.89916) (xy 0.0635 0.889) (xy 0.09144 0.87376) (xy 0.11684 0.85344) (xy 0.13716 0.82804)
						(xy 0.1524 0.8001) (xy 0.16256 0.76835) (xy 0.1651 0.7366) (xy 0.1651 0.19685) (xy 0.17272 0.18923)
						(xy 0.17907 0.18034) (xy 0.18669 0.17145) (xy 0.19177 0.16256) (xy 0.19812 0.15367) (xy 0.20828 0.13335)
						(xy 0.21971 0.10287) (xy 0.22225 0.09271) (xy 0.22479 0.08128) (xy 0.22606 0.07112) (xy 0.2286 0.05969)
						(xy 0.2286 0.01651) (xy 0.22606 0.00508) (xy 0.22479 -0.00508) (xy 0.22225 -0.01651) (xy 0.21971 -0.02667)
						(xy 0.20828 -0.05715) (xy 0.19812 -0.07747) (xy 0.19177 -0.08636) (xy 0.18669 -0.09525) (xy 0.17907 -0.10414)
						(xy 0.17272 -0.11303) (xy 0.1651 -0.12065) (xy 0.1651 -0.7366) (xy 0.16256 -0.76835) (xy 0.1524 -0.8001)
						(xy 0.13716 -0.82804) (xy 0.11684 -0.85344) (xy 0.09144 -0.87376) (xy 0.0635 -0.889) (xy 0.03175 -0.89916)
					)
					(width 0)
					(fill yes)
				)
			)
		)
		(pad "73" smd custom
			(at -7.649972 -4.100068)
			(size 0.1143 0.1143)
			(layers "B.Cu" "B.Mask" "B.Paste")
			(net "GND")
			(options
				(clearance outline)
				(anchor circle)
			)
			(primitives
				(gr_poly
					(pts
						(xy 0 -0.9017) (xy -0.03175 -0.89916) (xy -0.0635 -0.889) (xy -0.09144 -0.87376) (xy -0.11684 -0.85344)
						(xy -0.13716 -0.82804) (xy -0.1524 -0.8001) (xy -0.16256 -0.76835) (xy -0.1651 -0.7366) (xy -0.1651 -0.44958)
						(xy -0.17272 -0.44196) (xy -0.19812 -0.4064) (xy -0.2032 -0.39624) (xy -0.20701 -0.38735) (xy -0.21209 -0.37719)
						(xy -0.2159 -0.36703) (xy -0.21844 -0.35687) (xy -0.22225 -0.34544) (xy -0.22352 -0.33528) (xy -0.22606 -0.32512)
						(xy -0.22733 -0.31369) (xy -0.22733 -0.30353) (xy -0.2286 -0.2921) (xy -0.22733 -0.28067) (xy -0.22733 -0.27051)
						(xy -0.22606 -0.25908) (xy -0.22352 -0.24892) (xy -0.22225 -0.23876) (xy -0.21844 -0.22733) (xy -0.2159 -0.21717)
						(xy -0.21209 -0.20701) (xy -0.20701 -0.19685) (xy -0.2032 -0.18796) (xy -0.19812 -0.1778) (xy -0.17272 -0.14224)
						(xy -0.1651 -0.13462) (xy -0.1651 0.7366) (xy -0.16256 0.76835) (xy -0.1524 0.8001) (xy -0.13716 0.82804)
						(xy -0.11684 0.85344) (xy -0.09144 0.87376) (xy -0.0635 0.889) (xy -0.03175 0.89916) (xy 0 0.9017)
						(xy 0.03175 0.89916) (xy 0.0635 0.889) (xy 0.09144 0.87376) (xy 0.11684 0.85344) (xy 0.13716 0.82804)
						(xy 0.1524 0.8001) (xy 0.16256 0.76835) (xy 0.1651 0.7366) (xy 0.1651 -0.13462) (xy 0.17272 -0.14224)
						(xy 0.19812 -0.1778) (xy 0.2032 -0.18796) (xy 0.20701 -0.19685) (xy 0.21209 -0.20701) (xy 0.2159 -0.21717)
						(xy 0.21844 -0.22733) (xy 0.22225 -0.23876) (xy 0.22352 -0.24892) (xy 0.22606 -0.25908) (xy 0.22733 -0.27051)
						(xy 0.22733 -0.28067) (xy 0.2286 -0.2921) (xy 0.22733 -0.30353) (xy 0.22733 -0.31369) (xy 0.22606 -0.32512)
						(xy 0.22352 -0.33528) (xy 0.22225 -0.34544) (xy 0.21844 -0.35687) (xy 0.2159 -0.36703) (xy 0.21209 -0.37719)
						(xy 0.20701 -0.38735) (xy 0.2032 -0.39624) (xy 0.19812 -0.4064) (xy 0.17272 -0.44196) (xy 0.1651 -0.44958)
						(xy 0.1651 -0.7366) (xy 0.16256 -0.76835) (xy 0.1524 -0.8001) (xy 0.13716 -0.82804) (xy 0.11684 -0.85344)
						(xy 0.09144 -0.87376) (xy 0.0635 -0.889) (xy 0.03175 -0.89916)
					)
					(width 0)
					(fill yes)
				)
			)
		)
		(pad "74" smd custom
			(at -7.349998 4.100068)
			(size 0.1143 0.1143)
			(layers "B.Cu" "B.Mask" "B.Paste")
			(net "M_A_ECC5")
			(options
				(clearance outline)
				(anchor circle)
			)
			(primitives
				(gr_poly
					(pts
						(xy 0 -0.9017) (xy -0.03175 -0.89916) (xy -0.0635 -0.889) (xy -0.09144 -0.87376) (xy -0.11684 -0.85344)
						(xy -0.13716 -0.82804) (xy -0.1524 -0.8001) (xy -0.16256 -0.76835) (xy -0.1651 -0.7366) (xy -0.1651 0.13462)
						(xy -0.17272 0.14224) (xy -0.19812 0.1778) (xy -0.2032 0.18796) (xy -0.20701 0.19685) (xy -0.21209 0.20701)
						(xy -0.2159 0.21717) (xy -0.21844 0.22733) (xy -0.22225 0.23876) (xy -0.22352 0.24892) (xy -0.22606 0.25908)
						(xy -0.22733 0.27051) (xy -0.22733 0.28067) (xy -0.2286 0.2921) (xy -0.22733 0.30353) (xy -0.22733 0.31369)
						(xy -0.22606 0.32512) (xy -0.22352 0.33528) (xy -0.22225 0.34544) (xy -0.21844 0.35687) (xy -0.2159 0.36703)
						(xy -0.21209 0.37719) (xy -0.20701 0.38735) (xy -0.2032 0.39624) (xy -0.19812 0.4064) (xy -0.17272 0.44196)
						(xy -0.1651 0.44958) (xy -0.1651 0.7366) (xy -0.16256 0.76835) (xy -0.1524 0.8001) (xy -0.13716 0.82804)
						(xy -0.11684 0.85344) (xy -0.09144 0.87376) (xy -0.0635 0.889) (xy -0.03175 0.89916) (xy 0 0.9017)
						(xy 0.03175 0.89916) (xy 0.0635 0.889) (xy 0.09144 0.87376) (xy 0.11684 0.85344) (xy 0.13716 0.82804)
						(xy 0.1524 0.8001) (xy 0.16256 0.76835) (xy 0.1651 0.7366) (xy 0.1651 0.44958) (xy 0.17272 0.44196)
						(xy 0.19812 0.4064) (xy 0.2032 0.39624) (xy 0.20701 0.38735) (xy 0.21209 0.37719) (xy 0.2159 0.36703)
						(xy 0.21844 0.35687) (xy 0.22225 0.34544) (xy 0.22352 0.33528) (xy 0.22606 0.32512) (xy 0.22733 0.31369)
						(xy 0.22733 0.30353) (xy 0.2286 0.2921) (xy 0.22733 0.28067) (xy 0.22733 0.27051) (xy 0.22606 0.25908)
						(xy 0.22352 0.24892) (xy 0.22225 0.23876) (xy 0.21844 0.22733) (xy 0.2159 0.21717) (xy 0.21209 0.20701)
						(xy 0.20701 0.19685) (xy 0.2032 0.18796) (xy 0.19812 0.1778) (xy 0.17272 0.14224) (xy 0.1651 0.13462)
						(xy 0.1651 -0.7366) (xy 0.16256 -0.76835) (xy 0.1524 -0.8001) (xy 0.13716 -0.82804) (xy 0.11684 -0.85344)
						(xy 0.09144 -0.87376) (xy 0.0635 -0.889) (xy 0.03175 -0.89916)
					)
					(width 0)
					(fill yes)
				)
			)
		)
		(pad "75" smd custom
			(at -7.050024 -4.100068)
			(size 0.1143 0.1143)
			(layers "B.Cu" "B.Mask" "B.Paste")
			(net "M_A_DQS_DN8")
			(options
				(clearance outline)
				(anchor circle)
			)
			(primitives
				(gr_poly
					(pts
						(xy 0 -0.9017) (xy -0.03175 -0.89916) (xy -0.0635 -0.889) (xy -0.09144 -0.87376) (xy -0.11684 -0.85344)
						(xy -0.13716 -0.82804) (xy -0.1524 -0.8001) (xy -0.16256 -0.76835) (xy -0.1651 -0.7366) (xy -0.1651 -0.19685)
						(xy -0.17272 -0.18923) (xy -0.17907 -0.18034) (xy -0.18669 -0.17145) (xy -0.19177 -0.16256) (xy -0.19812 -0.15367)
						(xy -0.20828 -0.13335) (xy -0.21971 -0.10287) (xy -0.22225 -0.09271) (xy -0.22479 -0.08128) (xy -0.22606 -0.07112)
						(xy -0.2286 -0.05969) (xy -0.2286 -0.01651) (xy -0.22606 -0.00508) (xy -0.22479 0.00508) (xy -0.22225 0.01651)
						(xy -0.21971 0.02667) (xy -0.20828 0.05715) (xy -0.19812 0.07747) (xy -0.19177 0.08636) (xy -0.18669 0.09525)
						(xy -0.17907 0.10414) (xy -0.17272 0.11303) (xy -0.1651 0.12065) (xy -0.1651 0.7366) (xy -0.16256 0.76835)
						(xy -0.1524 0.8001) (xy -0.13716 0.82804) (xy -0.11684 0.85344) (xy -0.09144 0.87376) (xy -0.0635 0.889)
						(xy -0.03175 0.89916) (xy 0 0.9017) (xy 0.03175 0.89916) (xy 0.0635 0.889) (xy 0.09144 0.87376)
						(xy 0.11684 0.85344) (xy 0.13716 0.82804) (xy 0.1524 0.8001) (xy 0.16256 0.76835) (xy 0.1651 0.7366)
						(xy 0.1651 0.11938) (xy 0.17272 0.11176) (xy 0.19812 0.0762) (xy 0.2032 0.06604) (xy 0.20701 0.05715)
						(xy 0.21209 0.04699) (xy 0.2159 0.03683) (xy 0.21844 0.02667) (xy 0.22225 0.01524) (xy 0.22352 0.00508)
						(xy 0.22606 -0.00508) (xy 0.22733 -0.01651) (xy 0.22733 -0.02667) (xy 0.2286 -0.0381) (xy 0.22733 -0.04953)
						(xy 0.22733 -0.05969) (xy 0.22606 -0.07112) (xy 0.22352 -0.08128) (xy 0.22225 -0.09144) (xy 0.21844 -0.10287)
						(xy 0.2159 -0.11303) (xy 0.21209 -0.12319) (xy 0.20701 -0.13335) (xy 0.2032 -0.14224) (xy 0.19812 -0.1524)
						(xy 0.17272 -0.18796) (xy 0.1651 -0.19558) (xy 0.1651 -0.7366) (xy 0.16256 -0.76835) (xy 0.1524 -0.8001)
						(xy 0.13716 -0.82804) (xy 0.11684 -0.85344) (xy 0.09144 -0.87376) (xy 0.0635 -0.889) (xy 0.03175 -0.89916)
					)
					(width 0)
					(fill yes)
				)
			)
		)
		(pad "76" smd custom
			(at -6.75005 4.100068)
			(size 0.1143 0.1143)
			(layers "B.Cu" "B.Mask" "B.Paste")
			(net "GND")
			(options
				(clearance outline)
				(anchor circle)
			)
			(primitives
				(gr_poly
					(pts
						(xy 0 -0.9017) (xy -0.03175 -0.89916) (xy -0.0635 -0.889) (xy -0.09144 -0.87376) (xy -0.11684 -0.85344)
						(xy -0.13716 -0.82804) (xy -0.1524 -0.8001) (xy -0.16256 -0.76835) (xy -0.1651 -0.7366) (xy -0.1651 -0.11938)
						(xy -0.17272 -0.11176) (xy -0.19812 -0.0762) (xy -0.2032 -0.06604) (xy -0.20701 -0.05715) (xy -0.21209 -0.04699)
						(xy -0.2159 -0.03683) (xy -0.21844 -0.02667) (xy -0.22225 -0.01524) (xy -0.22352 -0.00508) (xy -0.22606 0.00508)
						(xy -0.22733 0.01651) (xy -0.22733 0.02667) (xy -0.2286 0.0381) (xy -0.22733 0.04953) (xy -0.22733 0.05969)
						(xy -0.22606 0.07112) (xy -0.22352 0.08128) (xy -0.22225 0.09144) (xy -0.21844 0.10287) (xy -0.2159 0.11303)
						(xy -0.21209 0.12319) (xy -0.20701 0.13335) (xy -0.2032 0.14224) (xy -0.19812 0.1524) (xy -0.17272 0.18796)
						(xy -0.1651 0.19558) (xy -0.1651 0.7366) (xy -0.16256 0.76835) (xy -0.1524 0.8001) (xy -0.13716 0.82804)
						(xy -0.11684 0.85344) (xy -0.09144 0.87376) (xy -0.0635 0.889) (xy -0.03175 0.89916) (xy 0 0.9017)
						(xy 0.03175 0.89916) (xy 0.0635 0.889) (xy 0.09144 0.87376) (xy 0.11684 0.85344) (xy 0.13716 0.82804)
						(xy 0.1524 0.8001) (xy 0.16256 0.76835) (xy 0.1651 0.7366) (xy 0.1651 0.19685) (xy 0.17272 0.18923)
						(xy 0.17907 0.18034) (xy 0.18669 0.17145) (xy 0.19177 0.16256) (xy 0.19812 0.15367) (xy 0.20828 0.13335)
						(xy 0.21971 0.10287) (xy 0.22225 0.09271) (xy 0.22479 0.08128) (xy 0.22606 0.07112) (xy 0.2286 0.05969)
						(xy 0.2286 0.01651) (xy 0.22606 0.00508) (xy 0.22479 -0.00508) (xy 0.22225 -0.01651) (xy 0.21971 -0.02667)
						(xy 0.20828 -0.05715) (xy 0.19812 -0.07747) (xy 0.19177 -0.08636) (xy 0.18669 -0.09525) (xy 0.17907 -0.10414)
						(xy 0.17272 -0.11303) (xy 0.1651 -0.12065) (xy 0.1651 -0.7366) (xy 0.16256 -0.76835) (xy 0.1524 -0.8001)
						(xy 0.13716 -0.82804) (xy 0.11684 -0.85344) (xy 0.09144 -0.87376) (xy 0.0635 -0.889) (xy 0.03175 -0.89916)
					)
					(width 0)
					(fill yes)
				)
			)
		)
		(pad "77" smd custom
			(at -6.450076 -4.100068)
			(size 0.1143 0.1143)
			(layers "B.Cu" "B.Mask" "B.Paste")
			(net "M_A_DQS_DP8")
			(options
				(clearance outline)
				(anchor circle)
			)
			(primitives
				(gr_poly
					(pts
						(xy 0 -0.9017) (xy -0.03175 -0.89916) (xy -0.0635 -0.889) (xy -0.09144 -0.87376) (xy -0.11684 -0.85344)
						(xy -0.13716 -0.82804) (xy -0.1524 -0.8001) (xy -0.16256 -0.76835) (xy -0.1651 -0.7366) (xy -0.1651 -0.44958)
						(xy -0.17272 -0.44196) (xy -0.19812 -0.4064) (xy -0.2032 -0.39624) (xy -0.20701 -0.38735) (xy -0.21209 -0.37719)
						(xy -0.2159 -0.36703) (xy -0.21844 -0.35687) (xy -0.22225 -0.34544) (xy -0.22352 -0.33528) (xy -0.22606 -0.32512)
						(xy -0.22733 -0.31369) (xy -0.22733 -0.30353) (xy -0.2286 -0.2921) (xy -0.22733 -0.28067) (xy -0.22733 -0.27051)
						(xy -0.22606 -0.25908) (xy -0.22352 -0.24892) (xy -0.22225 -0.23876) (xy -0.21844 -0.22733) (xy -0.2159 -0.21717)
						(xy -0.21209 -0.20701) (xy -0.20701 -0.19685) (xy -0.2032 -0.18796) (xy -0.19812 -0.1778) (xy -0.17272 -0.14224)
						(xy -0.1651 -0.13462) (xy -0.1651 0.7366) (xy -0.16256 0.76835) (xy -0.1524 0.8001) (xy -0.13716 0.82804)
						(xy -0.11684 0.85344) (xy -0.09144 0.87376) (xy -0.0635 0.889) (xy -0.03175 0.89916) (xy 0 0.9017)
						(xy 0.03175 0.89916) (xy 0.0635 0.889) (xy 0.09144 0.87376) (xy 0.11684 0.85344) (xy 0.13716 0.82804)
						(xy 0.1524 0.8001) (xy 0.16256 0.76835) (xy 0.1651 0.7366) (xy 0.1651 -0.13462) (xy 0.17272 -0.14224)
						(xy 0.19812 -0.1778) (xy 0.2032 -0.18796) (xy 0.20701 -0.19685) (xy 0.21209 -0.20701) (xy 0.2159 -0.21717)
						(xy 0.21844 -0.22733) (xy 0.22225 -0.23876) (xy 0.22352 -0.24892) (xy 0.22606 -0.25908) (xy 0.22733 -0.27051)
						(xy 0.22733 -0.28067) (xy 0.2286 -0.2921) (xy 0.22733 -0.30353) (xy 0.22733 -0.31369) (xy 0.22606 -0.32512)
						(xy 0.22352 -0.33528) (xy 0.22225 -0.34544) (xy 0.21844 -0.35687) (xy 0.2159 -0.36703) (xy 0.21209 -0.37719)
						(xy 0.20701 -0.38735) (xy 0.2032 -0.39624) (xy 0.19812 -0.4064) (xy 0.17272 -0.44196) (xy 0.1651 -0.44958)
						(xy 0.1651 -0.7366) (xy 0.16256 -0.76835) (xy 0.1524 -0.8001) (xy 0.13716 -0.82804) (xy 0.11684 -0.85344)
						(xy 0.09144 -0.87376) (xy 0.0635 -0.889) (xy 0.03175 -0.89916)
					)
					(width 0)
					(fill yes)
				)
			)
		)
		(pad "78" smd custom
			(at -6.150102 4.100068)
			(size 0.1143 0.1143)
			(layers "B.Cu" "B.Mask" "B.Paste")
			(net "GND")
			(options
				(clearance outline)
				(anchor circle)
			)
			(primitives
				(gr_poly
					(pts
						(xy 0 -0.9017) (xy -0.03175 -0.89916) (xy -0.0635 -0.889) (xy -0.09144 -0.87376) (xy -0.11684 -0.85344)
						(xy -0.13716 -0.82804) (xy -0.1524 -0.8001) (xy -0.16256 -0.76835) (xy -0.1651 -0.7366) (xy -0.1651 0.13462)
						(xy -0.17272 0.14224) (xy -0.19812 0.1778) (xy -0.2032 0.18796) (xy -0.20701 0.19685) (xy -0.21209 0.20701)
						(xy -0.2159 0.21717) (xy -0.21844 0.22733) (xy -0.22225 0.23876) (xy -0.22352 0.24892) (xy -0.22606 0.25908)
						(xy -0.22733 0.27051) (xy -0.22733 0.28067) (xy -0.2286 0.2921) (xy -0.22733 0.30353) (xy -0.22733 0.31369)
						(xy -0.22606 0.32512) (xy -0.22352 0.33528) (xy -0.22225 0.34544) (xy -0.21844 0.35687) (xy -0.2159 0.36703)
						(xy -0.21209 0.37719) (xy -0.20701 0.38735) (xy -0.2032 0.39624) (xy -0.19812 0.4064) (xy -0.17272 0.44196)
						(xy -0.1651 0.44958) (xy -0.1651 0.7366) (xy -0.16256 0.76835) (xy -0.1524 0.8001) (xy -0.13716 0.82804)
						(xy -0.11684 0.85344) (xy -0.09144 0.87376) (xy -0.0635 0.889) (xy -0.03175 0.89916) (xy 0 0.9017)
						(xy 0.03175 0.89916) (xy 0.0635 0.889) (xy 0.09144 0.87376) (xy 0.11684 0.85344) (xy 0.13716 0.82804)
						(xy 0.1524 0.8001) (xy 0.16256 0.76835) (xy 0.1651 0.7366) (xy 0.1651 0.44958) (xy 0.17272 0.44196)
						(xy 0.19812 0.4064) (xy 0.2032 0.39624) (xy 0.20701 0.38735) (xy 0.21209 0.37719) (xy 0.2159 0.36703)
						(xy 0.21844 0.35687) (xy 0.22225 0.34544) (xy 0.22352 0.33528) (xy 0.22606 0.32512) (xy 0.22733 0.31369)
						(xy 0.22733 0.30353) (xy 0.2286 0.2921) (xy 0.22733 0.28067) (xy 0.22733 0.27051) (xy 0.22606 0.25908)
						(xy 0.22352 0.24892) (xy 0.22225 0.23876) (xy 0.21844 0.22733) (xy 0.2159 0.21717) (xy 0.21209 0.20701)
						(xy 0.20701 0.19685) (xy 0.2032 0.18796) (xy 0.19812 0.1778) (xy 0.17272 0.14224) (xy 0.1651 0.13462)
						(xy 0.1651 -0.7366) (xy 0.16256 -0.76835) (xy 0.1524 -0.8001) (xy 0.13716 -0.82804) (xy 0.11684 -0.85344)
						(xy 0.09144 -0.87376) (xy 0.0635 -0.889) (xy 0.03175 -0.89916)
					)
					(width 0)
					(fill yes)
				)
			)
		)
		(pad "79" smd custom
			(at -5.849874 -4.100068)
			(size 0.1143 0.1143)
			(layers "B.Cu" "B.Mask" "B.Paste")
			(net "GND")
			(options
				(clearance outline)
				(anchor circle)
			)
			(primitives
				(gr_poly
					(pts
						(xy 0 -0.9017) (xy -0.03175 -0.89916) (xy -0.0635 -0.889) (xy -0.09144 -0.87376) (xy -0.11684 -0.85344)
						(xy -0.13716 -0.82804) (xy -0.1524 -0.8001) (xy -0.16256 -0.76835) (xy -0.1651 -0.7366) (xy -0.1651 -0.19685)
						(xy -0.17272 -0.18923) (xy -0.17907 -0.18034) (xy -0.18669 -0.17145) (xy -0.19177 -0.16256) (xy -0.19812 -0.15367)
						(xy -0.20828 -0.13335) (xy -0.21971 -0.10287) (xy -0.22225 -0.09271) (xy -0.22479 -0.08128) (xy -0.22606 -0.07112)
						(xy -0.2286 -0.05969) (xy -0.2286 -0.01651) (xy -0.22606 -0.00508) (xy -0.22479 0.00508) (xy -0.22225 0.01651)
						(xy -0.21971 0.02667) (xy -0.20828 0.05715) (xy -0.19812 0.07747) (xy -0.19177 0.08636) (xy -0.18669 0.09525)
						(xy -0.17907 0.10414) (xy -0.17272 0.11303) (xy -0.1651 0.12065) (xy -0.1651 0.7366) (xy -0.16256 0.76835)
						(xy -0.1524 0.8001) (xy -0.13716 0.82804) (xy -0.11684 0.85344) (xy -0.09144 0.87376) (xy -0.0635 0.889)
						(xy -0.03175 0.89916) (xy 0 0.9017) (xy 0.03175 0.89916) (xy 0.0635 0.889) (xy 0.09144 0.87376)
						(xy 0.11684 0.85344) (xy 0.13716 0.82804) (xy 0.1524 0.8001) (xy 0.16256 0.76835) (xy 0.1651 0.7366)
						(xy 0.1651 0.11938) (xy 0.17272 0.11176) (xy 0.19812 0.0762) (xy 0.2032 0.06604) (xy 0.20701 0.05715)
						(xy 0.21209 0.04699) (xy 0.2159 0.03683) (xy 0.21844 0.02667) (xy 0.22225 0.01524) (xy 0.22352 0.00508)
						(xy 0.22606 -0.00508) (xy 0.22733 -0.01651) (xy 0.22733 -0.02667) (xy 0.2286 -0.0381) (xy 0.22733 -0.04953)
						(xy 0.22733 -0.05969) (xy 0.22606 -0.07112) (xy 0.22352 -0.08128) (xy 0.22225 -0.09144) (xy 0.21844 -0.10287)
						(xy 0.2159 -0.11303) (xy 0.21209 -0.12319) (xy 0.20701 -0.13335) (xy 0.2032 -0.14224) (xy 0.19812 -0.1524)
						(xy 0.17272 -0.18796) (xy 0.1651 -0.19558) (xy 0.1651 -0.7366) (xy 0.16256 -0.76835) (xy 0.1524 -0.8001)
						(xy 0.13716 -0.82804) (xy 0.11684 -0.85344) (xy 0.09144 -0.87376) (xy 0.0635 -0.889) (xy 0.03175 -0.89916)
					)
					(width 0)
					(fill yes)
				)
			)
		)
		(pad "80" smd custom
			(at -5.5499 4.100068)
			(size 0.1143 0.1143)
			(layers "B.Cu" "B.Mask" "B.Paste")
			(net "M_A_ECC6")
			(options
				(clearance outline)
				(anchor circle)
			)
			(primitives
				(gr_poly
					(pts
						(xy 0 -0.9017) (xy -0.03175 -0.89916) (xy -0.0635 -0.889) (xy -0.09144 -0.87376) (xy -0.11684 -0.85344)
						(xy -0.13716 -0.82804) (xy -0.1524 -0.8001) (xy -0.16256 -0.76835) (xy -0.1651 -0.7366) (xy -0.1651 -0.11938)
						(xy -0.17272 -0.11176) (xy -0.19812 -0.0762) (xy -0.2032 -0.06604) (xy -0.20701 -0.05715) (xy -0.21209 -0.04699)
						(xy -0.2159 -0.03683) (xy -0.21844 -0.02667) (xy -0.22225 -0.01524) (xy -0.22352 -0.00508) (xy -0.22606 0.00508)
						(xy -0.22733 0.01651) (xy -0.22733 0.02667) (xy -0.2286 0.0381) (xy -0.22733 0.04953) (xy -0.22733 0.05969)
						(xy -0.22606 0.07112) (xy -0.22352 0.08128) (xy -0.22225 0.09144) (xy -0.21844 0.10287) (xy -0.2159 0.11303)
						(xy -0.21209 0.12319) (xy -0.20701 0.13335) (xy -0.2032 0.14224) (xy -0.19812 0.1524) (xy -0.17272 0.18796)
						(xy -0.1651 0.19558) (xy -0.1651 0.7366) (xy -0.16256 0.76835) (xy -0.1524 0.8001) (xy -0.13716 0.82804)
						(xy -0.11684 0.85344) (xy -0.09144 0.87376) (xy -0.0635 0.889) (xy -0.03175 0.89916) (xy 0 0.9017)
						(xy 0.03175 0.89916) (xy 0.0635 0.889) (xy 0.09144 0.87376) (xy 0.11684 0.85344) (xy 0.13716 0.82804)
						(xy 0.1524 0.8001) (xy 0.16256 0.76835) (xy 0.1651 0.7366) (xy 0.1651 0.19685) (xy 0.17272 0.18923)
						(xy 0.17907 0.18034) (xy 0.18669 0.17145) (xy 0.19177 0.16256) (xy 0.19812 0.15367) (xy 0.20828 0.13335)
						(xy 0.21971 0.10287) (xy 0.22225 0.09271) (xy 0.22479 0.08128) (xy 0.22606 0.07112) (xy 0.2286 0.05969)
						(xy 0.2286 0.01651) (xy 0.22606 0.00508) (xy 0.22479 -0.00508) (xy 0.22225 -0.01651) (xy 0.21971 -0.02667)
						(xy 0.20828 -0.05715) (xy 0.19812 -0.07747) (xy 0.19177 -0.08636) (xy 0.18669 -0.09525) (xy 0.17907 -0.10414)
						(xy 0.17272 -0.11303) (xy 0.1651 -0.12065) (xy 0.1651 -0.7366) (xy 0.16256 -0.76835) (xy 0.1524 -0.8001)
						(xy 0.13716 -0.82804) (xy 0.11684 -0.85344) (xy 0.09144 -0.87376) (xy 0.0635 -0.889) (xy 0.03175 -0.89916)
					)
					(width 0)
					(fill yes)
				)
			)
		)
		(pad "81" smd custom
			(at -5.249926 -4.100068)
			(size 0.1143 0.1143)
			(layers "B.Cu" "B.Mask" "B.Paste")
			(net "M_A_ECC2")
			(options
				(clearance outline)
				(anchor circle)
			)
			(primitives
				(gr_poly
					(pts
						(xy 0 -0.9017) (xy -0.03175 -0.89916) (xy -0.0635 -0.889) (xy -0.09144 -0.87376) (xy -0.11684 -0.85344)
						(xy -0.13716 -0.82804) (xy -0.1524 -0.8001) (xy -0.16256 -0.76835) (xy -0.1651 -0.7366) (xy -0.1651 -0.44958)
						(xy -0.17272 -0.44196) (xy -0.19812 -0.4064) (xy -0.2032 -0.39624) (xy -0.20701 -0.38735) (xy -0.21209 -0.37719)
						(xy -0.2159 -0.36703) (xy -0.21844 -0.35687) (xy -0.22225 -0.34544) (xy -0.22352 -0.33528) (xy -0.22606 -0.32512)
						(xy -0.22733 -0.31369) (xy -0.22733 -0.30353) (xy -0.2286 -0.2921) (xy -0.22733 -0.28067) (xy -0.22733 -0.27051)
						(xy -0.22606 -0.25908) (xy -0.22352 -0.24892) (xy -0.22225 -0.23876) (xy -0.21844 -0.22733) (xy -0.2159 -0.21717)
						(xy -0.21209 -0.20701) (xy -0.20701 -0.19685) (xy -0.2032 -0.18796) (xy -0.19812 -0.1778) (xy -0.17272 -0.14224)
						(xy -0.1651 -0.13462) (xy -0.1651 0.7366) (xy -0.16256 0.76835) (xy -0.1524 0.8001) (xy -0.13716 0.82804)
						(xy -0.11684 0.85344) (xy -0.09144 0.87376) (xy -0.0635 0.889) (xy -0.03175 0.89916) (xy 0 0.9017)
						(xy 0.03175 0.89916) (xy 0.0635 0.889) (xy 0.09144 0.87376) (xy 0.11684 0.85344) (xy 0.13716 0.82804)
						(xy 0.1524 0.8001) (xy 0.16256 0.76835) (xy 0.1651 0.7366) (xy 0.1651 -0.13462) (xy 0.17272 -0.14224)
						(xy 0.19812 -0.1778) (xy 0.2032 -0.18796) (xy 0.20701 -0.19685) (xy 0.21209 -0.20701) (xy 0.2159 -0.21717)
						(xy 0.21844 -0.22733) (xy 0.22225 -0.23876) (xy 0.22352 -0.24892) (xy 0.22606 -0.25908) (xy 0.22733 -0.27051)
						(xy 0.22733 -0.28067) (xy 0.2286 -0.2921) (xy 0.22733 -0.30353) (xy 0.22733 -0.31369) (xy 0.22606 -0.32512)
						(xy 0.22352 -0.33528) (xy 0.22225 -0.34544) (xy 0.21844 -0.35687) (xy 0.2159 -0.36703) (xy 0.21209 -0.37719)
						(xy 0.20701 -0.38735) (xy 0.2032 -0.39624) (xy 0.19812 -0.4064) (xy 0.17272 -0.44196) (xy 0.1651 -0.44958)
						(xy 0.1651 -0.7366) (xy 0.16256 -0.76835) (xy 0.1524 -0.8001) (xy 0.13716 -0.82804) (xy 0.11684 -0.85344)
						(xy 0.09144 -0.87376) (xy 0.0635 -0.889) (xy 0.03175 -0.89916)
					)
					(width 0)
					(fill yes)
				)
			)
		)
		(pad "82" smd custom
			(at -4.949952 4.100068)
			(size 0.1143 0.1143)
			(layers "B.Cu" "B.Mask" "B.Paste")
			(net "M_A_ECC7")
			(options
				(clearance outline)
				(anchor circle)
			)
			(primitives
				(gr_poly
					(pts
						(xy 0 -0.9017) (xy -0.03175 -0.89916) (xy -0.0635 -0.889) (xy -0.09144 -0.87376) (xy -0.11684 -0.85344)
						(xy -0.13716 -0.82804) (xy -0.1524 -0.8001) (xy -0.16256 -0.76835) (xy -0.1651 -0.7366) (xy -0.1651 0.13462)
						(xy -0.17272 0.14224) (xy -0.19812 0.1778) (xy -0.2032 0.18796) (xy -0.20701 0.19685) (xy -0.21209 0.20701)
						(xy -0.2159 0.21717) (xy -0.21844 0.22733) (xy -0.22225 0.23876) (xy -0.22352 0.24892) (xy -0.22606 0.25908)
						(xy -0.22733 0.27051) (xy -0.22733 0.28067) (xy -0.2286 0.2921) (xy -0.22733 0.30353) (xy -0.22733 0.31369)
						(xy -0.22606 0.32512) (xy -0.22352 0.33528) (xy -0.22225 0.34544) (xy -0.21844 0.35687) (xy -0.2159 0.36703)
						(xy -0.21209 0.37719) (xy -0.20701 0.38735) (xy -0.2032 0.39624) (xy -0.19812 0.4064) (xy -0.17272 0.44196)
						(xy -0.1651 0.44958) (xy -0.1651 0.7366) (xy -0.16256 0.76835) (xy -0.1524 0.8001) (xy -0.13716 0.82804)
						(xy -0.11684 0.85344) (xy -0.09144 0.87376) (xy -0.0635 0.889) (xy -0.03175 0.89916) (xy 0 0.9017)
						(xy 0.03175 0.89916) (xy 0.0635 0.889) (xy 0.09144 0.87376) (xy 0.11684 0.85344) (xy 0.13716 0.82804)
						(xy 0.1524 0.8001) (xy 0.16256 0.76835) (xy 0.1651 0.7366) (xy 0.1651 0.44958) (xy 0.17272 0.44196)
						(xy 0.19812 0.4064) (xy 0.2032 0.39624) (xy 0.20701 0.38735) (xy 0.21209 0.37719) (xy 0.2159 0.36703)
						(xy 0.21844 0.35687) (xy 0.22225 0.34544) (xy 0.22352 0.33528) (xy 0.22606 0.32512) (xy 0.22733 0.31369)
						(xy 0.22733 0.30353) (xy 0.2286 0.2921) (xy 0.22733 0.28067) (xy 0.22733 0.27051) (xy 0.22606 0.25908)
						(xy 0.22352 0.24892) (xy 0.22225 0.23876) (xy 0.21844 0.22733) (xy 0.2159 0.21717) (xy 0.21209 0.20701)
						(xy 0.20701 0.19685) (xy 0.2032 0.18796) (xy 0.19812 0.1778) (xy 0.17272 0.14224) (xy 0.1651 0.13462)
						(xy 0.1651 -0.7366) (xy 0.16256 -0.76835) (xy 0.1524 -0.8001) (xy 0.13716 -0.82804) (xy 0.11684 -0.85344)
						(xy 0.09144 -0.87376) (xy 0.0635 -0.889) (xy 0.03175 -0.89916)
					)
					(width 0)
					(fill yes)
				)
			)
		)
		(pad "83" smd custom
			(at -4.649978 -4.100068)
			(size 0.1143 0.1143)
			(layers "B.Cu" "B.Mask" "B.Paste")
			(net "M_A_ECC3")
			(options
				(clearance outline)
				(anchor circle)
			)
			(primitives
				(gr_poly
					(pts
						(xy 0 -0.9017) (xy -0.03175 -0.89916) (xy -0.0635 -0.889) (xy -0.09144 -0.87376) (xy -0.11684 -0.85344)
						(xy -0.13716 -0.82804) (xy -0.1524 -0.8001) (xy -0.16256 -0.76835) (xy -0.1651 -0.7366) (xy -0.1651 -0.19685)
						(xy -0.17272 -0.18923) (xy -0.17907 -0.18034) (xy -0.18669 -0.17145) (xy -0.19177 -0.16256) (xy -0.19812 -0.15367)
						(xy -0.20828 -0.13335) (xy -0.21971 -0.10287) (xy -0.22225 -0.09271) (xy -0.22479 -0.08128) (xy -0.22606 -0.07112)
						(xy -0.2286 -0.05969) (xy -0.2286 -0.01651) (xy -0.22606 -0.00508) (xy -0.22479 0.00508) (xy -0.22225 0.01651)
						(xy -0.21971 0.02667) (xy -0.20828 0.05715) (xy -0.19812 0.07747) (xy -0.19177 0.08636) (xy -0.18669 0.09525)
						(xy -0.17907 0.10414) (xy -0.17272 0.11303) (xy -0.1651 0.12065) (xy -0.1651 0.7366) (xy -0.16256 0.76835)
						(xy -0.1524 0.8001) (xy -0.13716 0.82804) (xy -0.11684 0.85344) (xy -0.09144 0.87376) (xy -0.0635 0.889)
						(xy -0.03175 0.89916) (xy 0 0.9017) (xy 0.03175 0.89916) (xy 0.0635 0.889) (xy 0.09144 0.87376)
						(xy 0.11684 0.85344) (xy 0.13716 0.82804) (xy 0.1524 0.8001) (xy 0.16256 0.76835) (xy 0.1651 0.7366)
						(xy 0.1651 0.11938) (xy 0.17272 0.11176) (xy 0.19812 0.0762) (xy 0.2032 0.06604) (xy 0.20701 0.05715)
						(xy 0.21209 0.04699) (xy 0.2159 0.03683) (xy 0.21844 0.02667) (xy 0.22225 0.01524) (xy 0.22352 0.00508)
						(xy 0.22606 -0.00508) (xy 0.22733 -0.01651) (xy 0.22733 -0.02667) (xy 0.2286 -0.0381) (xy 0.22733 -0.04953)
						(xy 0.22733 -0.05969) (xy 0.22606 -0.07112) (xy 0.22352 -0.08128) (xy 0.22225 -0.09144) (xy 0.21844 -0.10287)
						(xy 0.2159 -0.11303) (xy 0.21209 -0.12319) (xy 0.20701 -0.13335) (xy 0.2032 -0.14224) (xy 0.19812 -0.1524)
						(xy 0.17272 -0.18796) (xy 0.1651 -0.19558) (xy 0.1651 -0.7366) (xy 0.16256 -0.76835) (xy 0.1524 -0.8001)
						(xy 0.13716 -0.82804) (xy 0.11684 -0.85344) (xy 0.09144 -0.87376) (xy 0.0635 -0.889) (xy 0.03175 -0.89916)
					)
					(width 0)
					(fill yes)
				)
			)
		)
		(pad "84" smd custom
			(at -4.350004 4.100068)
			(size 0.1143 0.1143)
			(layers "B.Cu" "B.Mask" "B.Paste")
			(net "DDR3_M_A_VREF_CA")
			(options
				(clearance outline)
				(anchor circle)
			)
			(primitives
				(gr_poly
					(pts
						(xy 0 -0.9017) (xy -0.03175 -0.89916) (xy -0.0635 -0.889) (xy -0.09144 -0.87376) (xy -0.11684 -0.85344)
						(xy -0.13716 -0.82804) (xy -0.1524 -0.8001) (xy -0.16256 -0.76835) (xy -0.1651 -0.7366) (xy -0.1651 -0.11938)
						(xy -0.17272 -0.11176) (xy -0.19812 -0.0762) (xy -0.2032 -0.06604) (xy -0.20701 -0.05715) (xy -0.21209 -0.04699)
						(xy -0.2159 -0.03683) (xy -0.21844 -0.02667) (xy -0.22225 -0.01524) (xy -0.22352 -0.00508) (xy -0.22606 0.00508)
						(xy -0.22733 0.01651) (xy -0.22733 0.02667) (xy -0.2286 0.0381) (xy -0.22733 0.04953) (xy -0.22733 0.05969)
						(xy -0.22606 0.07112) (xy -0.22352 0.08128) (xy -0.22225 0.09144) (xy -0.21844 0.10287) (xy -0.2159 0.11303)
						(xy -0.21209 0.12319) (xy -0.20701 0.13335) (xy -0.2032 0.14224) (xy -0.19812 0.1524) (xy -0.17272 0.18796)
						(xy -0.1651 0.19558) (xy -0.1651 0.7366) (xy -0.16256 0.76835) (xy -0.1524 0.8001) (xy -0.13716 0.82804)
						(xy -0.11684 0.85344) (xy -0.09144 0.87376) (xy -0.0635 0.889) (xy -0.03175 0.89916) (xy 0 0.9017)
						(xy 0.03175 0.89916) (xy 0.0635 0.889) (xy 0.09144 0.87376) (xy 0.11684 0.85344) (xy 0.13716 0.82804)
						(xy 0.1524 0.8001) (xy 0.16256 0.76835) (xy 0.1651 0.7366) (xy 0.1651 0.19685) (xy 0.17272 0.18923)
						(xy 0.17907 0.18034) (xy 0.18669 0.17145) (xy 0.19177 0.16256) (xy 0.19812 0.15367) (xy 0.20828 0.13335)
						(xy 0.21971 0.10287) (xy 0.22225 0.09271) (xy 0.22479 0.08128) (xy 0.22606 0.07112) (xy 0.2286 0.05969)
						(xy 0.2286 0.01651) (xy 0.22606 0.00508) (xy 0.22479 -0.00508) (xy 0.22225 -0.01651) (xy 0.21971 -0.02667)
						(xy 0.20828 -0.05715) (xy 0.19812 -0.07747) (xy 0.19177 -0.08636) (xy 0.18669 -0.09525) (xy 0.17907 -0.10414)
						(xy 0.17272 -0.11303) (xy 0.1651 -0.12065) (xy 0.1651 -0.7366) (xy 0.16256 -0.76835) (xy 0.1524 -0.8001)
						(xy 0.13716 -0.82804) (xy 0.11684 -0.85344) (xy 0.09144 -0.87376) (xy 0.0635 -0.889) (xy 0.03175 -0.89916)
					)
					(width 0)
					(fill yes)
				)
			)
		)
		(pad "85" smd custom
			(at -4.05003 -4.100068)
			(size 0.1143 0.1143)
			(layers "B.Cu" "B.Mask" "B.Paste")
			(net "PV_VDDR")
			(options
				(clearance outline)
				(anchor circle)
			)
			(primitives
				(gr_poly
					(pts
						(xy 0 -0.9017) (xy -0.03175 -0.89916) (xy -0.0635 -0.889) (xy -0.09144 -0.87376) (xy -0.11684 -0.85344)
						(xy -0.13716 -0.82804) (xy -0.1524 -0.8001) (xy -0.16256 -0.76835) (xy -0.1651 -0.7366) (xy -0.1651 -0.44958)
						(xy -0.17272 -0.44196) (xy -0.19812 -0.4064) (xy -0.2032 -0.39624) (xy -0.20701 -0.38735) (xy -0.21209 -0.37719)
						(xy -0.2159 -0.36703) (xy -0.21844 -0.35687) (xy -0.22225 -0.34544) (xy -0.22352 -0.33528) (xy -0.22606 -0.32512)
						(xy -0.22733 -0.31369) (xy -0.22733 -0.30353) (xy -0.2286 -0.2921) (xy -0.22733 -0.28067) (xy -0.22733 -0.27051)
						(xy -0.22606 -0.25908) (xy -0.22352 -0.24892) (xy -0.22225 -0.23876) (xy -0.21844 -0.22733) (xy -0.2159 -0.21717)
						(xy -0.21209 -0.20701) (xy -0.20701 -0.19685) (xy -0.2032 -0.18796) (xy -0.19812 -0.1778) (xy -0.17272 -0.14224)
						(xy -0.1651 -0.13462) (xy -0.1651 0.7366) (xy -0.16256 0.76835) (xy -0.1524 0.8001) (xy -0.13716 0.82804)
						(xy -0.11684 0.85344) (xy -0.09144 0.87376) (xy -0.0635 0.889) (xy -0.03175 0.89916) (xy 0 0.9017)
						(xy 0.03175 0.89916) (xy 0.0635 0.889) (xy 0.09144 0.87376) (xy 0.11684 0.85344) (xy 0.13716 0.82804)
						(xy 0.1524 0.8001) (xy 0.16256 0.76835) (xy 0.1651 0.7366) (xy 0.1651 -0.13462) (xy 0.17272 -0.14224)
						(xy 0.19812 -0.1778) (xy 0.2032 -0.18796) (xy 0.20701 -0.19685) (xy 0.21209 -0.20701) (xy 0.2159 -0.21717)
						(xy 0.21844 -0.22733) (xy 0.22225 -0.23876) (xy 0.22352 -0.24892) (xy 0.22606 -0.25908) (xy 0.22733 -0.27051)
						(xy 0.22733 -0.28067) (xy 0.2286 -0.2921) (xy 0.22733 -0.30353) (xy 0.22733 -0.31369) (xy 0.22606 -0.32512)
						(xy 0.22352 -0.33528) (xy 0.22225 -0.34544) (xy 0.21844 -0.35687) (xy 0.2159 -0.36703) (xy 0.21209 -0.37719)
						(xy 0.20701 -0.38735) (xy 0.2032 -0.39624) (xy 0.19812 -0.4064) (xy 0.17272 -0.44196) (xy 0.1651 -0.44958)
						(xy 0.1651 -0.7366) (xy 0.16256 -0.76835) (xy 0.1524 -0.8001) (xy 0.13716 -0.82804) (xy 0.11684 -0.85344)
						(xy 0.09144 -0.87376) (xy 0.0635 -0.889) (xy 0.03175 -0.89916)
					)
					(width 0)
					(fill yes)
				)
			)
		)
		(pad "86" smd custom
			(at -3.750056 4.100068)
			(size 0.1143 0.1143)
			(layers "B.Cu" "B.Mask" "B.Paste")
			(net "PV_VDDR")
			(options
				(clearance outline)
				(anchor circle)
			)
			(primitives
				(gr_poly
					(pts
						(xy 0 -0.9017) (xy -0.03175 -0.89916) (xy -0.0635 -0.889) (xy -0.09144 -0.87376) (xy -0.11684 -0.85344)
						(xy -0.13716 -0.82804) (xy -0.1524 -0.8001) (xy -0.16256 -0.76835) (xy -0.1651 -0.7366) (xy -0.1651 0.13462)
						(xy -0.17272 0.14224) (xy -0.19812 0.1778) (xy -0.2032 0.18796) (xy -0.20701 0.19685) (xy -0.21209 0.20701)
						(xy -0.2159 0.21717) (xy -0.21844 0.22733) (xy -0.22225 0.23876) (xy -0.22352 0.24892) (xy -0.22606 0.25908)
						(xy -0.22733 0.27051) (xy -0.22733 0.28067) (xy -0.2286 0.2921) (xy -0.22733 0.30353) (xy -0.22733 0.31369)
						(xy -0.22606 0.32512) (xy -0.22352 0.33528) (xy -0.22225 0.34544) (xy -0.21844 0.35687) (xy -0.2159 0.36703)
						(xy -0.21209 0.37719) (xy -0.20701 0.38735) (xy -0.2032 0.39624) (xy -0.19812 0.4064) (xy -0.17272 0.44196)
						(xy -0.1651 0.44958) (xy -0.1651 0.7366) (xy -0.16256 0.76835) (xy -0.1524 0.8001) (xy -0.13716 0.82804)
						(xy -0.11684 0.85344) (xy -0.09144 0.87376) (xy -0.0635 0.889) (xy -0.03175 0.89916) (xy 0 0.9017)
						(xy 0.03175 0.89916) (xy 0.0635 0.889) (xy 0.09144 0.87376) (xy 0.11684 0.85344) (xy 0.13716 0.82804)
						(xy 0.1524 0.8001) (xy 0.16256 0.76835) (xy 0.1651 0.7366) (xy 0.1651 0.44958) (xy 0.17272 0.44196)
						(xy 0.19812 0.4064) (xy 0.2032 0.39624) (xy 0.20701 0.38735) (xy 0.21209 0.37719) (xy 0.2159 0.36703)
						(xy 0.21844 0.35687) (xy 0.22225 0.34544) (xy 0.22352 0.33528) (xy 0.22606 0.32512) (xy 0.22733 0.31369)
						(xy 0.22733 0.30353) (xy 0.2286 0.2921) (xy 0.22733 0.28067) (xy 0.22733 0.27051) (xy 0.22606 0.25908)
						(xy 0.22352 0.24892) (xy 0.22225 0.23876) (xy 0.21844 0.22733) (xy 0.2159 0.21717) (xy 0.21209 0.20701)
						(xy 0.20701 0.19685) (xy 0.2032 0.18796) (xy 0.19812 0.1778) (xy 0.17272 0.14224) (xy 0.1651 0.13462)
						(xy 0.1651 -0.7366) (xy 0.16256 -0.76835) (xy 0.1524 -0.8001) (xy 0.13716 -0.82804) (xy 0.11684 -0.85344)
						(xy 0.09144 -0.87376) (xy 0.0635 -0.889) (xy 0.03175 -0.89916)
					)
					(width 0)
					(fill yes)
				)
			)
		)
		(pad "87" smd custom
			(at -3.450082 -4.100068)
			(size 0.1143 0.1143)
			(layers "B.Cu" "B.Mask" "B.Paste")
			(net "M_A_CKE0")
			(options
				(clearance outline)
				(anchor circle)
			)
			(primitives
				(gr_poly
					(pts
						(xy 0 -0.9017) (xy -0.03175 -0.89916) (xy -0.0635 -0.889) (xy -0.09144 -0.87376) (xy -0.11684 -0.85344)
						(xy -0.13716 -0.82804) (xy -0.1524 -0.8001) (xy -0.16256 -0.76835) (xy -0.1651 -0.7366) (xy -0.1651 -0.19685)
						(xy -0.17272 -0.18923) (xy -0.17907 -0.18034) (xy -0.18669 -0.17145) (xy -0.19177 -0.16256) (xy -0.19812 -0.15367)
						(xy -0.20828 -0.13335) (xy -0.21971 -0.10287) (xy -0.22225 -0.09271) (xy -0.22479 -0.08128) (xy -0.22606 -0.07112)
						(xy -0.2286 -0.05969) (xy -0.2286 -0.01651) (xy -0.22606 -0.00508) (xy -0.22479 0.00508) (xy -0.22225 0.01651)
						(xy -0.21971 0.02667) (xy -0.20828 0.05715) (xy -0.19812 0.07747) (xy -0.19177 0.08636) (xy -0.18669 0.09525)
						(xy -0.17907 0.10414) (xy -0.17272 0.11303) (xy -0.1651 0.12065) (xy -0.1651 0.7366) (xy -0.16256 0.76835)
						(xy -0.1524 0.8001) (xy -0.13716 0.82804) (xy -0.11684 0.85344) (xy -0.09144 0.87376) (xy -0.0635 0.889)
						(xy -0.03175 0.89916) (xy 0 0.9017) (xy 0.03175 0.89916) (xy 0.0635 0.889) (xy 0.09144 0.87376)
						(xy 0.11684 0.85344) (xy 0.13716 0.82804) (xy 0.1524 0.8001) (xy 0.16256 0.76835) (xy 0.1651 0.7366)
						(xy 0.1651 0.11938) (xy 0.17272 0.11176) (xy 0.19812 0.0762) (xy 0.2032 0.06604) (xy 0.20701 0.05715)
						(xy 0.21209 0.04699) (xy 0.2159 0.03683) (xy 0.21844 0.02667) (xy 0.22225 0.01524) (xy 0.22352 0.00508)
						(xy 0.22606 -0.00508) (xy 0.22733 -0.01651) (xy 0.22733 -0.02667) (xy 0.2286 -0.0381) (xy 0.22733 -0.04953)
						(xy 0.22733 -0.05969) (xy 0.22606 -0.07112) (xy 0.22352 -0.08128) (xy 0.22225 -0.09144) (xy 0.21844 -0.10287)
						(xy 0.2159 -0.11303) (xy 0.21209 -0.12319) (xy 0.20701 -0.13335) (xy 0.2032 -0.14224) (xy 0.19812 -0.1524)
						(xy 0.17272 -0.18796) (xy 0.1651 -0.19558) (xy 0.1651 -0.7366) (xy 0.16256 -0.76835) (xy 0.1524 -0.8001)
						(xy 0.13716 -0.82804) (xy 0.11684 -0.85344) (xy 0.09144 -0.87376) (xy 0.0635 -0.889) (xy 0.03175 -0.89916)
					)
					(width 0)
					(fill yes)
				)
			)
		)
		(pad "88" smd custom
			(at -3.150108 4.100068)
			(size 0.1143 0.1143)
			(layers "B.Cu" "B.Mask" "B.Paste")
			(net "M_A_MA15")
			(options
				(clearance outline)
				(anchor circle)
			)
			(primitives
				(gr_poly
					(pts
						(xy 0 -0.9017) (xy -0.03175 -0.89916) (xy -0.0635 -0.889) (xy -0.09144 -0.87376) (xy -0.11684 -0.85344)
						(xy -0.13716 -0.82804) (xy -0.1524 -0.8001) (xy -0.16256 -0.76835) (xy -0.1651 -0.7366) (xy -0.1651 -0.11938)
						(xy -0.17272 -0.11176) (xy -0.19812 -0.0762) (xy -0.2032 -0.06604) (xy -0.20701 -0.05715) (xy -0.21209 -0.04699)
						(xy -0.2159 -0.03683) (xy -0.21844 -0.02667) (xy -0.22225 -0.01524) (xy -0.22352 -0.00508) (xy -0.22606 0.00508)
						(xy -0.22733 0.01651) (xy -0.22733 0.02667) (xy -0.2286 0.0381) (xy -0.22733 0.04953) (xy -0.22733 0.05969)
						(xy -0.22606 0.07112) (xy -0.22352 0.08128) (xy -0.22225 0.09144) (xy -0.21844 0.10287) (xy -0.2159 0.11303)
						(xy -0.21209 0.12319) (xy -0.20701 0.13335) (xy -0.2032 0.14224) (xy -0.19812 0.1524) (xy -0.17272 0.18796)
						(xy -0.1651 0.19558) (xy -0.1651 0.7366) (xy -0.16256 0.76835) (xy -0.1524 0.8001) (xy -0.13716 0.82804)
						(xy -0.11684 0.85344) (xy -0.09144 0.87376) (xy -0.0635 0.889) (xy -0.03175 0.89916) (xy 0 0.9017)
						(xy 0.03175 0.89916) (xy 0.0635 0.889) (xy 0.09144 0.87376) (xy 0.11684 0.85344) (xy 0.13716 0.82804)
						(xy 0.1524 0.8001) (xy 0.16256 0.76835) (xy 0.1651 0.7366) (xy 0.1651 0.19685) (xy 0.17272 0.18923)
						(xy 0.17907 0.18034) (xy 0.18669 0.17145) (xy 0.19177 0.16256) (xy 0.19812 0.15367) (xy 0.20828 0.13335)
						(xy 0.21971 0.10287) (xy 0.22225 0.09271) (xy 0.22479 0.08128) (xy 0.22606 0.07112) (xy 0.2286 0.05969)
						(xy 0.2286 0.01651) (xy 0.22606 0.00508) (xy 0.22479 -0.00508) (xy 0.22225 -0.01651) (xy 0.21971 -0.02667)
						(xy 0.20828 -0.05715) (xy 0.19812 -0.07747) (xy 0.19177 -0.08636) (xy 0.18669 -0.09525) (xy 0.17907 -0.10414)
						(xy 0.17272 -0.11303) (xy 0.1651 -0.12065) (xy 0.1651 -0.7366) (xy 0.16256 -0.76835) (xy 0.1524 -0.8001)
						(xy 0.13716 -0.82804) (xy 0.11684 -0.85344) (xy 0.09144 -0.87376) (xy 0.0635 -0.889) (xy 0.03175 -0.89916)
					)
					(width 0)
					(fill yes)
				)
			)
		)
		(pad "89" smd custom
			(at -2.84988 -4.100068)
			(size 0.1143 0.1143)
			(layers "B.Cu" "B.Mask" "B.Paste")
			(net "M_A_CKE1")
			(options
				(clearance outline)
				(anchor circle)
			)
			(primitives
				(gr_poly
					(pts
						(xy 0 -0.9017) (xy -0.03175 -0.89916) (xy -0.0635 -0.889) (xy -0.09144 -0.87376) (xy -0.11684 -0.85344)
						(xy -0.13716 -0.82804) (xy -0.1524 -0.8001) (xy -0.16256 -0.76835) (xy -0.1651 -0.7366) (xy -0.1651 -0.44958)
						(xy -0.17272 -0.44196) (xy -0.19812 -0.4064) (xy -0.2032 -0.39624) (xy -0.20701 -0.38735) (xy -0.21209 -0.37719)
						(xy -0.2159 -0.36703) (xy -0.21844 -0.35687) (xy -0.22225 -0.34544) (xy -0.22352 -0.33528) (xy -0.22606 -0.32512)
						(xy -0.22733 -0.31369) (xy -0.22733 -0.30353) (xy -0.2286 -0.2921) (xy -0.22733 -0.28067) (xy -0.22733 -0.27051)
						(xy -0.22606 -0.25908) (xy -0.22352 -0.24892) (xy -0.22225 -0.23876) (xy -0.21844 -0.22733) (xy -0.2159 -0.21717)
						(xy -0.21209 -0.20701) (xy -0.20701 -0.19685) (xy -0.2032 -0.18796) (xy -0.19812 -0.1778) (xy -0.17272 -0.14224)
						(xy -0.1651 -0.13462) (xy -0.1651 0.7366) (xy -0.16256 0.76835) (xy -0.1524 0.8001) (xy -0.13716 0.82804)
						(xy -0.11684 0.85344) (xy -0.09144 0.87376) (xy -0.0635 0.889) (xy -0.03175 0.89916) (xy 0 0.9017)
						(xy 0.03175 0.89916) (xy 0.0635 0.889) (xy 0.09144 0.87376) (xy 0.11684 0.85344) (xy 0.13716 0.82804)
						(xy 0.1524 0.8001) (xy 0.16256 0.76835) (xy 0.1651 0.7366) (xy 0.1651 -0.13462) (xy 0.17272 -0.14224)
						(xy 0.19812 -0.1778) (xy 0.2032 -0.18796) (xy 0.20701 -0.19685) (xy 0.21209 -0.20701) (xy 0.2159 -0.21717)
						(xy 0.21844 -0.22733) (xy 0.22225 -0.23876) (xy 0.22352 -0.24892) (xy 0.22606 -0.25908) (xy 0.22733 -0.27051)
						(xy 0.22733 -0.28067) (xy 0.2286 -0.2921) (xy 0.22733 -0.30353) (xy 0.22733 -0.31369) (xy 0.22606 -0.32512)
						(xy 0.22352 -0.33528) (xy 0.22225 -0.34544) (xy 0.21844 -0.35687) (xy 0.2159 -0.36703) (xy 0.21209 -0.37719)
						(xy 0.20701 -0.38735) (xy 0.2032 -0.39624) (xy 0.19812 -0.4064) (xy 0.17272 -0.44196) (xy 0.1651 -0.44958)
						(xy 0.1651 -0.7366) (xy 0.16256 -0.76835) (xy 0.1524 -0.8001) (xy 0.13716 -0.82804) (xy 0.11684 -0.85344)
						(xy 0.09144 -0.87376) (xy 0.0635 -0.889) (xy 0.03175 -0.89916)
					)
					(width 0)
					(fill yes)
				)
			)
		)
		(pad "90" smd custom
			(at -2.549906 4.100068)
			(size 0.1143 0.1143)
			(layers "B.Cu" "B.Mask" "B.Paste")
			(net "M_A_MA14")
			(options
				(clearance outline)
				(anchor circle)
			)
			(primitives
				(gr_poly
					(pts
						(xy 0 -0.9017) (xy -0.03175 -0.89916) (xy -0.0635 -0.889) (xy -0.09144 -0.87376) (xy -0.11684 -0.85344)
						(xy -0.13716 -0.82804) (xy -0.1524 -0.8001) (xy -0.16256 -0.76835) (xy -0.1651 -0.7366) (xy -0.1651 0.13462)
						(xy -0.17272 0.14224) (xy -0.19812 0.1778) (xy -0.2032 0.18796) (xy -0.20701 0.19685) (xy -0.21209 0.20701)
						(xy -0.2159 0.21717) (xy -0.21844 0.22733) (xy -0.22225 0.23876) (xy -0.22352 0.24892) (xy -0.22606 0.25908)
						(xy -0.22733 0.27051) (xy -0.22733 0.28067) (xy -0.2286 0.2921) (xy -0.22733 0.30353) (xy -0.22733 0.31369)
						(xy -0.22606 0.32512) (xy -0.22352 0.33528) (xy -0.22225 0.34544) (xy -0.21844 0.35687) (xy -0.2159 0.36703)
						(xy -0.21209 0.37719) (xy -0.20701 0.38735) (xy -0.2032 0.39624) (xy -0.19812 0.4064) (xy -0.17272 0.44196)
						(xy -0.1651 0.44958) (xy -0.1651 0.7366) (xy -0.16256 0.76835) (xy -0.1524 0.8001) (xy -0.13716 0.82804)
						(xy -0.11684 0.85344) (xy -0.09144 0.87376) (xy -0.0635 0.889) (xy -0.03175 0.89916) (xy 0 0.9017)
						(xy 0.03175 0.89916) (xy 0.0635 0.889) (xy 0.09144 0.87376) (xy 0.11684 0.85344) (xy 0.13716 0.82804)
						(xy 0.1524 0.8001) (xy 0.16256 0.76835) (xy 0.1651 0.7366) (xy 0.1651 0.44958) (xy 0.17272 0.44196)
						(xy 0.19812 0.4064) (xy 0.2032 0.39624) (xy 0.20701 0.38735) (xy 0.21209 0.37719) (xy 0.2159 0.36703)
						(xy 0.21844 0.35687) (xy 0.22225 0.34544) (xy 0.22352 0.33528) (xy 0.22606 0.32512) (xy 0.22733 0.31369)
						(xy 0.22733 0.30353) (xy 0.2286 0.2921) (xy 0.22733 0.28067) (xy 0.22733 0.27051) (xy 0.22606 0.25908)
						(xy 0.22352 0.24892) (xy 0.22225 0.23876) (xy 0.21844 0.22733) (xy 0.2159 0.21717) (xy 0.21209 0.20701)
						(xy 0.20701 0.19685) (xy 0.2032 0.18796) (xy 0.19812 0.1778) (xy 0.17272 0.14224) (xy 0.1651 0.13462)
						(xy 0.1651 -0.7366) (xy 0.16256 -0.76835) (xy 0.1524 -0.8001) (xy 0.13716 -0.82804) (xy 0.11684 -0.85344)
						(xy 0.09144 -0.87376) (xy 0.0635 -0.889) (xy 0.03175 -0.89916)
					)
					(width 0)
					(fill yes)
				)
			)
		)
		(pad "91" smd custom
			(at -2.249932 -4.100068)
			(size 0.1143 0.1143)
			(layers "B.Cu" "B.Mask" "B.Paste")
			(net "M_A_BS2")
			(options
				(clearance outline)
				(anchor circle)
			)
			(primitives
				(gr_poly
					(pts
						(xy 0 -0.9017) (xy -0.03175 -0.89916) (xy -0.0635 -0.889) (xy -0.09144 -0.87376) (xy -0.11684 -0.85344)
						(xy -0.13716 -0.82804) (xy -0.1524 -0.8001) (xy -0.16256 -0.76835) (xy -0.1651 -0.7366) (xy -0.1651 -0.19685)
						(xy -0.17272 -0.18923) (xy -0.17907 -0.18034) (xy -0.18669 -0.17145) (xy -0.19177 -0.16256) (xy -0.19812 -0.15367)
						(xy -0.20828 -0.13335) (xy -0.21971 -0.10287) (xy -0.22225 -0.09271) (xy -0.22479 -0.08128) (xy -0.22606 -0.07112)
						(xy -0.2286 -0.05969) (xy -0.2286 -0.01651) (xy -0.22606 -0.00508) (xy -0.22479 0.00508) (xy -0.22225 0.01651)
						(xy -0.21971 0.02667) (xy -0.20828 0.05715) (xy -0.19812 0.07747) (xy -0.19177 0.08636) (xy -0.18669 0.09525)
						(xy -0.17907 0.10414) (xy -0.17272 0.11303) (xy -0.1651 0.12065) (xy -0.1651 0.7366) (xy -0.16256 0.76835)
						(xy -0.1524 0.8001) (xy -0.13716 0.82804) (xy -0.11684 0.85344) (xy -0.09144 0.87376) (xy -0.0635 0.889)
						(xy -0.03175 0.89916) (xy 0 0.9017) (xy 0.03175 0.89916) (xy 0.0635 0.889) (xy 0.09144 0.87376)
						(xy 0.11684 0.85344) (xy 0.13716 0.82804) (xy 0.1524 0.8001) (xy 0.16256 0.76835) (xy 0.1651 0.7366)
						(xy 0.1651 0.11938) (xy 0.17272 0.11176) (xy 0.19812 0.0762) (xy 0.2032 0.06604) (xy 0.20701 0.05715)
						(xy 0.21209 0.04699) (xy 0.2159 0.03683) (xy 0.21844 0.02667) (xy 0.22225 0.01524) (xy 0.22352 0.00508)
						(xy 0.22606 -0.00508) (xy 0.22733 -0.01651) (xy 0.22733 -0.02667) (xy 0.2286 -0.0381) (xy 0.22733 -0.04953)
						(xy 0.22733 -0.05969) (xy 0.22606 -0.07112) (xy 0.22352 -0.08128) (xy 0.22225 -0.09144) (xy 0.21844 -0.10287)
						(xy 0.2159 -0.11303) (xy 0.21209 -0.12319) (xy 0.20701 -0.13335) (xy 0.2032 -0.14224) (xy 0.19812 -0.1524)
						(xy 0.17272 -0.18796) (xy 0.1651 -0.19558) (xy 0.1651 -0.7366) (xy 0.16256 -0.76835) (xy 0.1524 -0.8001)
						(xy 0.13716 -0.82804) (xy 0.11684 -0.85344) (xy 0.09144 -0.87376) (xy 0.0635 -0.889) (xy 0.03175 -0.89916)
					)
					(width 0)
					(fill yes)
				)
			)
		)
		(pad "92" smd custom
			(at -1.949958 4.100068)
			(size 0.1143 0.1143)
			(layers "B.Cu" "B.Mask" "B.Paste")
			(net "M_A_MA9")
			(options
				(clearance outline)
				(anchor circle)
			)
			(primitives
				(gr_poly
					(pts
						(xy 0 -0.9017) (xy -0.03175 -0.89916) (xy -0.0635 -0.889) (xy -0.09144 -0.87376) (xy -0.11684 -0.85344)
						(xy -0.13716 -0.82804) (xy -0.1524 -0.8001) (xy -0.16256 -0.76835) (xy -0.1651 -0.7366) (xy -0.1651 -0.11938)
						(xy -0.17272 -0.11176) (xy -0.19812 -0.0762) (xy -0.2032 -0.06604) (xy -0.20701 -0.05715) (xy -0.21209 -0.04699)
						(xy -0.2159 -0.03683) (xy -0.21844 -0.02667) (xy -0.22225 -0.01524) (xy -0.22352 -0.00508) (xy -0.22606 0.00508)
						(xy -0.22733 0.01651) (xy -0.22733 0.02667) (xy -0.2286 0.0381) (xy -0.22733 0.04953) (xy -0.22733 0.05969)
						(xy -0.22606 0.07112) (xy -0.22352 0.08128) (xy -0.22225 0.09144) (xy -0.21844 0.10287) (xy -0.2159 0.11303)
						(xy -0.21209 0.12319) (xy -0.20701 0.13335) (xy -0.2032 0.14224) (xy -0.19812 0.1524) (xy -0.17272 0.18796)
						(xy -0.1651 0.19558) (xy -0.1651 0.7366) (xy -0.16256 0.76835) (xy -0.1524 0.8001) (xy -0.13716 0.82804)
						(xy -0.11684 0.85344) (xy -0.09144 0.87376) (xy -0.0635 0.889) (xy -0.03175 0.89916) (xy 0 0.9017)
						(xy 0.03175 0.89916) (xy 0.0635 0.889) (xy 0.09144 0.87376) (xy 0.11684 0.85344) (xy 0.13716 0.82804)
						(xy 0.1524 0.8001) (xy 0.16256 0.76835) (xy 0.1651 0.7366) (xy 0.1651 0.19685) (xy 0.17272 0.18923)
						(xy 0.17907 0.18034) (xy 0.18669 0.17145) (xy 0.19177 0.16256) (xy 0.19812 0.15367) (xy 0.20828 0.13335)
						(xy 0.21971 0.10287) (xy 0.22225 0.09271) (xy 0.22479 0.08128) (xy 0.22606 0.07112) (xy 0.2286 0.05969)
						(xy 0.2286 0.01651) (xy 0.22606 0.00508) (xy 0.22479 -0.00508) (xy 0.22225 -0.01651) (xy 0.21971 -0.02667)
						(xy 0.20828 -0.05715) (xy 0.19812 -0.07747) (xy 0.19177 -0.08636) (xy 0.18669 -0.09525) (xy 0.17907 -0.10414)
						(xy 0.17272 -0.11303) (xy 0.1651 -0.12065) (xy 0.1651 -0.7366) (xy 0.16256 -0.76835) (xy 0.1524 -0.8001)
						(xy 0.13716 -0.82804) (xy 0.11684 -0.85344) (xy 0.09144 -0.87376) (xy 0.0635 -0.889) (xy 0.03175 -0.89916)
					)
					(width 0)
					(fill yes)
				)
			)
		)
		(pad "93" smd custom
			(at -1.649984 -4.100068)
			(size 0.1143 0.1143)
			(layers "B.Cu" "B.Mask" "B.Paste")
			(net "PV_VDDR")
			(options
				(clearance outline)
				(anchor circle)
			)
			(primitives
				(gr_poly
					(pts
						(xy 0 -0.9017) (xy -0.03175 -0.89916) (xy -0.0635 -0.889) (xy -0.09144 -0.87376) (xy -0.11684 -0.85344)
						(xy -0.13716 -0.82804) (xy -0.1524 -0.8001) (xy -0.16256 -0.76835) (xy -0.1651 -0.7366) (xy -0.1651 -0.44958)
						(xy -0.17272 -0.44196) (xy -0.19812 -0.4064) (xy -0.2032 -0.39624) (xy -0.20701 -0.38735) (xy -0.21209 -0.37719)
						(xy -0.2159 -0.36703) (xy -0.21844 -0.35687) (xy -0.22225 -0.34544) (xy -0.22352 -0.33528) (xy -0.22606 -0.32512)
						(xy -0.22733 -0.31369) (xy -0.22733 -0.30353) (xy -0.2286 -0.2921) (xy -0.22733 -0.28067) (xy -0.22733 -0.27051)
						(xy -0.22606 -0.25908) (xy -0.22352 -0.24892) (xy -0.22225 -0.23876) (xy -0.21844 -0.22733) (xy -0.2159 -0.21717)
						(xy -0.21209 -0.20701) (xy -0.20701 -0.19685) (xy -0.2032 -0.18796) (xy -0.19812 -0.1778) (xy -0.17272 -0.14224)
						(xy -0.1651 -0.13462) (xy -0.1651 0.7366) (xy -0.16256 0.76835) (xy -0.1524 0.8001) (xy -0.13716 0.82804)
						(xy -0.11684 0.85344) (xy -0.09144 0.87376) (xy -0.0635 0.889) (xy -0.03175 0.89916) (xy 0 0.9017)
						(xy 0.03175 0.89916) (xy 0.0635 0.889) (xy 0.09144 0.87376) (xy 0.11684 0.85344) (xy 0.13716 0.82804)
						(xy 0.1524 0.8001) (xy 0.16256 0.76835) (xy 0.1651 0.7366) (xy 0.1651 -0.13462) (xy 0.17272 -0.14224)
						(xy 0.19812 -0.1778) (xy 0.2032 -0.18796) (xy 0.20701 -0.19685) (xy 0.21209 -0.20701) (xy 0.2159 -0.21717)
						(xy 0.21844 -0.22733) (xy 0.22225 -0.23876) (xy 0.22352 -0.24892) (xy 0.22606 -0.25908) (xy 0.22733 -0.27051)
						(xy 0.22733 -0.28067) (xy 0.2286 -0.2921) (xy 0.22733 -0.30353) (xy 0.22733 -0.31369) (xy 0.22606 -0.32512)
						(xy 0.22352 -0.33528) (xy 0.22225 -0.34544) (xy 0.21844 -0.35687) (xy 0.2159 -0.36703) (xy 0.21209 -0.37719)
						(xy 0.20701 -0.38735) (xy 0.2032 -0.39624) (xy 0.19812 -0.4064) (xy 0.17272 -0.44196) (xy 0.1651 -0.44958)
						(xy 0.1651 -0.7366) (xy 0.16256 -0.76835) (xy 0.1524 -0.8001) (xy 0.13716 -0.82804) (xy 0.11684 -0.85344)
						(xy 0.09144 -0.87376) (xy 0.0635 -0.889) (xy 0.03175 -0.89916)
					)
					(width 0)
					(fill yes)
				)
			)
		)
		(pad "94" smd custom
			(at -1.35001 4.100068)
			(size 0.1143 0.1143)
			(layers "B.Cu" "B.Mask" "B.Paste")
			(net "PV_VDDR")
			(options
				(clearance outline)
				(anchor circle)
			)
			(primitives
				(gr_poly
					(pts
						(xy 0 -0.9017) (xy -0.03175 -0.89916) (xy -0.0635 -0.889) (xy -0.09144 -0.87376) (xy -0.11684 -0.85344)
						(xy -0.13716 -0.82804) (xy -0.1524 -0.8001) (xy -0.16256 -0.76835) (xy -0.1651 -0.7366) (xy -0.1651 0.13462)
						(xy -0.17272 0.14224) (xy -0.19812 0.1778) (xy -0.2032 0.18796) (xy -0.20701 0.19685) (xy -0.21209 0.20701)
						(xy -0.2159 0.21717) (xy -0.21844 0.22733) (xy -0.22225 0.23876) (xy -0.22352 0.24892) (xy -0.22606 0.25908)
						(xy -0.22733 0.27051) (xy -0.22733 0.28067) (xy -0.2286 0.2921) (xy -0.22733 0.30353) (xy -0.22733 0.31369)
						(xy -0.22606 0.32512) (xy -0.22352 0.33528) (xy -0.22225 0.34544) (xy -0.21844 0.35687) (xy -0.2159 0.36703)
						(xy -0.21209 0.37719) (xy -0.20701 0.38735) (xy -0.2032 0.39624) (xy -0.19812 0.4064) (xy -0.17272 0.44196)
						(xy -0.1651 0.44958) (xy -0.1651 0.7366) (xy -0.16256 0.76835) (xy -0.1524 0.8001) (xy -0.13716 0.82804)
						(xy -0.11684 0.85344) (xy -0.09144 0.87376) (xy -0.0635 0.889) (xy -0.03175 0.89916) (xy 0 0.9017)
						(xy 0.03175 0.89916) (xy 0.0635 0.889) (xy 0.09144 0.87376) (xy 0.11684 0.85344) (xy 0.13716 0.82804)
						(xy 0.1524 0.8001) (xy 0.16256 0.76835) (xy 0.1651 0.7366) (xy 0.1651 0.44958) (xy 0.17272 0.44196)
						(xy 0.19812 0.4064) (xy 0.2032 0.39624) (xy 0.20701 0.38735) (xy 0.21209 0.37719) (xy 0.2159 0.36703)
						(xy 0.21844 0.35687) (xy 0.22225 0.34544) (xy 0.22352 0.33528) (xy 0.22606 0.32512) (xy 0.22733 0.31369)
						(xy 0.22733 0.30353) (xy 0.2286 0.2921) (xy 0.22733 0.28067) (xy 0.22733 0.27051) (xy 0.22606 0.25908)
						(xy 0.22352 0.24892) (xy 0.22225 0.23876) (xy 0.21844 0.22733) (xy 0.2159 0.21717) (xy 0.21209 0.20701)
						(xy 0.20701 0.19685) (xy 0.2032 0.18796) (xy 0.19812 0.1778) (xy 0.17272 0.14224) (xy 0.1651 0.13462)
						(xy 0.1651 -0.7366) (xy 0.16256 -0.76835) (xy 0.1524 -0.8001) (xy 0.13716 -0.82804) (xy 0.11684 -0.85344)
						(xy 0.09144 -0.87376) (xy 0.0635 -0.889) (xy 0.03175 -0.89916)
					)
					(width 0)
					(fill yes)
				)
			)
		)
		(pad "95" smd custom
			(at -1.050036 -4.100068)
			(size 0.1143 0.1143)
			(layers "B.Cu" "B.Mask" "B.Paste")
			(net "M_A_MA12")
			(options
				(clearance outline)
				(anchor circle)
			)
			(primitives
				(gr_poly
					(pts
						(xy 0 -0.9017) (xy -0.03175 -0.89916) (xy -0.0635 -0.889) (xy -0.09144 -0.87376) (xy -0.11684 -0.85344)
						(xy -0.13716 -0.82804) (xy -0.1524 -0.8001) (xy -0.16256 -0.76835) (xy -0.1651 -0.7366) (xy -0.1651 -0.19685)
						(xy -0.17272 -0.18923) (xy -0.17907 -0.18034) (xy -0.18669 -0.17145) (xy -0.19177 -0.16256) (xy -0.19812 -0.15367)
						(xy -0.20828 -0.13335) (xy -0.21971 -0.10287) (xy -0.22225 -0.09271) (xy -0.22479 -0.08128) (xy -0.22606 -0.07112)
						(xy -0.2286 -0.05969) (xy -0.2286 -0.01651) (xy -0.22606 -0.00508) (xy -0.22479 0.00508) (xy -0.22225 0.01651)
						(xy -0.21971 0.02667) (xy -0.20828 0.05715) (xy -0.19812 0.07747) (xy -0.19177 0.08636) (xy -0.18669 0.09525)
						(xy -0.17907 0.10414) (xy -0.17272 0.11303) (xy -0.1651 0.12065) (xy -0.1651 0.7366) (xy -0.16256 0.76835)
						(xy -0.1524 0.8001) (xy -0.13716 0.82804) (xy -0.11684 0.85344) (xy -0.09144 0.87376) (xy -0.0635 0.889)
						(xy -0.03175 0.89916) (xy 0 0.9017) (xy 0.03175 0.89916) (xy 0.0635 0.889) (xy 0.09144 0.87376)
						(xy 0.11684 0.85344) (xy 0.13716 0.82804) (xy 0.1524 0.8001) (xy 0.16256 0.76835) (xy 0.1651 0.7366)
						(xy 0.1651 0.11938) (xy 0.17272 0.11176) (xy 0.19812 0.0762) (xy 0.2032 0.06604) (xy 0.20701 0.05715)
						(xy 0.21209 0.04699) (xy 0.2159 0.03683) (xy 0.21844 0.02667) (xy 0.22225 0.01524) (xy 0.22352 0.00508)
						(xy 0.22606 -0.00508) (xy 0.22733 -0.01651) (xy 0.22733 -0.02667) (xy 0.2286 -0.0381) (xy 0.22733 -0.04953)
						(xy 0.22733 -0.05969) (xy 0.22606 -0.07112) (xy 0.22352 -0.08128) (xy 0.22225 -0.09144) (xy 0.21844 -0.10287)
						(xy 0.2159 -0.11303) (xy 0.21209 -0.12319) (xy 0.20701 -0.13335) (xy 0.2032 -0.14224) (xy 0.19812 -0.1524)
						(xy 0.17272 -0.18796) (xy 0.1651 -0.19558) (xy 0.1651 -0.7366) (xy 0.16256 -0.76835) (xy 0.1524 -0.8001)
						(xy 0.13716 -0.82804) (xy 0.11684 -0.85344) (xy 0.09144 -0.87376) (xy 0.0635 -0.889) (xy 0.03175 -0.89916)
					)
					(width 0)
					(fill yes)
				)
			)
		)
		(pad "96" smd custom
			(at -0.750062 4.100068)
			(size 0.1143 0.1143)
			(layers "B.Cu" "B.Mask" "B.Paste")
			(net "M_A_MA11")
			(options
				(clearance outline)
				(anchor circle)
			)
			(primitives
				(gr_poly
					(pts
						(xy 0 -0.9017) (xy -0.03175 -0.89916) (xy -0.0635 -0.889) (xy -0.09144 -0.87376) (xy -0.11684 -0.85344)
						(xy -0.13716 -0.82804) (xy -0.1524 -0.8001) (xy -0.16256 -0.76835) (xy -0.1651 -0.7366) (xy -0.1651 -0.11938)
						(xy -0.17272 -0.11176) (xy -0.19812 -0.0762) (xy -0.2032 -0.06604) (xy -0.20701 -0.05715) (xy -0.21209 -0.04699)
						(xy -0.2159 -0.03683) (xy -0.21844 -0.02667) (xy -0.22225 -0.01524) (xy -0.22352 -0.00508) (xy -0.22606 0.00508)
						(xy -0.22733 0.01651) (xy -0.22733 0.02667) (xy -0.2286 0.0381) (xy -0.22733 0.04953) (xy -0.22733 0.05969)
						(xy -0.22606 0.07112) (xy -0.22352 0.08128) (xy -0.22225 0.09144) (xy -0.21844 0.10287) (xy -0.2159 0.11303)
						(xy -0.21209 0.12319) (xy -0.20701 0.13335) (xy -0.2032 0.14224) (xy -0.19812 0.1524) (xy -0.17272 0.18796)
						(xy -0.1651 0.19558) (xy -0.1651 0.7366) (xy -0.16256 0.76835) (xy -0.1524 0.8001) (xy -0.13716 0.82804)
						(xy -0.11684 0.85344) (xy -0.09144 0.87376) (xy -0.0635 0.889) (xy -0.03175 0.89916) (xy 0 0.9017)
						(xy 0.03175 0.89916) (xy 0.0635 0.889) (xy 0.09144 0.87376) (xy 0.11684 0.85344) (xy 0.13716 0.82804)
						(xy 0.1524 0.8001) (xy 0.16256 0.76835) (xy 0.1651 0.7366) (xy 0.1651 0.19685) (xy 0.17272 0.18923)
						(xy 0.17907 0.18034) (xy 0.18669 0.17145) (xy 0.19177 0.16256) (xy 0.19812 0.15367) (xy 0.20828 0.13335)
						(xy 0.21971 0.10287) (xy 0.22225 0.09271) (xy 0.22479 0.08128) (xy 0.22606 0.07112) (xy 0.2286 0.05969)
						(xy 0.2286 0.01651) (xy 0.22606 0.00508) (xy 0.22479 -0.00508) (xy 0.22225 -0.01651) (xy 0.21971 -0.02667)
						(xy 0.20828 -0.05715) (xy 0.19812 -0.07747) (xy 0.19177 -0.08636) (xy 0.18669 -0.09525) (xy 0.17907 -0.10414)
						(xy 0.17272 -0.11303) (xy 0.1651 -0.12065) (xy 0.1651 -0.7366) (xy 0.16256 -0.76835) (xy 0.1524 -0.8001)
						(xy 0.13716 -0.82804) (xy 0.11684 -0.85344) (xy 0.09144 -0.87376) (xy 0.0635 -0.889) (xy 0.03175 -0.89916)
					)
					(width 0)
					(fill yes)
				)
			)
		)
		(pad "97" smd custom
			(at -0.450088 -4.100068)
			(size 0.1143 0.1143)
			(layers "B.Cu" "B.Mask" "B.Paste")
			(net "M_A_MA8")
			(options
				(clearance outline)
				(anchor circle)
			)
			(primitives
				(gr_poly
					(pts
						(xy 0 -0.9017) (xy -0.03175 -0.89916) (xy -0.0635 -0.889) (xy -0.09144 -0.87376) (xy -0.11684 -0.85344)
						(xy -0.13716 -0.82804) (xy -0.1524 -0.8001) (xy -0.16256 -0.76835) (xy -0.1651 -0.7366) (xy -0.1651 -0.44958)
						(xy -0.17272 -0.44196) (xy -0.19812 -0.4064) (xy -0.2032 -0.39624) (xy -0.20701 -0.38735) (xy -0.21209 -0.37719)
						(xy -0.2159 -0.36703) (xy -0.21844 -0.35687) (xy -0.22225 -0.34544) (xy -0.22352 -0.33528) (xy -0.22606 -0.32512)
						(xy -0.22733 -0.31369) (xy -0.22733 -0.30353) (xy -0.2286 -0.2921) (xy -0.22733 -0.28067) (xy -0.22733 -0.27051)
						(xy -0.22606 -0.25908) (xy -0.22352 -0.24892) (xy -0.22225 -0.23876) (xy -0.21844 -0.22733) (xy -0.2159 -0.21717)
						(xy -0.21209 -0.20701) (xy -0.20701 -0.19685) (xy -0.2032 -0.18796) (xy -0.19812 -0.1778) (xy -0.17272 -0.14224)
						(xy -0.1651 -0.13462) (xy -0.1651 0.7366) (xy -0.16256 0.76835) (xy -0.1524 0.8001) (xy -0.13716 0.82804)
						(xy -0.11684 0.85344) (xy -0.09144 0.87376) (xy -0.0635 0.889) (xy -0.03175 0.89916) (xy 0 0.9017)
						(xy 0.03175 0.89916) (xy 0.0635 0.889) (xy 0.09144 0.87376) (xy 0.11684 0.85344) (xy 0.13716 0.82804)
						(xy 0.1524 0.8001) (xy 0.16256 0.76835) (xy 0.1651 0.7366) (xy 0.1651 -0.13462) (xy 0.17272 -0.14224)
						(xy 0.19812 -0.1778) (xy 0.2032 -0.18796) (xy 0.20701 -0.19685) (xy 0.21209 -0.20701) (xy 0.2159 -0.21717)
						(xy 0.21844 -0.22733) (xy 0.22225 -0.23876) (xy 0.22352 -0.24892) (xy 0.22606 -0.25908) (xy 0.22733 -0.27051)
						(xy 0.22733 -0.28067) (xy 0.2286 -0.2921) (xy 0.22733 -0.30353) (xy 0.22733 -0.31369) (xy 0.22606 -0.32512)
						(xy 0.22352 -0.33528) (xy 0.22225 -0.34544) (xy 0.21844 -0.35687) (xy 0.2159 -0.36703) (xy 0.21209 -0.37719)
						(xy 0.20701 -0.38735) (xy 0.2032 -0.39624) (xy 0.19812 -0.4064) (xy 0.17272 -0.44196) (xy 0.1651 -0.44958)
						(xy 0.1651 -0.7366) (xy 0.16256 -0.76835) (xy 0.1524 -0.8001) (xy 0.13716 -0.82804) (xy 0.11684 -0.85344)
						(xy 0.09144 -0.87376) (xy 0.0635 -0.889) (xy 0.03175 -0.89916)
					)
					(width 0)
					(fill yes)
				)
			)
		)
		(pad "98" smd custom
			(at -0.150114 4.100068)
			(size 0.1143 0.1143)
			(layers "B.Cu" "B.Mask" "B.Paste")
			(net "M_A_MA7")
			(options
				(clearance outline)
				(anchor circle)
			)
			(primitives
				(gr_poly
					(pts
						(xy 0 -0.9017) (xy -0.03175 -0.89916) (xy -0.0635 -0.889) (xy -0.09144 -0.87376) (xy -0.11684 -0.85344)
						(xy -0.13716 -0.82804) (xy -0.1524 -0.8001) (xy -0.16256 -0.76835) (xy -0.1651 -0.7366) (xy -0.1651 0.13462)
						(xy -0.17272 0.14224) (xy -0.19812 0.1778) (xy -0.2032 0.18796) (xy -0.20701 0.19685) (xy -0.21209 0.20701)
						(xy -0.2159 0.21717) (xy -0.21844 0.22733) (xy -0.22225 0.23876) (xy -0.22352 0.24892) (xy -0.22606 0.25908)
						(xy -0.22733 0.27051) (xy -0.22733 0.28067) (xy -0.2286 0.2921) (xy -0.22733 0.30353) (xy -0.22733 0.31369)
						(xy -0.22606 0.32512) (xy -0.22352 0.33528) (xy -0.22225 0.34544) (xy -0.21844 0.35687) (xy -0.2159 0.36703)
						(xy -0.21209 0.37719) (xy -0.20701 0.38735) (xy -0.2032 0.39624) (xy -0.19812 0.4064) (xy -0.17272 0.44196)
						(xy -0.1651 0.44958) (xy -0.1651 0.7366) (xy -0.16256 0.76835) (xy -0.1524 0.8001) (xy -0.13716 0.82804)
						(xy -0.11684 0.85344) (xy -0.09144 0.87376) (xy -0.0635 0.889) (xy -0.03175 0.89916) (xy 0 0.9017)
						(xy 0.03175 0.89916) (xy 0.0635 0.889) (xy 0.09144 0.87376) (xy 0.11684 0.85344) (xy 0.13716 0.82804)
						(xy 0.1524 0.8001) (xy 0.16256 0.76835) (xy 0.1651 0.7366) (xy 0.1651 0.44958) (xy 0.17272 0.44196)
						(xy 0.19812 0.4064) (xy 0.2032 0.39624) (xy 0.20701 0.38735) (xy 0.21209 0.37719) (xy 0.2159 0.36703)
						(xy 0.21844 0.35687) (xy 0.22225 0.34544) (xy 0.22352 0.33528) (xy 0.22606 0.32512) (xy 0.22733 0.31369)
						(xy 0.22733 0.30353) (xy 0.2286 0.2921) (xy 0.22733 0.28067) (xy 0.22733 0.27051) (xy 0.22606 0.25908)
						(xy 0.22352 0.24892) (xy 0.22225 0.23876) (xy 0.21844 0.22733) (xy 0.2159 0.21717) (xy 0.21209 0.20701)
						(xy 0.20701 0.19685) (xy 0.2032 0.18796) (xy 0.19812 0.1778) (xy 0.17272 0.14224) (xy 0.1651 0.13462)
						(xy 0.1651 -0.7366) (xy 0.16256 -0.76835) (xy 0.1524 -0.8001) (xy 0.13716 -0.82804) (xy 0.11684 -0.85344)
						(xy 0.09144 -0.87376) (xy 0.0635 -0.889) (xy 0.03175 -0.89916)
					)
					(width 0)
					(fill yes)
				)
			)
		)
		(pad "99" smd custom
			(at 0.150114 -4.100068)
			(size 0.1143 0.1143)
			(layers "B.Cu" "B.Mask" "B.Paste")
			(net "M_A_MA5")
			(options
				(clearance outline)
				(anchor circle)
			)
			(primitives
				(gr_poly
					(pts
						(xy 0 -0.9017) (xy -0.03175 -0.89916) (xy -0.0635 -0.889) (xy -0.09144 -0.87376) (xy -0.11684 -0.85344)
						(xy -0.13716 -0.82804) (xy -0.1524 -0.8001) (xy -0.16256 -0.76835) (xy -0.1651 -0.7366) (xy -0.1651 -0.19685)
						(xy -0.17272 -0.18923) (xy -0.17907 -0.18034) (xy -0.18669 -0.17145) (xy -0.19177 -0.16256) (xy -0.19812 -0.15367)
						(xy -0.20828 -0.13335) (xy -0.21971 -0.10287) (xy -0.22225 -0.09271) (xy -0.22479 -0.08128) (xy -0.22606 -0.07112)
						(xy -0.2286 -0.05969) (xy -0.2286 -0.01651) (xy -0.22606 -0.00508) (xy -0.22479 0.00508) (xy -0.22225 0.01651)
						(xy -0.21971 0.02667) (xy -0.20828 0.05715) (xy -0.19812 0.07747) (xy -0.19177 0.08636) (xy -0.18669 0.09525)
						(xy -0.17907 0.10414) (xy -0.17272 0.11303) (xy -0.1651 0.12065) (xy -0.1651 0.7366) (xy -0.16256 0.76835)
						(xy -0.1524 0.8001) (xy -0.13716 0.82804) (xy -0.11684 0.85344) (xy -0.09144 0.87376) (xy -0.0635 0.889)
						(xy -0.03175 0.89916) (xy 0 0.9017) (xy 0.03175 0.89916) (xy 0.0635 0.889) (xy 0.09144 0.87376)
						(xy 0.11684 0.85344) (xy 0.13716 0.82804) (xy 0.1524 0.8001) (xy 0.16256 0.76835) (xy 0.1651 0.7366)
						(xy 0.1651 0.11938) (xy 0.17272 0.11176) (xy 0.19812 0.0762) (xy 0.2032 0.06604) (xy 0.20701 0.05715)
						(xy 0.21209 0.04699) (xy 0.2159 0.03683) (xy 0.21844 0.02667) (xy 0.22225 0.01524) (xy 0.22352 0.00508)
						(xy 0.22606 -0.00508) (xy 0.22733 -0.01651) (xy 0.22733 -0.02667) (xy 0.2286 -0.0381) (xy 0.22733 -0.04953)
						(xy 0.22733 -0.05969) (xy 0.22606 -0.07112) (xy 0.22352 -0.08128) (xy 0.22225 -0.09144) (xy 0.21844 -0.10287)
						(xy 0.2159 -0.11303) (xy 0.21209 -0.12319) (xy 0.20701 -0.13335) (xy 0.2032 -0.14224) (xy 0.19812 -0.1524)
						(xy 0.17272 -0.18796) (xy 0.1651 -0.19558) (xy 0.1651 -0.7366) (xy 0.16256 -0.76835) (xy 0.1524 -0.8001)
						(xy 0.13716 -0.82804) (xy 0.11684 -0.85344) (xy 0.09144 -0.87376) (xy 0.0635 -0.889) (xy 0.03175 -0.89916)
					)
					(width 0)
					(fill yes)
				)
			)
		)
		(pad "100" smd custom
			(at 0.450088 4.100068)
			(size 0.1143 0.1143)
			(layers "B.Cu" "B.Mask" "B.Paste")
			(net "M_A_MA6")
			(options
				(clearance outline)
				(anchor circle)
			)
			(primitives
				(gr_poly
					(pts
						(xy 0 -0.9017) (xy -0.03175 -0.89916) (xy -0.0635 -0.889) (xy -0.09144 -0.87376) (xy -0.11684 -0.85344)
						(xy -0.13716 -0.82804) (xy -0.1524 -0.8001) (xy -0.16256 -0.76835) (xy -0.1651 -0.7366) (xy -0.1651 -0.11938)
						(xy -0.17272 -0.11176) (xy -0.19812 -0.0762) (xy -0.2032 -0.06604) (xy -0.20701 -0.05715) (xy -0.21209 -0.04699)
						(xy -0.2159 -0.03683) (xy -0.21844 -0.02667) (xy -0.22225 -0.01524) (xy -0.22352 -0.00508) (xy -0.22606 0.00508)
						(xy -0.22733 0.01651) (xy -0.22733 0.02667) (xy -0.2286 0.0381) (xy -0.22733 0.04953) (xy -0.22733 0.05969)
						(xy -0.22606 0.07112) (xy -0.22352 0.08128) (xy -0.22225 0.09144) (xy -0.21844 0.10287) (xy -0.2159 0.11303)
						(xy -0.21209 0.12319) (xy -0.20701 0.13335) (xy -0.2032 0.14224) (xy -0.19812 0.1524) (xy -0.17272 0.18796)
						(xy -0.1651 0.19558) (xy -0.1651 0.7366) (xy -0.16256 0.76835) (xy -0.1524 0.8001) (xy -0.13716 0.82804)
						(xy -0.11684 0.85344) (xy -0.09144 0.87376) (xy -0.0635 0.889) (xy -0.03175 0.89916) (xy 0 0.9017)
						(xy 0.03175 0.89916) (xy 0.0635 0.889) (xy 0.09144 0.87376) (xy 0.11684 0.85344) (xy 0.13716 0.82804)
						(xy 0.1524 0.8001) (xy 0.16256 0.76835) (xy 0.1651 0.7366) (xy 0.1651 0.19685) (xy 0.17272 0.18923)
						(xy 0.17907 0.18034) (xy 0.18669 0.17145) (xy 0.19177 0.16256) (xy 0.19812 0.15367) (xy 0.20828 0.13335)
						(xy 0.21971 0.10287) (xy 0.22225 0.09271) (xy 0.22479 0.08128) (xy 0.22606 0.07112) (xy 0.2286 0.05969)
						(xy 0.2286 0.01651) (xy 0.22606 0.00508) (xy 0.22479 -0.00508) (xy 0.22225 -0.01651) (xy 0.21971 -0.02667)
						(xy 0.20828 -0.05715) (xy 0.19812 -0.07747) (xy 0.19177 -0.08636) (xy 0.18669 -0.09525) (xy 0.17907 -0.10414)
						(xy 0.17272 -0.11303) (xy 0.1651 -0.12065) (xy 0.1651 -0.7366) (xy 0.16256 -0.76835) (xy 0.1524 -0.8001)
						(xy 0.13716 -0.82804) (xy 0.11684 -0.85344) (xy 0.09144 -0.87376) (xy 0.0635 -0.889) (xy 0.03175 -0.89916)
					)
					(width 0)
					(fill yes)
				)
			)
		)
		(pad "101" smd custom
			(at 0.750062 -4.100068)
			(size 0.1143 0.1143)
			(layers "B.Cu" "B.Mask" "B.Paste")
			(net "PV_VDDR")
			(options
				(clearance outline)
				(anchor circle)
			)
			(primitives
				(gr_poly
					(pts
						(xy 0 -0.9017) (xy -0.03175 -0.89916) (xy -0.0635 -0.889) (xy -0.09144 -0.87376) (xy -0.11684 -0.85344)
						(xy -0.13716 -0.82804) (xy -0.1524 -0.8001) (xy -0.16256 -0.76835) (xy -0.1651 -0.7366) (xy -0.1651 -0.44958)
						(xy -0.17272 -0.44196) (xy -0.19812 -0.4064) (xy -0.2032 -0.39624) (xy -0.20701 -0.38735) (xy -0.21209 -0.37719)
						(xy -0.2159 -0.36703) (xy -0.21844 -0.35687) (xy -0.22225 -0.34544) (xy -0.22352 -0.33528) (xy -0.22606 -0.32512)
						(xy -0.22733 -0.31369) (xy -0.22733 -0.30353) (xy -0.2286 -0.2921) (xy -0.22733 -0.28067) (xy -0.22733 -0.27051)
						(xy -0.22606 -0.25908) (xy -0.22352 -0.24892) (xy -0.22225 -0.23876) (xy -0.21844 -0.22733) (xy -0.2159 -0.21717)
						(xy -0.21209 -0.20701) (xy -0.20701 -0.19685) (xy -0.2032 -0.18796) (xy -0.19812 -0.1778) (xy -0.17272 -0.14224)
						(xy -0.1651 -0.13462) (xy -0.1651 0.7366) (xy -0.16256 0.76835) (xy -0.1524 0.8001) (xy -0.13716 0.82804)
						(xy -0.11684 0.85344) (xy -0.09144 0.87376) (xy -0.0635 0.889) (xy -0.03175 0.89916) (xy 0 0.9017)
						(xy 0.03175 0.89916) (xy 0.0635 0.889) (xy 0.09144 0.87376) (xy 0.11684 0.85344) (xy 0.13716 0.82804)
						(xy 0.1524 0.8001) (xy 0.16256 0.76835) (xy 0.1651 0.7366) (xy 0.1651 -0.13462) (xy 0.17272 -0.14224)
						(xy 0.19812 -0.1778) (xy 0.2032 -0.18796) (xy 0.20701 -0.19685) (xy 0.21209 -0.20701) (xy 0.2159 -0.21717)
						(xy 0.21844 -0.22733) (xy 0.22225 -0.23876) (xy 0.22352 -0.24892) (xy 0.22606 -0.25908) (xy 0.22733 -0.27051)
						(xy 0.22733 -0.28067) (xy 0.2286 -0.2921) (xy 0.22733 -0.30353) (xy 0.22733 -0.31369) (xy 0.22606 -0.32512)
						(xy 0.22352 -0.33528) (xy 0.22225 -0.34544) (xy 0.21844 -0.35687) (xy 0.2159 -0.36703) (xy 0.21209 -0.37719)
						(xy 0.20701 -0.38735) (xy 0.2032 -0.39624) (xy 0.19812 -0.4064) (xy 0.17272 -0.44196) (xy 0.1651 -0.44958)
						(xy 0.1651 -0.7366) (xy 0.16256 -0.76835) (xy 0.1524 -0.8001) (xy 0.13716 -0.82804) (xy 0.11684 -0.85344)
						(xy 0.09144 -0.87376) (xy 0.0635 -0.889) (xy 0.03175 -0.89916)
					)
					(width 0)
					(fill yes)
				)
			)
		)
		(pad "102" smd custom
			(at 1.050036 4.100068)
			(size 0.1143 0.1143)
			(layers "B.Cu" "B.Mask" "B.Paste")
			(net "PV_VDDR")
			(options
				(clearance outline)
				(anchor circle)
			)
			(primitives
				(gr_poly
					(pts
						(xy 0 -0.9017) (xy -0.03175 -0.89916) (xy -0.0635 -0.889) (xy -0.09144 -0.87376) (xy -0.11684 -0.85344)
						(xy -0.13716 -0.82804) (xy -0.1524 -0.8001) (xy -0.16256 -0.76835) (xy -0.1651 -0.7366) (xy -0.1651 0.13462)
						(xy -0.17272 0.14224) (xy -0.19812 0.1778) (xy -0.2032 0.18796) (xy -0.20701 0.19685) (xy -0.21209 0.20701)
						(xy -0.2159 0.21717) (xy -0.21844 0.22733) (xy -0.22225 0.23876) (xy -0.22352 0.24892) (xy -0.22606 0.25908)
						(xy -0.22733 0.27051) (xy -0.22733 0.28067) (xy -0.2286 0.2921) (xy -0.22733 0.30353) (xy -0.22733 0.31369)
						(xy -0.22606 0.32512) (xy -0.22352 0.33528) (xy -0.22225 0.34544) (xy -0.21844 0.35687) (xy -0.2159 0.36703)
						(xy -0.21209 0.37719) (xy -0.20701 0.38735) (xy -0.2032 0.39624) (xy -0.19812 0.4064) (xy -0.17272 0.44196)
						(xy -0.1651 0.44958) (xy -0.1651 0.7366) (xy -0.16256 0.76835) (xy -0.1524 0.8001) (xy -0.13716 0.82804)
						(xy -0.11684 0.85344) (xy -0.09144 0.87376) (xy -0.0635 0.889) (xy -0.03175 0.89916) (xy 0 0.9017)
						(xy 0.03175 0.89916) (xy 0.0635 0.889) (xy 0.09144 0.87376) (xy 0.11684 0.85344) (xy 0.13716 0.82804)
						(xy 0.1524 0.8001) (xy 0.16256 0.76835) (xy 0.1651 0.7366) (xy 0.1651 0.44958) (xy 0.17272 0.44196)
						(xy 0.19812 0.4064) (xy 0.2032 0.39624) (xy 0.20701 0.38735) (xy 0.21209 0.37719) (xy 0.2159 0.36703)
						(xy 0.21844 0.35687) (xy 0.22225 0.34544) (xy 0.22352 0.33528) (xy 0.22606 0.32512) (xy 0.22733 0.31369)
						(xy 0.22733 0.30353) (xy 0.2286 0.2921) (xy 0.22733 0.28067) (xy 0.22733 0.27051) (xy 0.22606 0.25908)
						(xy 0.22352 0.24892) (xy 0.22225 0.23876) (xy 0.21844 0.22733) (xy 0.2159 0.21717) (xy 0.21209 0.20701)
						(xy 0.20701 0.19685) (xy 0.2032 0.18796) (xy 0.19812 0.1778) (xy 0.17272 0.14224) (xy 0.1651 0.13462)
						(xy 0.1651 -0.7366) (xy 0.16256 -0.76835) (xy 0.1524 -0.8001) (xy 0.13716 -0.82804) (xy 0.11684 -0.85344)
						(xy 0.09144 -0.87376) (xy 0.0635 -0.889) (xy 0.03175 -0.89916)
					)
					(width 0)
					(fill yes)
				)
			)
		)
		(pad "103" smd custom
			(at 1.35001 -4.100068)
			(size 0.1143 0.1143)
			(layers "B.Cu" "B.Mask" "B.Paste")
			(net "M_A_MA3")
			(options
				(clearance outline)
				(anchor circle)
			)
			(primitives
				(gr_poly
					(pts
						(xy 0 -0.9017) (xy -0.03175 -0.89916) (xy -0.0635 -0.889) (xy -0.09144 -0.87376) (xy -0.11684 -0.85344)
						(xy -0.13716 -0.82804) (xy -0.1524 -0.8001) (xy -0.16256 -0.76835) (xy -0.1651 -0.7366) (xy -0.1651 -0.19685)
						(xy -0.17272 -0.18923) (xy -0.17907 -0.18034) (xy -0.18669 -0.17145) (xy -0.19177 -0.16256) (xy -0.19812 -0.15367)
						(xy -0.20828 -0.13335) (xy -0.21971 -0.10287) (xy -0.22225 -0.09271) (xy -0.22479 -0.08128) (xy -0.22606 -0.07112)
						(xy -0.2286 -0.05969) (xy -0.2286 -0.01651) (xy -0.22606 -0.00508) (xy -0.22479 0.00508) (xy -0.22225 0.01651)
						(xy -0.21971 0.02667) (xy -0.20828 0.05715) (xy -0.19812 0.07747) (xy -0.19177 0.08636) (xy -0.18669 0.09525)
						(xy -0.17907 0.10414) (xy -0.17272 0.11303) (xy -0.1651 0.12065) (xy -0.1651 0.7366) (xy -0.16256 0.76835)
						(xy -0.1524 0.8001) (xy -0.13716 0.82804) (xy -0.11684 0.85344) (xy -0.09144 0.87376) (xy -0.0635 0.889)
						(xy -0.03175 0.89916) (xy 0 0.9017) (xy 0.03175 0.89916) (xy 0.0635 0.889) (xy 0.09144 0.87376)
						(xy 0.11684 0.85344) (xy 0.13716 0.82804) (xy 0.1524 0.8001) (xy 0.16256 0.76835) (xy 0.1651 0.7366)
						(xy 0.1651 0.11938) (xy 0.17272 0.11176) (xy 0.19812 0.0762) (xy 0.2032 0.06604) (xy 0.20701 0.05715)
						(xy 0.21209 0.04699) (xy 0.2159 0.03683) (xy 0.21844 0.02667) (xy 0.22225 0.01524) (xy 0.22352 0.00508)
						(xy 0.22606 -0.00508) (xy 0.22733 -0.01651) (xy 0.22733 -0.02667) (xy 0.2286 -0.0381) (xy 0.22733 -0.04953)
						(xy 0.22733 -0.05969) (xy 0.22606 -0.07112) (xy 0.22352 -0.08128) (xy 0.22225 -0.09144) (xy 0.21844 -0.10287)
						(xy 0.2159 -0.11303) (xy 0.21209 -0.12319) (xy 0.20701 -0.13335) (xy 0.2032 -0.14224) (xy 0.19812 -0.1524)
						(xy 0.17272 -0.18796) (xy 0.1651 -0.19558) (xy 0.1651 -0.7366) (xy 0.16256 -0.76835) (xy 0.1524 -0.8001)
						(xy 0.13716 -0.82804) (xy 0.11684 -0.85344) (xy 0.09144 -0.87376) (xy 0.0635 -0.889) (xy 0.03175 -0.89916)
					)
					(width 0)
					(fill yes)
				)
			)
		)
		(pad "104" smd custom
			(at 1.649984 4.100068)
			(size 0.1143 0.1143)
			(layers "B.Cu" "B.Mask" "B.Paste")
			(net "M_A_MA4")
			(options
				(clearance outline)
				(anchor circle)
			)
			(primitives
				(gr_poly
					(pts
						(xy 0 -0.9017) (xy -0.03175 -0.89916) (xy -0.0635 -0.889) (xy -0.09144 -0.87376) (xy -0.11684 -0.85344)
						(xy -0.13716 -0.82804) (xy -0.1524 -0.8001) (xy -0.16256 -0.76835) (xy -0.1651 -0.7366) (xy -0.1651 -0.11938)
						(xy -0.17272 -0.11176) (xy -0.19812 -0.0762) (xy -0.2032 -0.06604) (xy -0.20701 -0.05715) (xy -0.21209 -0.04699)
						(xy -0.2159 -0.03683) (xy -0.21844 -0.02667) (xy -0.22225 -0.01524) (xy -0.22352 -0.00508) (xy -0.22606 0.00508)
						(xy -0.22733 0.01651) (xy -0.22733 0.02667) (xy -0.2286 0.0381) (xy -0.22733 0.04953) (xy -0.22733 0.05969)
						(xy -0.22606 0.07112) (xy -0.22352 0.08128) (xy -0.22225 0.09144) (xy -0.21844 0.10287) (xy -0.2159 0.11303)
						(xy -0.21209 0.12319) (xy -0.20701 0.13335) (xy -0.2032 0.14224) (xy -0.19812 0.1524) (xy -0.17272 0.18796)
						(xy -0.1651 0.19558) (xy -0.1651 0.7366) (xy -0.16256 0.76835) (xy -0.1524 0.8001) (xy -0.13716 0.82804)
						(xy -0.11684 0.85344) (xy -0.09144 0.87376) (xy -0.0635 0.889) (xy -0.03175 0.89916) (xy 0 0.9017)
						(xy 0.03175 0.89916) (xy 0.0635 0.889) (xy 0.09144 0.87376) (xy 0.11684 0.85344) (xy 0.13716 0.82804)
						(xy 0.1524 0.8001) (xy 0.16256 0.76835) (xy 0.1651 0.7366) (xy 0.1651 0.19685) (xy 0.17272 0.18923)
						(xy 0.17907 0.18034) (xy 0.18669 0.17145) (xy 0.19177 0.16256) (xy 0.19812 0.15367) (xy 0.20828 0.13335)
						(xy 0.21971 0.10287) (xy 0.22225 0.09271) (xy 0.22479 0.08128) (xy 0.22606 0.07112) (xy 0.2286 0.05969)
						(xy 0.2286 0.01651) (xy 0.22606 0.00508) (xy 0.22479 -0.00508) (xy 0.22225 -0.01651) (xy 0.21971 -0.02667)
						(xy 0.20828 -0.05715) (xy 0.19812 -0.07747) (xy 0.19177 -0.08636) (xy 0.18669 -0.09525) (xy 0.17907 -0.10414)
						(xy 0.17272 -0.11303) (xy 0.1651 -0.12065) (xy 0.1651 -0.7366) (xy 0.16256 -0.76835) (xy 0.1524 -0.8001)
						(xy 0.13716 -0.82804) (xy 0.11684 -0.85344) (xy 0.09144 -0.87376) (xy 0.0635 -0.889) (xy 0.03175 -0.89916)
					)
					(width 0)
					(fill yes)
				)
			)
		)
		(pad "105" smd custom
			(at 1.949958 -4.100068)
			(size 0.1143 0.1143)
			(layers "B.Cu" "B.Mask" "B.Paste")
			(net "M_A_MA1")
			(options
				(clearance outline)
				(anchor circle)
			)
			(primitives
				(gr_poly
					(pts
						(xy 0 -0.9017) (xy -0.03175 -0.89916) (xy -0.0635 -0.889) (xy -0.09144 -0.87376) (xy -0.11684 -0.85344)
						(xy -0.13716 -0.82804) (xy -0.1524 -0.8001) (xy -0.16256 -0.76835) (xy -0.1651 -0.7366) (xy -0.1651 -0.44958)
						(xy -0.17272 -0.44196) (xy -0.19812 -0.4064) (xy -0.2032 -0.39624) (xy -0.20701 -0.38735) (xy -0.21209 -0.37719)
						(xy -0.2159 -0.36703) (xy -0.21844 -0.35687) (xy -0.22225 -0.34544) (xy -0.22352 -0.33528) (xy -0.22606 -0.32512)
						(xy -0.22733 -0.31369) (xy -0.22733 -0.30353) (xy -0.2286 -0.2921) (xy -0.22733 -0.28067) (xy -0.22733 -0.27051)
						(xy -0.22606 -0.25908) (xy -0.22352 -0.24892) (xy -0.22225 -0.23876) (xy -0.21844 -0.22733) (xy -0.2159 -0.21717)
						(xy -0.21209 -0.20701) (xy -0.20701 -0.19685) (xy -0.2032 -0.18796) (xy -0.19812 -0.1778) (xy -0.17272 -0.14224)
						(xy -0.1651 -0.13462) (xy -0.1651 0.7366) (xy -0.16256 0.76835) (xy -0.1524 0.8001) (xy -0.13716 0.82804)
						(xy -0.11684 0.85344) (xy -0.09144 0.87376) (xy -0.0635 0.889) (xy -0.03175 0.89916) (xy 0 0.9017)
						(xy 0.03175 0.89916) (xy 0.0635 0.889) (xy 0.09144 0.87376) (xy 0.11684 0.85344) (xy 0.13716 0.82804)
						(xy 0.1524 0.8001) (xy 0.16256 0.76835) (xy 0.1651 0.7366) (xy 0.1651 -0.13462) (xy 0.17272 -0.14224)
						(xy 0.19812 -0.1778) (xy 0.2032 -0.18796) (xy 0.20701 -0.19685) (xy 0.21209 -0.20701) (xy 0.2159 -0.21717)
						(xy 0.21844 -0.22733) (xy 0.22225 -0.23876) (xy 0.22352 -0.24892) (xy 0.22606 -0.25908) (xy 0.22733 -0.27051)
						(xy 0.22733 -0.28067) (xy 0.2286 -0.2921) (xy 0.22733 -0.30353) (xy 0.22733 -0.31369) (xy 0.22606 -0.32512)
						(xy 0.22352 -0.33528) (xy 0.22225 -0.34544) (xy 0.21844 -0.35687) (xy 0.2159 -0.36703) (xy 0.21209 -0.37719)
						(xy 0.20701 -0.38735) (xy 0.2032 -0.39624) (xy 0.19812 -0.4064) (xy 0.17272 -0.44196) (xy 0.1651 -0.44958)
						(xy 0.1651 -0.7366) (xy 0.16256 -0.76835) (xy 0.1524 -0.8001) (xy 0.13716 -0.82804) (xy 0.11684 -0.85344)
						(xy 0.09144 -0.87376) (xy 0.0635 -0.889) (xy 0.03175 -0.89916)
					)
					(width 0)
					(fill yes)
				)
			)
		)
		(pad "106" smd custom
			(at 2.249932 4.100068)
			(size 0.1143 0.1143)
			(layers "B.Cu" "B.Mask" "B.Paste")
			(net "M_A_MA2")
			(options
				(clearance outline)
				(anchor circle)
			)
			(primitives
				(gr_poly
					(pts
						(xy 0 -0.9017) (xy -0.03175 -0.89916) (xy -0.0635 -0.889) (xy -0.09144 -0.87376) (xy -0.11684 -0.85344)
						(xy -0.13716 -0.82804) (xy -0.1524 -0.8001) (xy -0.16256 -0.76835) (xy -0.1651 -0.7366) (xy -0.1651 0.13462)
						(xy -0.17272 0.14224) (xy -0.19812 0.1778) (xy -0.2032 0.18796) (xy -0.20701 0.19685) (xy -0.21209 0.20701)
						(xy -0.2159 0.21717) (xy -0.21844 0.22733) (xy -0.22225 0.23876) (xy -0.22352 0.24892) (xy -0.22606 0.25908)
						(xy -0.22733 0.27051) (xy -0.22733 0.28067) (xy -0.2286 0.2921) (xy -0.22733 0.30353) (xy -0.22733 0.31369)
						(xy -0.22606 0.32512) (xy -0.22352 0.33528) (xy -0.22225 0.34544) (xy -0.21844 0.35687) (xy -0.2159 0.36703)
						(xy -0.21209 0.37719) (xy -0.20701 0.38735) (xy -0.2032 0.39624) (xy -0.19812 0.4064) (xy -0.17272 0.44196)
						(xy -0.1651 0.44958) (xy -0.1651 0.7366) (xy -0.16256 0.76835) (xy -0.1524 0.8001) (xy -0.13716 0.82804)
						(xy -0.11684 0.85344) (xy -0.09144 0.87376) (xy -0.0635 0.889) (xy -0.03175 0.89916) (xy 0 0.9017)
						(xy 0.03175 0.89916) (xy 0.0635 0.889) (xy 0.09144 0.87376) (xy 0.11684 0.85344) (xy 0.13716 0.82804)
						(xy 0.1524 0.8001) (xy 0.16256 0.76835) (xy 0.1651 0.7366) (xy 0.1651 0.44958) (xy 0.17272 0.44196)
						(xy 0.19812 0.4064) (xy 0.2032 0.39624) (xy 0.20701 0.38735) (xy 0.21209 0.37719) (xy 0.2159 0.36703)
						(xy 0.21844 0.35687) (xy 0.22225 0.34544) (xy 0.22352 0.33528) (xy 0.22606 0.32512) (xy 0.22733 0.31369)
						(xy 0.22733 0.30353) (xy 0.2286 0.2921) (xy 0.22733 0.28067) (xy 0.22733 0.27051) (xy 0.22606 0.25908)
						(xy 0.22352 0.24892) (xy 0.22225 0.23876) (xy 0.21844 0.22733) (xy 0.2159 0.21717) (xy 0.21209 0.20701)
						(xy 0.20701 0.19685) (xy 0.2032 0.18796) (xy 0.19812 0.1778) (xy 0.17272 0.14224) (xy 0.1651 0.13462)
						(xy 0.1651 -0.7366) (xy 0.16256 -0.76835) (xy 0.1524 -0.8001) (xy 0.13716 -0.82804) (xy 0.11684 -0.85344)
						(xy 0.09144 -0.87376) (xy 0.0635 -0.889) (xy 0.03175 -0.89916)
					)
					(width 0)
					(fill yes)
				)
			)
		)
		(pad "107" smd custom
			(at 2.549906 -4.100068)
			(size 0.1143 0.1143)
			(layers "B.Cu" "B.Mask" "B.Paste")
			(net "M_A_MA0")
			(options
				(clearance outline)
				(anchor circle)
			)
			(primitives
				(gr_poly
					(pts
						(xy 0 -0.9017) (xy -0.03175 -0.89916) (xy -0.0635 -0.889) (xy -0.09144 -0.87376) (xy -0.11684 -0.85344)
						(xy -0.13716 -0.82804) (xy -0.1524 -0.8001) (xy -0.16256 -0.76835) (xy -0.1651 -0.7366) (xy -0.1651 -0.19685)
						(xy -0.17272 -0.18923) (xy -0.17907 -0.18034) (xy -0.18669 -0.17145) (xy -0.19177 -0.16256) (xy -0.19812 -0.15367)
						(xy -0.20828 -0.13335) (xy -0.21971 -0.10287) (xy -0.22225 -0.09271) (xy -0.22479 -0.08128) (xy -0.22606 -0.07112)
						(xy -0.2286 -0.05969) (xy -0.2286 -0.01651) (xy -0.22606 -0.00508) (xy -0.22479 0.00508) (xy -0.22225 0.01651)
						(xy -0.21971 0.02667) (xy -0.20828 0.05715) (xy -0.19812 0.07747) (xy -0.19177 0.08636) (xy -0.18669 0.09525)
						(xy -0.17907 0.10414) (xy -0.17272 0.11303) (xy -0.1651 0.12065) (xy -0.1651 0.7366) (xy -0.16256 0.76835)
						(xy -0.1524 0.8001) (xy -0.13716 0.82804) (xy -0.11684 0.85344) (xy -0.09144 0.87376) (xy -0.0635 0.889)
						(xy -0.03175 0.89916) (xy 0 0.9017) (xy 0.03175 0.89916) (xy 0.0635 0.889) (xy 0.09144 0.87376)
						(xy 0.11684 0.85344) (xy 0.13716 0.82804) (xy 0.1524 0.8001) (xy 0.16256 0.76835) (xy 0.1651 0.7366)
						(xy 0.1651 0.11938) (xy 0.17272 0.11176) (xy 0.19812 0.0762) (xy 0.2032 0.06604) (xy 0.20701 0.05715)
						(xy 0.21209 0.04699) (xy 0.2159 0.03683) (xy 0.21844 0.02667) (xy 0.22225 0.01524) (xy 0.22352 0.00508)
						(xy 0.22606 -0.00508) (xy 0.22733 -0.01651) (xy 0.22733 -0.02667) (xy 0.2286 -0.0381) (xy 0.22733 -0.04953)
						(xy 0.22733 -0.05969) (xy 0.22606 -0.07112) (xy 0.22352 -0.08128) (xy 0.22225 -0.09144) (xy 0.21844 -0.10287)
						(xy 0.2159 -0.11303) (xy 0.21209 -0.12319) (xy 0.20701 -0.13335) (xy 0.2032 -0.14224) (xy 0.19812 -0.1524)
						(xy 0.17272 -0.18796) (xy 0.1651 -0.19558) (xy 0.1651 -0.7366) (xy 0.16256 -0.76835) (xy 0.1524 -0.8001)
						(xy 0.13716 -0.82804) (xy 0.11684 -0.85344) (xy 0.09144 -0.87376) (xy 0.0635 -0.889) (xy 0.03175 -0.89916)
					)
					(width 0)
					(fill yes)
				)
			)
		)
		(pad "108" smd custom
			(at 2.84988 4.100068)
			(size 0.1143 0.1143)
			(layers "B.Cu" "B.Mask" "B.Paste")
			(net "M_A_BS1")
			(options
				(clearance outline)
				(anchor circle)
			)
			(primitives
				(gr_poly
					(pts
						(xy 0 -0.9017) (xy -0.03175 -0.89916) (xy -0.0635 -0.889) (xy -0.09144 -0.87376) (xy -0.11684 -0.85344)
						(xy -0.13716 -0.82804) (xy -0.1524 -0.8001) (xy -0.16256 -0.76835) (xy -0.1651 -0.7366) (xy -0.1651 -0.11938)
						(xy -0.17272 -0.11176) (xy -0.19812 -0.0762) (xy -0.2032 -0.06604) (xy -0.20701 -0.05715) (xy -0.21209 -0.04699)
						(xy -0.2159 -0.03683) (xy -0.21844 -0.02667) (xy -0.22225 -0.01524) (xy -0.22352 -0.00508) (xy -0.22606 0.00508)
						(xy -0.22733 0.01651) (xy -0.22733 0.02667) (xy -0.2286 0.0381) (xy -0.22733 0.04953) (xy -0.22733 0.05969)
						(xy -0.22606 0.07112) (xy -0.22352 0.08128) (xy -0.22225 0.09144) (xy -0.21844 0.10287) (xy -0.2159 0.11303)
						(xy -0.21209 0.12319) (xy -0.20701 0.13335) (xy -0.2032 0.14224) (xy -0.19812 0.1524) (xy -0.17272 0.18796)
						(xy -0.1651 0.19558) (xy -0.1651 0.7366) (xy -0.16256 0.76835) (xy -0.1524 0.8001) (xy -0.13716 0.82804)
						(xy -0.11684 0.85344) (xy -0.09144 0.87376) (xy -0.0635 0.889) (xy -0.03175 0.89916) (xy 0 0.9017)
						(xy 0.03175 0.89916) (xy 0.0635 0.889) (xy 0.09144 0.87376) (xy 0.11684 0.85344) (xy 0.13716 0.82804)
						(xy 0.1524 0.8001) (xy 0.16256 0.76835) (xy 0.1651 0.7366) (xy 0.1651 0.19685) (xy 0.17272 0.18923)
						(xy 0.17907 0.18034) (xy 0.18669 0.17145) (xy 0.19177 0.16256) (xy 0.19812 0.15367) (xy 0.20828 0.13335)
						(xy 0.21971 0.10287) (xy 0.22225 0.09271) (xy 0.22479 0.08128) (xy 0.22606 0.07112) (xy 0.2286 0.05969)
						(xy 0.2286 0.01651) (xy 0.22606 0.00508) (xy 0.22479 -0.00508) (xy 0.22225 -0.01651) (xy 0.21971 -0.02667)
						(xy 0.20828 -0.05715) (xy 0.19812 -0.07747) (xy 0.19177 -0.08636) (xy 0.18669 -0.09525) (xy 0.17907 -0.10414)
						(xy 0.17272 -0.11303) (xy 0.1651 -0.12065) (xy 0.1651 -0.7366) (xy 0.16256 -0.76835) (xy 0.1524 -0.8001)
						(xy 0.13716 -0.82804) (xy 0.11684 -0.85344) (xy 0.09144 -0.87376) (xy 0.0635 -0.889) (xy 0.03175 -0.89916)
					)
					(width 0)
					(fill yes)
				)
			)
		)
		(pad "109" smd custom
			(at 3.150108 -4.100068)
			(size 0.1143 0.1143)
			(layers "B.Cu" "B.Mask" "B.Paste")
			(net "PV_VDDR")
			(options
				(clearance outline)
				(anchor circle)
			)
			(primitives
				(gr_poly
					(pts
						(xy 0 -0.9017) (xy -0.03175 -0.89916) (xy -0.0635 -0.889) (xy -0.09144 -0.87376) (xy -0.11684 -0.85344)
						(xy -0.13716 -0.82804) (xy -0.1524 -0.8001) (xy -0.16256 -0.76835) (xy -0.1651 -0.7366) (xy -0.1651 -0.44958)
						(xy -0.17272 -0.44196) (xy -0.19812 -0.4064) (xy -0.2032 -0.39624) (xy -0.20701 -0.38735) (xy -0.21209 -0.37719)
						(xy -0.2159 -0.36703) (xy -0.21844 -0.35687) (xy -0.22225 -0.34544) (xy -0.22352 -0.33528) (xy -0.22606 -0.32512)
						(xy -0.22733 -0.31369) (xy -0.22733 -0.30353) (xy -0.2286 -0.2921) (xy -0.22733 -0.28067) (xy -0.22733 -0.27051)
						(xy -0.22606 -0.25908) (xy -0.22352 -0.24892) (xy -0.22225 -0.23876) (xy -0.21844 -0.22733) (xy -0.2159 -0.21717)
						(xy -0.21209 -0.20701) (xy -0.20701 -0.19685) (xy -0.2032 -0.18796) (xy -0.19812 -0.1778) (xy -0.17272 -0.14224)
						(xy -0.1651 -0.13462) (xy -0.1651 0.7366) (xy -0.16256 0.76835) (xy -0.1524 0.8001) (xy -0.13716 0.82804)
						(xy -0.11684 0.85344) (xy -0.09144 0.87376) (xy -0.0635 0.889) (xy -0.03175 0.89916) (xy 0 0.9017)
						(xy 0.03175 0.89916) (xy 0.0635 0.889) (xy 0.09144 0.87376) (xy 0.11684 0.85344) (xy 0.13716 0.82804)
						(xy 0.1524 0.8001) (xy 0.16256 0.76835) (xy 0.1651 0.7366) (xy 0.1651 -0.13462) (xy 0.17272 -0.14224)
						(xy 0.19812 -0.1778) (xy 0.2032 -0.18796) (xy 0.20701 -0.19685) (xy 0.21209 -0.20701) (xy 0.2159 -0.21717)
						(xy 0.21844 -0.22733) (xy 0.22225 -0.23876) (xy 0.22352 -0.24892) (xy 0.22606 -0.25908) (xy 0.22733 -0.27051)
						(xy 0.22733 -0.28067) (xy 0.2286 -0.2921) (xy 0.22733 -0.30353) (xy 0.22733 -0.31369) (xy 0.22606 -0.32512)
						(xy 0.22352 -0.33528) (xy 0.22225 -0.34544) (xy 0.21844 -0.35687) (xy 0.2159 -0.36703) (xy 0.21209 -0.37719)
						(xy 0.20701 -0.38735) (xy 0.2032 -0.39624) (xy 0.19812 -0.4064) (xy 0.17272 -0.44196) (xy 0.1651 -0.44958)
						(xy 0.1651 -0.7366) (xy 0.16256 -0.76835) (xy 0.1524 -0.8001) (xy 0.13716 -0.82804) (xy 0.11684 -0.85344)
						(xy 0.09144 -0.87376) (xy 0.0635 -0.889) (xy 0.03175 -0.89916)
					)
					(width 0)
					(fill yes)
				)
			)
		)
		(pad "110" smd custom
			(at 3.450082 4.100068)
			(size 0.1143 0.1143)
			(layers "B.Cu" "B.Mask" "B.Paste")
			(net "PV_VDDR")
			(options
				(clearance outline)
				(anchor circle)
			)
			(primitives
				(gr_poly
					(pts
						(xy 0 -0.9017) (xy -0.03175 -0.89916) (xy -0.0635 -0.889) (xy -0.09144 -0.87376) (xy -0.11684 -0.85344)
						(xy -0.13716 -0.82804) (xy -0.1524 -0.8001) (xy -0.16256 -0.76835) (xy -0.1651 -0.7366) (xy -0.1651 0.13462)
						(xy -0.17272 0.14224) (xy -0.19812 0.1778) (xy -0.2032 0.18796) (xy -0.20701 0.19685) (xy -0.21209 0.20701)
						(xy -0.2159 0.21717) (xy -0.21844 0.22733) (xy -0.22225 0.23876) (xy -0.22352 0.24892) (xy -0.22606 0.25908)
						(xy -0.22733 0.27051) (xy -0.22733 0.28067) (xy -0.2286 0.2921) (xy -0.22733 0.30353) (xy -0.22733 0.31369)
						(xy -0.22606 0.32512) (xy -0.22352 0.33528) (xy -0.22225 0.34544) (xy -0.21844 0.35687) (xy -0.2159 0.36703)
						(xy -0.21209 0.37719) (xy -0.20701 0.38735) (xy -0.2032 0.39624) (xy -0.19812 0.4064) (xy -0.17272 0.44196)
						(xy -0.1651 0.44958) (xy -0.1651 0.7366) (xy -0.16256 0.76835) (xy -0.1524 0.8001) (xy -0.13716 0.82804)
						(xy -0.11684 0.85344) (xy -0.09144 0.87376) (xy -0.0635 0.889) (xy -0.03175 0.89916) (xy 0 0.9017)
						(xy 0.03175 0.89916) (xy 0.0635 0.889) (xy 0.09144 0.87376) (xy 0.11684 0.85344) (xy 0.13716 0.82804)
						(xy 0.1524 0.8001) (xy 0.16256 0.76835) (xy 0.1651 0.7366) (xy 0.1651 0.44958) (xy 0.17272 0.44196)
						(xy 0.19812 0.4064) (xy 0.2032 0.39624) (xy 0.20701 0.38735) (xy 0.21209 0.37719) (xy 0.2159 0.36703)
						(xy 0.21844 0.35687) (xy 0.22225 0.34544) (xy 0.22352 0.33528) (xy 0.22606 0.32512) (xy 0.22733 0.31369)
						(xy 0.22733 0.30353) (xy 0.2286 0.2921) (xy 0.22733 0.28067) (xy 0.22733 0.27051) (xy 0.22606 0.25908)
						(xy 0.22352 0.24892) (xy 0.22225 0.23876) (xy 0.21844 0.22733) (xy 0.2159 0.21717) (xy 0.21209 0.20701)
						(xy 0.20701 0.19685) (xy 0.2032 0.18796) (xy 0.19812 0.1778) (xy 0.17272 0.14224) (xy 0.1651 0.13462)
						(xy 0.1651 -0.7366) (xy 0.16256 -0.76835) (xy 0.1524 -0.8001) (xy 0.13716 -0.82804) (xy 0.11684 -0.85344)
						(xy 0.09144 -0.87376) (xy 0.0635 -0.889) (xy 0.03175 -0.89916)
					)
					(width 0)
					(fill yes)
				)
			)
		)
		(pad "111" smd custom
			(at 3.750056 -4.100068)
			(size 0.1143 0.1143)
			(layers "B.Cu" "B.Mask" "B.Paste")
			(net "M_A_CK_DP0")
			(options
				(clearance outline)
				(anchor circle)
			)
			(primitives
				(gr_poly
					(pts
						(xy 0 -0.9017) (xy -0.03175 -0.89916) (xy -0.0635 -0.889) (xy -0.09144 -0.87376) (xy -0.11684 -0.85344)
						(xy -0.13716 -0.82804) (xy -0.1524 -0.8001) (xy -0.16256 -0.76835) (xy -0.1651 -0.7366) (xy -0.1651 -0.19685)
						(xy -0.17272 -0.18923) (xy -0.17907 -0.18034) (xy -0.18669 -0.17145) (xy -0.19177 -0.16256) (xy -0.19812 -0.15367)
						(xy -0.20828 -0.13335) (xy -0.21971 -0.10287) (xy -0.22225 -0.09271) (xy -0.22479 -0.08128) (xy -0.22606 -0.07112)
						(xy -0.2286 -0.05969) (xy -0.2286 -0.01651) (xy -0.22606 -0.00508) (xy -0.22479 0.00508) (xy -0.22225 0.01651)
						(xy -0.21971 0.02667) (xy -0.20828 0.05715) (xy -0.19812 0.07747) (xy -0.19177 0.08636) (xy -0.18669 0.09525)
						(xy -0.17907 0.10414) (xy -0.17272 0.11303) (xy -0.1651 0.12065) (xy -0.1651 0.7366) (xy -0.16256 0.76835)
						(xy -0.1524 0.8001) (xy -0.13716 0.82804) (xy -0.11684 0.85344) (xy -0.09144 0.87376) (xy -0.0635 0.889)
						(xy -0.03175 0.89916) (xy 0 0.9017) (xy 0.03175 0.89916) (xy 0.0635 0.889) (xy 0.09144 0.87376)
						(xy 0.11684 0.85344) (xy 0.13716 0.82804) (xy 0.1524 0.8001) (xy 0.16256 0.76835) (xy 0.1651 0.7366)
						(xy 0.1651 0.11938) (xy 0.17272 0.11176) (xy 0.19812 0.0762) (xy 0.2032 0.06604) (xy 0.20701 0.05715)
						(xy 0.21209 0.04699) (xy 0.2159 0.03683) (xy 0.21844 0.02667) (xy 0.22225 0.01524) (xy 0.22352 0.00508)
						(xy 0.22606 -0.00508) (xy 0.22733 -0.01651) (xy 0.22733 -0.02667) (xy 0.2286 -0.0381) (xy 0.22733 -0.04953)
						(xy 0.22733 -0.05969) (xy 0.22606 -0.07112) (xy 0.22352 -0.08128) (xy 0.22225 -0.09144) (xy 0.21844 -0.10287)
						(xy 0.2159 -0.11303) (xy 0.21209 -0.12319) (xy 0.20701 -0.13335) (xy 0.2032 -0.14224) (xy 0.19812 -0.1524)
						(xy 0.17272 -0.18796) (xy 0.1651 -0.19558) (xy 0.1651 -0.7366) (xy 0.16256 -0.76835) (xy 0.1524 -0.8001)
						(xy 0.13716 -0.82804) (xy 0.11684 -0.85344) (xy 0.09144 -0.87376) (xy 0.0635 -0.889) (xy 0.03175 -0.89916)
					)
					(width 0)
					(fill yes)
				)
			)
		)
		(pad "112" smd custom
			(at 4.05003 4.100068)
			(size 0.1143 0.1143)
			(layers "B.Cu" "B.Mask" "B.Paste")
			(net "M_A_CK_DP1")
			(options
				(clearance outline)
				(anchor circle)
			)
			(primitives
				(gr_poly
					(pts
						(xy 0 -0.9017) (xy -0.03175 -0.89916) (xy -0.0635 -0.889) (xy -0.09144 -0.87376) (xy -0.11684 -0.85344)
						(xy -0.13716 -0.82804) (xy -0.1524 -0.8001) (xy -0.16256 -0.76835) (xy -0.1651 -0.7366) (xy -0.1651 -0.11938)
						(xy -0.17272 -0.11176) (xy -0.19812 -0.0762) (xy -0.2032 -0.06604) (xy -0.20701 -0.05715) (xy -0.21209 -0.04699)
						(xy -0.2159 -0.03683) (xy -0.21844 -0.02667) (xy -0.22225 -0.01524) (xy -0.22352 -0.00508) (xy -0.22606 0.00508)
						(xy -0.22733 0.01651) (xy -0.22733 0.02667) (xy -0.2286 0.0381) (xy -0.22733 0.04953) (xy -0.22733 0.05969)
						(xy -0.22606 0.07112) (xy -0.22352 0.08128) (xy -0.22225 0.09144) (xy -0.21844 0.10287) (xy -0.2159 0.11303)
						(xy -0.21209 0.12319) (xy -0.20701 0.13335) (xy -0.2032 0.14224) (xy -0.19812 0.1524) (xy -0.17272 0.18796)
						(xy -0.1651 0.19558) (xy -0.1651 0.7366) (xy -0.16256 0.76835) (xy -0.1524 0.8001) (xy -0.13716 0.82804)
						(xy -0.11684 0.85344) (xy -0.09144 0.87376) (xy -0.0635 0.889) (xy -0.03175 0.89916) (xy 0 0.9017)
						(xy 0.03175 0.89916) (xy 0.0635 0.889) (xy 0.09144 0.87376) (xy 0.11684 0.85344) (xy 0.13716 0.82804)
						(xy 0.1524 0.8001) (xy 0.16256 0.76835) (xy 0.1651 0.7366) (xy 0.1651 0.19685) (xy 0.17272 0.18923)
						(xy 0.17907 0.18034) (xy 0.18669 0.17145) (xy 0.19177 0.16256) (xy 0.19812 0.15367) (xy 0.20828 0.13335)
						(xy 0.21971 0.10287) (xy 0.22225 0.09271) (xy 0.22479 0.08128) (xy 0.22606 0.07112) (xy 0.2286 0.05969)
						(xy 0.2286 0.01651) (xy 0.22606 0.00508) (xy 0.22479 -0.00508) (xy 0.22225 -0.01651) (xy 0.21971 -0.02667)
						(xy 0.20828 -0.05715) (xy 0.19812 -0.07747) (xy 0.19177 -0.08636) (xy 0.18669 -0.09525) (xy 0.17907 -0.10414)
						(xy 0.17272 -0.11303) (xy 0.1651 -0.12065) (xy 0.1651 -0.7366) (xy 0.16256 -0.76835) (xy 0.1524 -0.8001)
						(xy 0.13716 -0.82804) (xy 0.11684 -0.85344) (xy 0.09144 -0.87376) (xy 0.0635 -0.889) (xy 0.03175 -0.89916)
					)
					(width 0)
					(fill yes)
				)
			)
		)
		(pad "113" smd custom
			(at 4.350004 -4.100068)
			(size 0.1143 0.1143)
			(layers "B.Cu" "B.Mask" "B.Paste")
			(net "M_A_CK_DN0")
			(options
				(clearance outline)
				(anchor circle)
			)
			(primitives
				(gr_poly
					(pts
						(xy 0 -0.9017) (xy -0.03175 -0.89916) (xy -0.0635 -0.889) (xy -0.09144 -0.87376) (xy -0.11684 -0.85344)
						(xy -0.13716 -0.82804) (xy -0.1524 -0.8001) (xy -0.16256 -0.76835) (xy -0.1651 -0.7366) (xy -0.1651 -0.44958)
						(xy -0.17272 -0.44196) (xy -0.19812 -0.4064) (xy -0.2032 -0.39624) (xy -0.20701 -0.38735) (xy -0.21209 -0.37719)
						(xy -0.2159 -0.36703) (xy -0.21844 -0.35687) (xy -0.22225 -0.34544) (xy -0.22352 -0.33528) (xy -0.22606 -0.32512)
						(xy -0.22733 -0.31369) (xy -0.22733 -0.30353) (xy -0.2286 -0.2921) (xy -0.22733 -0.28067) (xy -0.22733 -0.27051)
						(xy -0.22606 -0.25908) (xy -0.22352 -0.24892) (xy -0.22225 -0.23876) (xy -0.21844 -0.22733) (xy -0.2159 -0.21717)
						(xy -0.21209 -0.20701) (xy -0.20701 -0.19685) (xy -0.2032 -0.18796) (xy -0.19812 -0.1778) (xy -0.17272 -0.14224)
						(xy -0.1651 -0.13462) (xy -0.1651 0.7366) (xy -0.16256 0.76835) (xy -0.1524 0.8001) (xy -0.13716 0.82804)
						(xy -0.11684 0.85344) (xy -0.09144 0.87376) (xy -0.0635 0.889) (xy -0.03175 0.89916) (xy 0 0.9017)
						(xy 0.03175 0.89916) (xy 0.0635 0.889) (xy 0.09144 0.87376) (xy 0.11684 0.85344) (xy 0.13716 0.82804)
						(xy 0.1524 0.8001) (xy 0.16256 0.76835) (xy 0.1651 0.7366) (xy 0.1651 -0.13462) (xy 0.17272 -0.14224)
						(xy 0.19812 -0.1778) (xy 0.2032 -0.18796) (xy 0.20701 -0.19685) (xy 0.21209 -0.20701) (xy 0.2159 -0.21717)
						(xy 0.21844 -0.22733) (xy 0.22225 -0.23876) (xy 0.22352 -0.24892) (xy 0.22606 -0.25908) (xy 0.22733 -0.27051)
						(xy 0.22733 -0.28067) (xy 0.2286 -0.2921) (xy 0.22733 -0.30353) (xy 0.22733 -0.31369) (xy 0.22606 -0.32512)
						(xy 0.22352 -0.33528) (xy 0.22225 -0.34544) (xy 0.21844 -0.35687) (xy 0.2159 -0.36703) (xy 0.21209 -0.37719)
						(xy 0.20701 -0.38735) (xy 0.2032 -0.39624) (xy 0.19812 -0.4064) (xy 0.17272 -0.44196) (xy 0.1651 -0.44958)
						(xy 0.1651 -0.7366) (xy 0.16256 -0.76835) (xy 0.1524 -0.8001) (xy 0.13716 -0.82804) (xy 0.11684 -0.85344)
						(xy 0.09144 -0.87376) (xy 0.0635 -0.889) (xy 0.03175 -0.89916)
					)
					(width 0)
					(fill yes)
				)
			)
		)
		(pad "114" smd custom
			(at 4.649978 4.100068)
			(size 0.1143 0.1143)
			(layers "B.Cu" "B.Mask" "B.Paste")
			(net "M_A_CK_DN1")
			(options
				(clearance outline)
				(anchor circle)
			)
			(primitives
				(gr_poly
					(pts
						(xy 0 -0.9017) (xy -0.03175 -0.89916) (xy -0.0635 -0.889) (xy -0.09144 -0.87376) (xy -0.11684 -0.85344)
						(xy -0.13716 -0.82804) (xy -0.1524 -0.8001) (xy -0.16256 -0.76835) (xy -0.1651 -0.7366) (xy -0.1651 0.13462)
						(xy -0.17272 0.14224) (xy -0.19812 0.1778) (xy -0.2032 0.18796) (xy -0.20701 0.19685) (xy -0.21209 0.20701)
						(xy -0.2159 0.21717) (xy -0.21844 0.22733) (xy -0.22225 0.23876) (xy -0.22352 0.24892) (xy -0.22606 0.25908)
						(xy -0.22733 0.27051) (xy -0.22733 0.28067) (xy -0.2286 0.2921) (xy -0.22733 0.30353) (xy -0.22733 0.31369)
						(xy -0.22606 0.32512) (xy -0.22352 0.33528) (xy -0.22225 0.34544) (xy -0.21844 0.35687) (xy -0.2159 0.36703)
						(xy -0.21209 0.37719) (xy -0.20701 0.38735) (xy -0.2032 0.39624) (xy -0.19812 0.4064) (xy -0.17272 0.44196)
						(xy -0.1651 0.44958) (xy -0.1651 0.7366) (xy -0.16256 0.76835) (xy -0.1524 0.8001) (xy -0.13716 0.82804)
						(xy -0.11684 0.85344) (xy -0.09144 0.87376) (xy -0.0635 0.889) (xy -0.03175 0.89916) (xy 0 0.9017)
						(xy 0.03175 0.89916) (xy 0.0635 0.889) (xy 0.09144 0.87376) (xy 0.11684 0.85344) (xy 0.13716 0.82804)
						(xy 0.1524 0.8001) (xy 0.16256 0.76835) (xy 0.1651 0.7366) (xy 0.1651 0.44958) (xy 0.17272 0.44196)
						(xy 0.19812 0.4064) (xy 0.2032 0.39624) (xy 0.20701 0.38735) (xy 0.21209 0.37719) (xy 0.2159 0.36703)
						(xy 0.21844 0.35687) (xy 0.22225 0.34544) (xy 0.22352 0.33528) (xy 0.22606 0.32512) (xy 0.22733 0.31369)
						(xy 0.22733 0.30353) (xy 0.2286 0.2921) (xy 0.22733 0.28067) (xy 0.22733 0.27051) (xy 0.22606 0.25908)
						(xy 0.22352 0.24892) (xy 0.22225 0.23876) (xy 0.21844 0.22733) (xy 0.2159 0.21717) (xy 0.21209 0.20701)
						(xy 0.20701 0.19685) (xy 0.2032 0.18796) (xy 0.19812 0.1778) (xy 0.17272 0.14224) (xy 0.1651 0.13462)
						(xy 0.1651 -0.7366) (xy 0.16256 -0.76835) (xy 0.1524 -0.8001) (xy 0.13716 -0.82804) (xy 0.11684 -0.85344)
						(xy 0.09144 -0.87376) (xy 0.0635 -0.889) (xy 0.03175 -0.89916)
					)
					(width 0)
					(fill yes)
				)
			)
		)
		(pad "115" smd custom
			(at 4.949952 -4.100068)
			(size 0.1143 0.1143)
			(layers "B.Cu" "B.Mask" "B.Paste")
			(net "PV_VDDR")
			(options
				(clearance outline)
				(anchor circle)
			)
			(primitives
				(gr_poly
					(pts
						(xy 0 -0.9017) (xy -0.03175 -0.89916) (xy -0.0635 -0.889) (xy -0.09144 -0.87376) (xy -0.11684 -0.85344)
						(xy -0.13716 -0.82804) (xy -0.1524 -0.8001) (xy -0.16256 -0.76835) (xy -0.1651 -0.7366) (xy -0.1651 -0.19685)
						(xy -0.17272 -0.18923) (xy -0.17907 -0.18034) (xy -0.18669 -0.17145) (xy -0.19177 -0.16256) (xy -0.19812 -0.15367)
						(xy -0.20828 -0.13335) (xy -0.21971 -0.10287) (xy -0.22225 -0.09271) (xy -0.22479 -0.08128) (xy -0.22606 -0.07112)
						(xy -0.2286 -0.05969) (xy -0.2286 -0.01651) (xy -0.22606 -0.00508) (xy -0.22479 0.00508) (xy -0.22225 0.01651)
						(xy -0.21971 0.02667) (xy -0.20828 0.05715) (xy -0.19812 0.07747) (xy -0.19177 0.08636) (xy -0.18669 0.09525)
						(xy -0.17907 0.10414) (xy -0.17272 0.11303) (xy -0.1651 0.12065) (xy -0.1651 0.7366) (xy -0.16256 0.76835)
						(xy -0.1524 0.8001) (xy -0.13716 0.82804) (xy -0.11684 0.85344) (xy -0.09144 0.87376) (xy -0.0635 0.889)
						(xy -0.03175 0.89916) (xy 0 0.9017) (xy 0.03175 0.89916) (xy 0.0635 0.889) (xy 0.09144 0.87376)
						(xy 0.11684 0.85344) (xy 0.13716 0.82804) (xy 0.1524 0.8001) (xy 0.16256 0.76835) (xy 0.1651 0.7366)
						(xy 0.1651 0.11938) (xy 0.17272 0.11176) (xy 0.19812 0.0762) (xy 0.2032 0.06604) (xy 0.20701 0.05715)
						(xy 0.21209 0.04699) (xy 0.2159 0.03683) (xy 0.21844 0.02667) (xy 0.22225 0.01524) (xy 0.22352 0.00508)
						(xy 0.22606 -0.00508) (xy 0.22733 -0.01651) (xy 0.22733 -0.02667) (xy 0.2286 -0.0381) (xy 0.22733 -0.04953)
						(xy 0.22733 -0.05969) (xy 0.22606 -0.07112) (xy 0.22352 -0.08128) (xy 0.22225 -0.09144) (xy 0.21844 -0.10287)
						(xy 0.2159 -0.11303) (xy 0.21209 -0.12319) (xy 0.20701 -0.13335) (xy 0.2032 -0.14224) (xy 0.19812 -0.1524)
						(xy 0.17272 -0.18796) (xy 0.1651 -0.19558) (xy 0.1651 -0.7366) (xy 0.16256 -0.76835) (xy 0.1524 -0.8001)
						(xy 0.13716 -0.82804) (xy 0.11684 -0.85344) (xy 0.09144 -0.87376) (xy 0.0635 -0.889) (xy 0.03175 -0.89916)
					)
					(width 0)
					(fill yes)
				)
			)
		)
		(pad "116" smd custom
			(at 5.249926 4.100068)
			(size 0.1143 0.1143)
			(layers "B.Cu" "B.Mask" "B.Paste")
			(net "PV_VDDR")
			(options
				(clearance outline)
				(anchor circle)
			)
			(primitives
				(gr_poly
					(pts
						(xy 0 -0.9017) (xy -0.03175 -0.89916) (xy -0.0635 -0.889) (xy -0.09144 -0.87376) (xy -0.11684 -0.85344)
						(xy -0.13716 -0.82804) (xy -0.1524 -0.8001) (xy -0.16256 -0.76835) (xy -0.1651 -0.7366) (xy -0.1651 -0.11938)
						(xy -0.17272 -0.11176) (xy -0.19812 -0.0762) (xy -0.2032 -0.06604) (xy -0.20701 -0.05715) (xy -0.21209 -0.04699)
						(xy -0.2159 -0.03683) (xy -0.21844 -0.02667) (xy -0.22225 -0.01524) (xy -0.22352 -0.00508) (xy -0.22606 0.00508)
						(xy -0.22733 0.01651) (xy -0.22733 0.02667) (xy -0.2286 0.0381) (xy -0.22733 0.04953) (xy -0.22733 0.05969)
						(xy -0.22606 0.07112) (xy -0.22352 0.08128) (xy -0.22225 0.09144) (xy -0.21844 0.10287) (xy -0.2159 0.11303)
						(xy -0.21209 0.12319) (xy -0.20701 0.13335) (xy -0.2032 0.14224) (xy -0.19812 0.1524) (xy -0.17272 0.18796)
						(xy -0.1651 0.19558) (xy -0.1651 0.7366) (xy -0.16256 0.76835) (xy -0.1524 0.8001) (xy -0.13716 0.82804)
						(xy -0.11684 0.85344) (xy -0.09144 0.87376) (xy -0.0635 0.889) (xy -0.03175 0.89916) (xy 0 0.9017)
						(xy 0.03175 0.89916) (xy 0.0635 0.889) (xy 0.09144 0.87376) (xy 0.11684 0.85344) (xy 0.13716 0.82804)
						(xy 0.1524 0.8001) (xy 0.16256 0.76835) (xy 0.1651 0.7366) (xy 0.1651 0.19685) (xy 0.17272 0.18923)
						(xy 0.17907 0.18034) (xy 0.18669 0.17145) (xy 0.19177 0.16256) (xy 0.19812 0.15367) (xy 0.20828 0.13335)
						(xy 0.21971 0.10287) (xy 0.22225 0.09271) (xy 0.22479 0.08128) (xy 0.22606 0.07112) (xy 0.2286 0.05969)
						(xy 0.2286 0.01651) (xy 0.22606 0.00508) (xy 0.22479 -0.00508) (xy 0.22225 -0.01651) (xy 0.21971 -0.02667)
						(xy 0.20828 -0.05715) (xy 0.19812 -0.07747) (xy 0.19177 -0.08636) (xy 0.18669 -0.09525) (xy 0.17907 -0.10414)
						(xy 0.17272 -0.11303) (xy 0.1651 -0.12065) (xy 0.1651 -0.7366) (xy 0.16256 -0.76835) (xy 0.1524 -0.8001)
						(xy 0.13716 -0.82804) (xy 0.11684 -0.85344) (xy 0.09144 -0.87376) (xy 0.0635 -0.889) (xy 0.03175 -0.89916)
					)
					(width 0)
					(fill yes)
				)
			)
		)
		(pad "117" smd custom
			(at 5.5499 -4.100068)
			(size 0.1143 0.1143)
			(layers "B.Cu" "B.Mask" "B.Paste")
			(net "M_A_MA10")
			(options
				(clearance outline)
				(anchor circle)
			)
			(primitives
				(gr_poly
					(pts
						(xy 0 -0.9017) (xy -0.03175 -0.89916) (xy -0.0635 -0.889) (xy -0.09144 -0.87376) (xy -0.11684 -0.85344)
						(xy -0.13716 -0.82804) (xy -0.1524 -0.8001) (xy -0.16256 -0.76835) (xy -0.1651 -0.7366) (xy -0.1651 -0.44958)
						(xy -0.17272 -0.44196) (xy -0.19812 -0.4064) (xy -0.2032 -0.39624) (xy -0.20701 -0.38735) (xy -0.21209 -0.37719)
						(xy -0.2159 -0.36703) (xy -0.21844 -0.35687) (xy -0.22225 -0.34544) (xy -0.22352 -0.33528) (xy -0.22606 -0.32512)
						(xy -0.22733 -0.31369) (xy -0.22733 -0.30353) (xy -0.2286 -0.2921) (xy -0.22733 -0.28067) (xy -0.22733 -0.27051)
						(xy -0.22606 -0.25908) (xy -0.22352 -0.24892) (xy -0.22225 -0.23876) (xy -0.21844 -0.22733) (xy -0.2159 -0.21717)
						(xy -0.21209 -0.20701) (xy -0.20701 -0.19685) (xy -0.2032 -0.18796) (xy -0.19812 -0.1778) (xy -0.17272 -0.14224)
						(xy -0.1651 -0.13462) (xy -0.1651 0.7366) (xy -0.16256 0.76835) (xy -0.1524 0.8001) (xy -0.13716 0.82804)
						(xy -0.11684 0.85344) (xy -0.09144 0.87376) (xy -0.0635 0.889) (xy -0.03175 0.89916) (xy 0 0.9017)
						(xy 0.03175 0.89916) (xy 0.0635 0.889) (xy 0.09144 0.87376) (xy 0.11684 0.85344) (xy 0.13716 0.82804)
						(xy 0.1524 0.8001) (xy 0.16256 0.76835) (xy 0.1651 0.7366) (xy 0.1651 -0.13462) (xy 0.17272 -0.14224)
						(xy 0.19812 -0.1778) (xy 0.2032 -0.18796) (xy 0.20701 -0.19685) (xy 0.21209 -0.20701) (xy 0.2159 -0.21717)
						(xy 0.21844 -0.22733) (xy 0.22225 -0.23876) (xy 0.22352 -0.24892) (xy 0.22606 -0.25908) (xy 0.22733 -0.27051)
						(xy 0.22733 -0.28067) (xy 0.2286 -0.2921) (xy 0.22733 -0.30353) (xy 0.22733 -0.31369) (xy 0.22606 -0.32512)
						(xy 0.22352 -0.33528) (xy 0.22225 -0.34544) (xy 0.21844 -0.35687) (xy 0.2159 -0.36703) (xy 0.21209 -0.37719)
						(xy 0.20701 -0.38735) (xy 0.2032 -0.39624) (xy 0.19812 -0.4064) (xy 0.17272 -0.44196) (xy 0.1651 -0.44958)
						(xy 0.1651 -0.7366) (xy 0.16256 -0.76835) (xy 0.1524 -0.8001) (xy 0.13716 -0.82804) (xy 0.11684 -0.85344)
						(xy 0.09144 -0.87376) (xy 0.0635 -0.889) (xy 0.03175 -0.89916)
					)
					(width 0)
					(fill yes)
				)
			)
		)
		(pad "118" smd custom
			(at 5.849874 4.100068)
			(size 0.1143 0.1143)
			(layers "B.Cu" "B.Mask" "B.Paste")
			(net "Net_16")
			(options
				(clearance outline)
				(anchor circle)
			)
			(primitives
				(gr_poly
					(pts
						(xy 0 -0.9017) (xy -0.03175 -0.89916) (xy -0.0635 -0.889) (xy -0.09144 -0.87376) (xy -0.11684 -0.85344)
						(xy -0.13716 -0.82804) (xy -0.1524 -0.8001) (xy -0.16256 -0.76835) (xy -0.1651 -0.7366) (xy -0.1651 0.13462)
						(xy -0.17272 0.14224) (xy -0.19812 0.1778) (xy -0.2032 0.18796) (xy -0.20701 0.19685) (xy -0.21209 0.20701)
						(xy -0.2159 0.21717) (xy -0.21844 0.22733) (xy -0.22225 0.23876) (xy -0.22352 0.24892) (xy -0.22606 0.25908)
						(xy -0.22733 0.27051) (xy -0.22733 0.28067) (xy -0.2286 0.2921) (xy -0.22733 0.30353) (xy -0.22733 0.31369)
						(xy -0.22606 0.32512) (xy -0.22352 0.33528) (xy -0.22225 0.34544) (xy -0.21844 0.35687) (xy -0.2159 0.36703)
						(xy -0.21209 0.37719) (xy -0.20701 0.38735) (xy -0.2032 0.39624) (xy -0.19812 0.4064) (xy -0.17272 0.44196)
						(xy -0.1651 0.44958) (xy -0.1651 0.7366) (xy -0.16256 0.76835) (xy -0.1524 0.8001) (xy -0.13716 0.82804)
						(xy -0.11684 0.85344) (xy -0.09144 0.87376) (xy -0.0635 0.889) (xy -0.03175 0.89916) (xy 0 0.9017)
						(xy 0.03175 0.89916) (xy 0.0635 0.889) (xy 0.09144 0.87376) (xy 0.11684 0.85344) (xy 0.13716 0.82804)
						(xy 0.1524 0.8001) (xy 0.16256 0.76835) (xy 0.1651 0.7366) (xy 0.1651 0.44958) (xy 0.17272 0.44196)
						(xy 0.19812 0.4064) (xy 0.2032 0.39624) (xy 0.20701 0.38735) (xy 0.21209 0.37719) (xy 0.2159 0.36703)
						(xy 0.21844 0.35687) (xy 0.22225 0.34544) (xy 0.22352 0.33528) (xy 0.22606 0.32512) (xy 0.22733 0.31369)
						(xy 0.22733 0.30353) (xy 0.2286 0.2921) (xy 0.22733 0.28067) (xy 0.22733 0.27051) (xy 0.22606 0.25908)
						(xy 0.22352 0.24892) (xy 0.22225 0.23876) (xy 0.21844 0.22733) (xy 0.2159 0.21717) (xy 0.21209 0.20701)
						(xy 0.20701 0.19685) (xy 0.2032 0.18796) (xy 0.19812 0.1778) (xy 0.17272 0.14224) (xy 0.1651 0.13462)
						(xy 0.1651 -0.7366) (xy 0.16256 -0.76835) (xy 0.1524 -0.8001) (xy 0.13716 -0.82804) (xy 0.11684 -0.85344)
						(xy 0.09144 -0.87376) (xy 0.0635 -0.889) (xy 0.03175 -0.89916)
					)
					(width 0)
					(fill yes)
				)
			)
		)
		(pad "119" smd custom
			(at 6.150102 -4.100068)
			(size 0.1143 0.1143)
			(layers "B.Cu" "B.Mask" "B.Paste")
			(net "M_A_BS0")
			(options
				(clearance outline)
				(anchor circle)
			)
			(primitives
				(gr_poly
					(pts
						(xy 0 -0.9017) (xy -0.03175 -0.89916) (xy -0.0635 -0.889) (xy -0.09144 -0.87376) (xy -0.11684 -0.85344)
						(xy -0.13716 -0.82804) (xy -0.1524 -0.8001) (xy -0.16256 -0.76835) (xy -0.1651 -0.7366) (xy -0.1651 -0.19685)
						(xy -0.17272 -0.18923) (xy -0.17907 -0.18034) (xy -0.18669 -0.17145) (xy -0.19177 -0.16256) (xy -0.19812 -0.15367)
						(xy -0.20828 -0.13335) (xy -0.21971 -0.10287) (xy -0.22225 -0.09271) (xy -0.22479 -0.08128) (xy -0.22606 -0.07112)
						(xy -0.2286 -0.05969) (xy -0.2286 -0.01651) (xy -0.22606 -0.00508) (xy -0.22479 0.00508) (xy -0.22225 0.01651)
						(xy -0.21971 0.02667) (xy -0.20828 0.05715) (xy -0.19812 0.07747) (xy -0.19177 0.08636) (xy -0.18669 0.09525)
						(xy -0.17907 0.10414) (xy -0.17272 0.11303) (xy -0.1651 0.12065) (xy -0.1651 0.7366) (xy -0.16256 0.76835)
						(xy -0.1524 0.8001) (xy -0.13716 0.82804) (xy -0.11684 0.85344) (xy -0.09144 0.87376) (xy -0.0635 0.889)
						(xy -0.03175 0.89916) (xy 0 0.9017) (xy 0.03175 0.89916) (xy 0.0635 0.889) (xy 0.09144 0.87376)
						(xy 0.11684 0.85344) (xy 0.13716 0.82804) (xy 0.1524 0.8001) (xy 0.16256 0.76835) (xy 0.1651 0.7366)
						(xy 0.1651 0.11938) (xy 0.17272 0.11176) (xy 0.19812 0.0762) (xy 0.2032 0.06604) (xy 0.20701 0.05715)
						(xy 0.21209 0.04699) (xy 0.2159 0.03683) (xy 0.21844 0.02667) (xy 0.22225 0.01524) (xy 0.22352 0.00508)
						(xy 0.22606 -0.00508) (xy 0.22733 -0.01651) (xy 0.22733 -0.02667) (xy 0.2286 -0.0381) (xy 0.22733 -0.04953)
						(xy 0.22733 -0.05969) (xy 0.22606 -0.07112) (xy 0.22352 -0.08128) (xy 0.22225 -0.09144) (xy 0.21844 -0.10287)
						(xy 0.2159 -0.11303) (xy 0.21209 -0.12319) (xy 0.20701 -0.13335) (xy 0.2032 -0.14224) (xy 0.19812 -0.1524)
						(xy 0.17272 -0.18796) (xy 0.1651 -0.19558) (xy 0.1651 -0.7366) (xy 0.16256 -0.76835) (xy 0.1524 -0.8001)
						(xy 0.13716 -0.82804) (xy 0.11684 -0.85344) (xy 0.09144 -0.87376) (xy 0.0635 -0.889) (xy 0.03175 -0.89916)
					)
					(width 0)
					(fill yes)
				)
			)
		)
		(pad "120" smd custom
			(at 6.450076 4.100068)
			(size 0.1143 0.1143)
			(layers "B.Cu" "B.Mask" "B.Paste")
			(net "Net_15")
			(options
				(clearance outline)
				(anchor circle)
			)
			(primitives
				(gr_poly
					(pts
						(xy 0 -0.9017) (xy -0.03175 -0.89916) (xy -0.0635 -0.889) (xy -0.09144 -0.87376) (xy -0.11684 -0.85344)
						(xy -0.13716 -0.82804) (xy -0.1524 -0.8001) (xy -0.16256 -0.76835) (xy -0.1651 -0.7366) (xy -0.1651 -0.11938)
						(xy -0.17272 -0.11176) (xy -0.19812 -0.0762) (xy -0.2032 -0.06604) (xy -0.20701 -0.05715) (xy -0.21209 -0.04699)
						(xy -0.2159 -0.03683) (xy -0.21844 -0.02667) (xy -0.22225 -0.01524) (xy -0.22352 -0.00508) (xy -0.22606 0.00508)
						(xy -0.22733 0.01651) (xy -0.22733 0.02667) (xy -0.2286 0.0381) (xy -0.22733 0.04953) (xy -0.22733 0.05969)
						(xy -0.22606 0.07112) (xy -0.22352 0.08128) (xy -0.22225 0.09144) (xy -0.21844 0.10287) (xy -0.2159 0.11303)
						(xy -0.21209 0.12319) (xy -0.20701 0.13335) (xy -0.2032 0.14224) (xy -0.19812 0.1524) (xy -0.17272 0.18796)
						(xy -0.1651 0.19558) (xy -0.1651 0.7366) (xy -0.16256 0.76835) (xy -0.1524 0.8001) (xy -0.13716 0.82804)
						(xy -0.11684 0.85344) (xy -0.09144 0.87376) (xy -0.0635 0.889) (xy -0.03175 0.89916) (xy 0 0.9017)
						(xy 0.03175 0.89916) (xy 0.0635 0.889) (xy 0.09144 0.87376) (xy 0.11684 0.85344) (xy 0.13716 0.82804)
						(xy 0.1524 0.8001) (xy 0.16256 0.76835) (xy 0.1651 0.7366) (xy 0.1651 0.19685) (xy 0.17272 0.18923)
						(xy 0.17907 0.18034) (xy 0.18669 0.17145) (xy 0.19177 0.16256) (xy 0.19812 0.15367) (xy 0.20828 0.13335)
						(xy 0.21971 0.10287) (xy 0.22225 0.09271) (xy 0.22479 0.08128) (xy 0.22606 0.07112) (xy 0.2286 0.05969)
						(xy 0.2286 0.01651) (xy 0.22606 0.00508) (xy 0.22479 -0.00508) (xy 0.22225 -0.01651) (xy 0.21971 -0.02667)
						(xy 0.20828 -0.05715) (xy 0.19812 -0.07747) (xy 0.19177 -0.08636) (xy 0.18669 -0.09525) (xy 0.17907 -0.10414)
						(xy 0.17272 -0.11303) (xy 0.1651 -0.12065) (xy 0.1651 -0.7366) (xy 0.16256 -0.76835) (xy 0.1524 -0.8001)
						(xy 0.13716 -0.82804) (xy 0.11684 -0.85344) (xy 0.09144 -0.87376) (xy 0.0635 -0.889) (xy 0.03175 -0.89916)
					)
					(width 0)
					(fill yes)
				)
			)
		)
		(pad "121" smd custom
			(at 6.75005 -4.100068)
			(size 0.1143 0.1143)
			(layers "B.Cu" "B.Mask" "B.Paste")
			(net "M_A_WE#")
			(options
				(clearance outline)
				(anchor circle)
			)
			(primitives
				(gr_poly
					(pts
						(xy 0 -0.9017) (xy -0.03175 -0.89916) (xy -0.0635 -0.889) (xy -0.09144 -0.87376) (xy -0.11684 -0.85344)
						(xy -0.13716 -0.82804) (xy -0.1524 -0.8001) (xy -0.16256 -0.76835) (xy -0.1651 -0.7366) (xy -0.1651 -0.44958)
						(xy -0.17272 -0.44196) (xy -0.19812 -0.4064) (xy -0.2032 -0.39624) (xy -0.20701 -0.38735) (xy -0.21209 -0.37719)
						(xy -0.2159 -0.36703) (xy -0.21844 -0.35687) (xy -0.22225 -0.34544) (xy -0.22352 -0.33528) (xy -0.22606 -0.32512)
						(xy -0.22733 -0.31369) (xy -0.22733 -0.30353) (xy -0.2286 -0.2921) (xy -0.22733 -0.28067) (xy -0.22733 -0.27051)
						(xy -0.22606 -0.25908) (xy -0.22352 -0.24892) (xy -0.22225 -0.23876) (xy -0.21844 -0.22733) (xy -0.2159 -0.21717)
						(xy -0.21209 -0.20701) (xy -0.20701 -0.19685) (xy -0.2032 -0.18796) (xy -0.19812 -0.1778) (xy -0.17272 -0.14224)
						(xy -0.1651 -0.13462) (xy -0.1651 0.7366) (xy -0.16256 0.76835) (xy -0.1524 0.8001) (xy -0.13716 0.82804)
						(xy -0.11684 0.85344) (xy -0.09144 0.87376) (xy -0.0635 0.889) (xy -0.03175 0.89916) (xy 0 0.9017)
						(xy 0.03175 0.89916) (xy 0.0635 0.889) (xy 0.09144 0.87376) (xy 0.11684 0.85344) (xy 0.13716 0.82804)
						(xy 0.1524 0.8001) (xy 0.16256 0.76835) (xy 0.1651 0.7366) (xy 0.1651 -0.13462) (xy 0.17272 -0.14224)
						(xy 0.19812 -0.1778) (xy 0.2032 -0.18796) (xy 0.20701 -0.19685) (xy 0.21209 -0.20701) (xy 0.2159 -0.21717)
						(xy 0.21844 -0.22733) (xy 0.22225 -0.23876) (xy 0.22352 -0.24892) (xy 0.22606 -0.25908) (xy 0.22733 -0.27051)
						(xy 0.22733 -0.28067) (xy 0.2286 -0.2921) (xy 0.22733 -0.30353) (xy 0.22733 -0.31369) (xy 0.22606 -0.32512)
						(xy 0.22352 -0.33528) (xy 0.22225 -0.34544) (xy 0.21844 -0.35687) (xy 0.2159 -0.36703) (xy 0.21209 -0.37719)
						(xy 0.20701 -0.38735) (xy 0.2032 -0.39624) (xy 0.19812 -0.4064) (xy 0.17272 -0.44196) (xy 0.1651 -0.44958)
						(xy 0.1651 -0.7366) (xy 0.16256 -0.76835) (xy 0.1524 -0.8001) (xy 0.13716 -0.82804) (xy 0.11684 -0.85344)
						(xy 0.09144 -0.87376) (xy 0.0635 -0.889) (xy 0.03175 -0.89916)
					)
					(width 0)
					(fill yes)
				)
			)
		)
		(pad "122" smd custom
			(at 7.050024 4.100068)
			(size 0.1143 0.1143)
			(layers "B.Cu" "B.Mask" "B.Paste")
			(net "M_A_RAS#")
			(options
				(clearance outline)
				(anchor circle)
			)
			(primitives
				(gr_poly
					(pts
						(xy 0 -0.9017) (xy -0.03175 -0.89916) (xy -0.0635 -0.889) (xy -0.09144 -0.87376) (xy -0.11684 -0.85344)
						(xy -0.13716 -0.82804) (xy -0.1524 -0.8001) (xy -0.16256 -0.76835) (xy -0.1651 -0.7366) (xy -0.1651 0.13462)
						(xy -0.17272 0.14224) (xy -0.19812 0.1778) (xy -0.2032 0.18796) (xy -0.20701 0.19685) (xy -0.21209 0.20701)
						(xy -0.2159 0.21717) (xy -0.21844 0.22733) (xy -0.22225 0.23876) (xy -0.22352 0.24892) (xy -0.22606 0.25908)
						(xy -0.22733 0.27051) (xy -0.22733 0.28067) (xy -0.2286 0.2921) (xy -0.22733 0.30353) (xy -0.22733 0.31369)
						(xy -0.22606 0.32512) (xy -0.22352 0.33528) (xy -0.22225 0.34544) (xy -0.21844 0.35687) (xy -0.2159 0.36703)
						(xy -0.21209 0.37719) (xy -0.20701 0.38735) (xy -0.2032 0.39624) (xy -0.19812 0.4064) (xy -0.17272 0.44196)
						(xy -0.1651 0.44958) (xy -0.1651 0.7366) (xy -0.16256 0.76835) (xy -0.1524 0.8001) (xy -0.13716 0.82804)
						(xy -0.11684 0.85344) (xy -0.09144 0.87376) (xy -0.0635 0.889) (xy -0.03175 0.89916) (xy 0 0.9017)
						(xy 0.03175 0.89916) (xy 0.0635 0.889) (xy 0.09144 0.87376) (xy 0.11684 0.85344) (xy 0.13716 0.82804)
						(xy 0.1524 0.8001) (xy 0.16256 0.76835) (xy 0.1651 0.7366) (xy 0.1651 0.44958) (xy 0.17272 0.44196)
						(xy 0.19812 0.4064) (xy 0.2032 0.39624) (xy 0.20701 0.38735) (xy 0.21209 0.37719) (xy 0.2159 0.36703)
						(xy 0.21844 0.35687) (xy 0.22225 0.34544) (xy 0.22352 0.33528) (xy 0.22606 0.32512) (xy 0.22733 0.31369)
						(xy 0.22733 0.30353) (xy 0.2286 0.2921) (xy 0.22733 0.28067) (xy 0.22733 0.27051) (xy 0.22606 0.25908)
						(xy 0.22352 0.24892) (xy 0.22225 0.23876) (xy 0.21844 0.22733) (xy 0.2159 0.21717) (xy 0.21209 0.20701)
						(xy 0.20701 0.19685) (xy 0.2032 0.18796) (xy 0.19812 0.1778) (xy 0.17272 0.14224) (xy 0.1651 0.13462)
						(xy 0.1651 -0.7366) (xy 0.16256 -0.76835) (xy 0.1524 -0.8001) (xy 0.13716 -0.82804) (xy 0.11684 -0.85344)
						(xy 0.09144 -0.87376) (xy 0.0635 -0.889) (xy 0.03175 -0.89916)
					)
					(width 0)
					(fill yes)
				)
			)
		)
		(pad "123" smd custom
			(at 7.349998 -4.100068)
			(size 0.1143 0.1143)
			(layers "B.Cu" "B.Mask" "B.Paste")
			(net "PV_VDDR")
			(options
				(clearance outline)
				(anchor circle)
			)
			(primitives
				(gr_poly
					(pts
						(xy 0 -0.9017) (xy -0.03175 -0.89916) (xy -0.0635 -0.889) (xy -0.09144 -0.87376) (xy -0.11684 -0.85344)
						(xy -0.13716 -0.82804) (xy -0.1524 -0.8001) (xy -0.16256 -0.76835) (xy -0.1651 -0.7366) (xy -0.1651 -0.19685)
						(xy -0.17272 -0.18923) (xy -0.17907 -0.18034) (xy -0.18669 -0.17145) (xy -0.19177 -0.16256) (xy -0.19812 -0.15367)
						(xy -0.20828 -0.13335) (xy -0.21971 -0.10287) (xy -0.22225 -0.09271) (xy -0.22479 -0.08128) (xy -0.22606 -0.07112)
						(xy -0.2286 -0.05969) (xy -0.2286 -0.01651) (xy -0.22606 -0.00508) (xy -0.22479 0.00508) (xy -0.22225 0.01651)
						(xy -0.21971 0.02667) (xy -0.20828 0.05715) (xy -0.19812 0.07747) (xy -0.19177 0.08636) (xy -0.18669 0.09525)
						(xy -0.17907 0.10414) (xy -0.17272 0.11303) (xy -0.1651 0.12065) (xy -0.1651 0.7366) (xy -0.16256 0.76835)
						(xy -0.1524 0.8001) (xy -0.13716 0.82804) (xy -0.11684 0.85344) (xy -0.09144 0.87376) (xy -0.0635 0.889)
						(xy -0.03175 0.89916) (xy 0 0.9017) (xy 0.03175 0.89916) (xy 0.0635 0.889) (xy 0.09144 0.87376)
						(xy 0.11684 0.85344) (xy 0.13716 0.82804) (xy 0.1524 0.8001) (xy 0.16256 0.76835) (xy 0.1651 0.7366)
						(xy 0.1651 0.11938) (xy 0.17272 0.11176) (xy 0.19812 0.0762) (xy 0.2032 0.06604) (xy 0.20701 0.05715)
						(xy 0.21209 0.04699) (xy 0.2159 0.03683) (xy 0.21844 0.02667) (xy 0.22225 0.01524) (xy 0.22352 0.00508)
						(xy 0.22606 -0.00508) (xy 0.22733 -0.01651) (xy 0.22733 -0.02667) (xy 0.2286 -0.0381) (xy 0.22733 -0.04953)
						(xy 0.22733 -0.05969) (xy 0.22606 -0.07112) (xy 0.22352 -0.08128) (xy 0.22225 -0.09144) (xy 0.21844 -0.10287)
						(xy 0.2159 -0.11303) (xy 0.21209 -0.12319) (xy 0.20701 -0.13335) (xy 0.2032 -0.14224) (xy 0.19812 -0.1524)
						(xy 0.17272 -0.18796) (xy 0.1651 -0.19558) (xy 0.1651 -0.7366) (xy 0.16256 -0.76835) (xy 0.1524 -0.8001)
						(xy 0.13716 -0.82804) (xy 0.11684 -0.85344) (xy 0.09144 -0.87376) (xy 0.0635 -0.889) (xy 0.03175 -0.89916)
					)
					(width 0)
					(fill yes)
				)
			)
		)
		(pad "124" smd custom
			(at 7.649972 4.100068)
			(size 0.1143 0.1143)
			(layers "B.Cu" "B.Mask" "B.Paste")
			(net "PV_VDDR")
			(options
				(clearance outline)
				(anchor circle)
			)
			(primitives
				(gr_poly
					(pts
						(xy 0 -0.9017) (xy -0.03175 -0.89916) (xy -0.0635 -0.889) (xy -0.09144 -0.87376) (xy -0.11684 -0.85344)
						(xy -0.13716 -0.82804) (xy -0.1524 -0.8001) (xy -0.16256 -0.76835) (xy -0.1651 -0.7366) (xy -0.1651 -0.11938)
						(xy -0.17272 -0.11176) (xy -0.19812 -0.0762) (xy -0.2032 -0.06604) (xy -0.20701 -0.05715) (xy -0.21209 -0.04699)
						(xy -0.2159 -0.03683) (xy -0.21844 -0.02667) (xy -0.22225 -0.01524) (xy -0.22352 -0.00508) (xy -0.22606 0.00508)
						(xy -0.22733 0.01651) (xy -0.22733 0.02667) (xy -0.2286 0.0381) (xy -0.22733 0.04953) (xy -0.22733 0.05969)
						(xy -0.22606 0.07112) (xy -0.22352 0.08128) (xy -0.22225 0.09144) (xy -0.21844 0.10287) (xy -0.2159 0.11303)
						(xy -0.21209 0.12319) (xy -0.20701 0.13335) (xy -0.2032 0.14224) (xy -0.19812 0.1524) (xy -0.17272 0.18796)
						(xy -0.1651 0.19558) (xy -0.1651 0.7366) (xy -0.16256 0.76835) (xy -0.1524 0.8001) (xy -0.13716 0.82804)
						(xy -0.11684 0.85344) (xy -0.09144 0.87376) (xy -0.0635 0.889) (xy -0.03175 0.89916) (xy 0 0.9017)
						(xy 0.03175 0.89916) (xy 0.0635 0.889) (xy 0.09144 0.87376) (xy 0.11684 0.85344) (xy 0.13716 0.82804)
						(xy 0.1524 0.8001) (xy 0.16256 0.76835) (xy 0.1651 0.7366) (xy 0.1651 0.19685) (xy 0.17272 0.18923)
						(xy 0.17907 0.18034) (xy 0.18669 0.17145) (xy 0.19177 0.16256) (xy 0.19812 0.15367) (xy 0.20828 0.13335)
						(xy 0.21971 0.10287) (xy 0.22225 0.09271) (xy 0.22479 0.08128) (xy 0.22606 0.07112) (xy 0.2286 0.05969)
						(xy 0.2286 0.01651) (xy 0.22606 0.00508) (xy 0.22479 -0.00508) (xy 0.22225 -0.01651) (xy 0.21971 -0.02667)
						(xy 0.20828 -0.05715) (xy 0.19812 -0.07747) (xy 0.19177 -0.08636) (xy 0.18669 -0.09525) (xy 0.17907 -0.10414)
						(xy 0.17272 -0.11303) (xy 0.1651 -0.12065) (xy 0.1651 -0.7366) (xy 0.16256 -0.76835) (xy 0.1524 -0.8001)
						(xy 0.13716 -0.82804) (xy 0.11684 -0.85344) (xy 0.09144 -0.87376) (xy 0.0635 -0.889) (xy 0.03175 -0.89916)
					)
					(width 0)
					(fill yes)
				)
			)
		)
		(pad "125" smd custom
			(at 7.949946 -4.100068)
			(size 0.1143 0.1143)
			(layers "B.Cu" "B.Mask" "B.Paste")
			(net "M_A_CAS#")
			(options
				(clearance outline)
				(anchor circle)
			)
			(primitives
				(gr_poly
					(pts
						(xy 0 -0.9017) (xy -0.03175 -0.89916) (xy -0.0635 -0.889) (xy -0.09144 -0.87376) (xy -0.11684 -0.85344)
						(xy -0.13716 -0.82804) (xy -0.1524 -0.8001) (xy -0.16256 -0.76835) (xy -0.1651 -0.7366) (xy -0.1651 -0.44958)
						(xy -0.17272 -0.44196) (xy -0.19812 -0.4064) (xy -0.2032 -0.39624) (xy -0.20701 -0.38735) (xy -0.21209 -0.37719)
						(xy -0.2159 -0.36703) (xy -0.21844 -0.35687) (xy -0.22225 -0.34544) (xy -0.22352 -0.33528) (xy -0.22606 -0.32512)
						(xy -0.22733 -0.31369) (xy -0.22733 -0.30353) (xy -0.2286 -0.2921) (xy -0.22733 -0.28067) (xy -0.22733 -0.27051)
						(xy -0.22606 -0.25908) (xy -0.22352 -0.24892) (xy -0.22225 -0.23876) (xy -0.21844 -0.22733) (xy -0.2159 -0.21717)
						(xy -0.21209 -0.20701) (xy -0.20701 -0.19685) (xy -0.2032 -0.18796) (xy -0.19812 -0.1778) (xy -0.17272 -0.14224)
						(xy -0.1651 -0.13462) (xy -0.1651 0.7366) (xy -0.16256 0.76835) (xy -0.1524 0.8001) (xy -0.13716 0.82804)
						(xy -0.11684 0.85344) (xy -0.09144 0.87376) (xy -0.0635 0.889) (xy -0.03175 0.89916) (xy 0 0.9017)
						(xy 0.03175 0.89916) (xy 0.0635 0.889) (xy 0.09144 0.87376) (xy 0.11684 0.85344) (xy 0.13716 0.82804)
						(xy 0.1524 0.8001) (xy 0.16256 0.76835) (xy 0.1651 0.7366) (xy 0.1651 -0.13462) (xy 0.17272 -0.14224)
						(xy 0.19812 -0.1778) (xy 0.2032 -0.18796) (xy 0.20701 -0.19685) (xy 0.21209 -0.20701) (xy 0.2159 -0.21717)
						(xy 0.21844 -0.22733) (xy 0.22225 -0.23876) (xy 0.22352 -0.24892) (xy 0.22606 -0.25908) (xy 0.22733 -0.27051)
						(xy 0.22733 -0.28067) (xy 0.2286 -0.2921) (xy 0.22733 -0.30353) (xy 0.22733 -0.31369) (xy 0.22606 -0.32512)
						(xy 0.22352 -0.33528) (xy 0.22225 -0.34544) (xy 0.21844 -0.35687) (xy 0.2159 -0.36703) (xy 0.21209 -0.37719)
						(xy 0.20701 -0.38735) (xy 0.2032 -0.39624) (xy 0.19812 -0.4064) (xy 0.17272 -0.44196) (xy 0.1651 -0.44958)
						(xy 0.1651 -0.7366) (xy 0.16256 -0.76835) (xy 0.1524 -0.8001) (xy 0.13716 -0.82804) (xy 0.11684 -0.85344)
						(xy 0.09144 -0.87376) (xy 0.0635 -0.889) (xy 0.03175 -0.89916)
					)
					(width 0)
					(fill yes)
				)
			)
		)
		(pad "126" smd custom
			(at 8.24992 4.100068)
			(size 0.1143 0.1143)
			(layers "B.Cu" "B.Mask" "B.Paste")
			(net "M_A_ODT0")
			(options
				(clearance outline)
				(anchor circle)
			)
			(primitives
				(gr_poly
					(pts
						(xy 0 -0.9017) (xy -0.03175 -0.89916) (xy -0.0635 -0.889) (xy -0.09144 -0.87376) (xy -0.11684 -0.85344)
						(xy -0.13716 -0.82804) (xy -0.1524 -0.8001) (xy -0.16256 -0.76835) (xy -0.1651 -0.7366) (xy -0.1651 0.13462)
						(xy -0.17272 0.14224) (xy -0.19812 0.1778) (xy -0.2032 0.18796) (xy -0.20701 0.19685) (xy -0.21209 0.20701)
						(xy -0.2159 0.21717) (xy -0.21844 0.22733) (xy -0.22225 0.23876) (xy -0.22352 0.24892) (xy -0.22606 0.25908)
						(xy -0.22733 0.27051) (xy -0.22733 0.28067) (xy -0.2286 0.2921) (xy -0.22733 0.30353) (xy -0.22733 0.31369)
						(xy -0.22606 0.32512) (xy -0.22352 0.33528) (xy -0.22225 0.34544) (xy -0.21844 0.35687) (xy -0.2159 0.36703)
						(xy -0.21209 0.37719) (xy -0.20701 0.38735) (xy -0.2032 0.39624) (xy -0.19812 0.4064) (xy -0.17272 0.44196)
						(xy -0.1651 0.44958) (xy -0.1651 0.7366) (xy -0.16256 0.76835) (xy -0.1524 0.8001) (xy -0.13716 0.82804)
						(xy -0.11684 0.85344) (xy -0.09144 0.87376) (xy -0.0635 0.889) (xy -0.03175 0.89916) (xy 0 0.9017)
						(xy 0.03175 0.89916) (xy 0.0635 0.889) (xy 0.09144 0.87376) (xy 0.11684 0.85344) (xy 0.13716 0.82804)
						(xy 0.1524 0.8001) (xy 0.16256 0.76835) (xy 0.1651 0.7366) (xy 0.1651 0.44958) (xy 0.17272 0.44196)
						(xy 0.19812 0.4064) (xy 0.2032 0.39624) (xy 0.20701 0.38735) (xy 0.21209 0.37719) (xy 0.2159 0.36703)
						(xy 0.21844 0.35687) (xy 0.22225 0.34544) (xy 0.22352 0.33528) (xy 0.22606 0.32512) (xy 0.22733 0.31369)
						(xy 0.22733 0.30353) (xy 0.2286 0.2921) (xy 0.22733 0.28067) (xy 0.22733 0.27051) (xy 0.22606 0.25908)
						(xy 0.22352 0.24892) (xy 0.22225 0.23876) (xy 0.21844 0.22733) (xy 0.2159 0.21717) (xy 0.21209 0.20701)
						(xy 0.20701 0.19685) (xy 0.2032 0.18796) (xy 0.19812 0.1778) (xy 0.17272 0.14224) (xy 0.1651 0.13462)
						(xy 0.1651 -0.7366) (xy 0.16256 -0.76835) (xy 0.1524 -0.8001) (xy 0.13716 -0.82804) (xy 0.11684 -0.85344)
						(xy 0.09144 -0.87376) (xy 0.0635 -0.889) (xy 0.03175 -0.89916)
					)
					(width 0)
					(fill yes)
				)
			)
		)
		(pad "127" smd custom
			(at 8.549894 -4.100068)
			(size 0.1143 0.1143)
			(layers "B.Cu" "B.Mask" "B.Paste")
			(net "M_A_CS_N0")
			(options
				(clearance outline)
				(anchor circle)
			)
			(primitives
				(gr_poly
					(pts
						(xy 0 -0.9017) (xy -0.03175 -0.89916) (xy -0.0635 -0.889) (xy -0.09144 -0.87376) (xy -0.11684 -0.85344)
						(xy -0.13716 -0.82804) (xy -0.1524 -0.8001) (xy -0.16256 -0.76835) (xy -0.1651 -0.7366) (xy -0.1651 -0.19685)
						(xy -0.17272 -0.18923) (xy -0.17907 -0.18034) (xy -0.18669 -0.17145) (xy -0.19177 -0.16256) (xy -0.19812 -0.15367)
						(xy -0.20828 -0.13335) (xy -0.21971 -0.10287) (xy -0.22225 -0.09271) (xy -0.22479 -0.08128) (xy -0.22606 -0.07112)
						(xy -0.2286 -0.05969) (xy -0.2286 -0.01651) (xy -0.22606 -0.00508) (xy -0.22479 0.00508) (xy -0.22225 0.01651)
						(xy -0.21971 0.02667) (xy -0.20828 0.05715) (xy -0.19812 0.07747) (xy -0.19177 0.08636) (xy -0.18669 0.09525)
						(xy -0.17907 0.10414) (xy -0.17272 0.11303) (xy -0.1651 0.12065) (xy -0.1651 0.7366) (xy -0.16256 0.76835)
						(xy -0.1524 0.8001) (xy -0.13716 0.82804) (xy -0.11684 0.85344) (xy -0.09144 0.87376) (xy -0.0635 0.889)
						(xy -0.03175 0.89916) (xy 0 0.9017) (xy 0.03175 0.89916) (xy 0.0635 0.889) (xy 0.09144 0.87376)
						(xy 0.11684 0.85344) (xy 0.13716 0.82804) (xy 0.1524 0.8001) (xy 0.16256 0.76835) (xy 0.1651 0.7366)
						(xy 0.1651 0.11938) (xy 0.17272 0.11176) (xy 0.19812 0.0762) (xy 0.2032 0.06604) (xy 0.20701 0.05715)
						(xy 0.21209 0.04699) (xy 0.2159 0.03683) (xy 0.21844 0.02667) (xy 0.22225 0.01524) (xy 0.22352 0.00508)
						(xy 0.22606 -0.00508) (xy 0.22733 -0.01651) (xy 0.22733 -0.02667) (xy 0.2286 -0.0381) (xy 0.22733 -0.04953)
						(xy 0.22733 -0.05969) (xy 0.22606 -0.07112) (xy 0.22352 -0.08128) (xy 0.22225 -0.09144) (xy 0.21844 -0.10287)
						(xy 0.2159 -0.11303) (xy 0.21209 -0.12319) (xy 0.20701 -0.13335) (xy 0.2032 -0.14224) (xy 0.19812 -0.1524)
						(xy 0.17272 -0.18796) (xy 0.1651 -0.19558) (xy 0.1651 -0.7366) (xy 0.16256 -0.76835) (xy 0.1524 -0.8001)
						(xy 0.13716 -0.82804) (xy 0.11684 -0.85344) (xy 0.09144 -0.87376) (xy 0.0635 -0.889) (xy 0.03175 -0.89916)
					)
					(width 0)
					(fill yes)
				)
			)
		)
		(pad "128" smd custom
			(at 8.850122 4.100068)
			(size 0.1143 0.1143)
			(layers "B.Cu" "B.Mask" "B.Paste")
			(net "M_A_ODT1")
			(options
				(clearance outline)
				(anchor circle)
			)
			(primitives
				(gr_poly
					(pts
						(xy 0 -0.9017) (xy -0.03175 -0.89916) (xy -0.0635 -0.889) (xy -0.09144 -0.87376) (xy -0.11684 -0.85344)
						(xy -0.13716 -0.82804) (xy -0.1524 -0.8001) (xy -0.16256 -0.76835) (xy -0.1651 -0.7366) (xy -0.1651 -0.11938)
						(xy -0.17272 -0.11176) (xy -0.19812 -0.0762) (xy -0.2032 -0.06604) (xy -0.20701 -0.05715) (xy -0.21209 -0.04699)
						(xy -0.2159 -0.03683) (xy -0.21844 -0.02667) (xy -0.22225 -0.01524) (xy -0.22352 -0.00508) (xy -0.22606 0.00508)
						(xy -0.22733 0.01651) (xy -0.22733 0.02667) (xy -0.2286 0.0381) (xy -0.22733 0.04953) (xy -0.22733 0.05969)
						(xy -0.22606 0.07112) (xy -0.22352 0.08128) (xy -0.22225 0.09144) (xy -0.21844 0.10287) (xy -0.2159 0.11303)
						(xy -0.21209 0.12319) (xy -0.20701 0.13335) (xy -0.2032 0.14224) (xy -0.19812 0.1524) (xy -0.17272 0.18796)
						(xy -0.1651 0.19558) (xy -0.1651 0.7366) (xy -0.16256 0.76835) (xy -0.1524 0.8001) (xy -0.13716 0.82804)
						(xy -0.11684 0.85344) (xy -0.09144 0.87376) (xy -0.0635 0.889) (xy -0.03175 0.89916) (xy 0 0.9017)
						(xy 0.03175 0.89916) (xy 0.0635 0.889) (xy 0.09144 0.87376) (xy 0.11684 0.85344) (xy 0.13716 0.82804)
						(xy 0.1524 0.8001) (xy 0.16256 0.76835) (xy 0.1651 0.7366) (xy 0.1651 0.19685) (xy 0.17272 0.18923)
						(xy 0.17907 0.18034) (xy 0.18669 0.17145) (xy 0.19177 0.16256) (xy 0.19812 0.15367) (xy 0.20828 0.13335)
						(xy 0.21971 0.10287) (xy 0.22225 0.09271) (xy 0.22479 0.08128) (xy 0.22606 0.07112) (xy 0.2286 0.05969)
						(xy 0.2286 0.01651) (xy 0.22606 0.00508) (xy 0.22479 -0.00508) (xy 0.22225 -0.01651) (xy 0.21971 -0.02667)
						(xy 0.20828 -0.05715) (xy 0.19812 -0.07747) (xy 0.19177 -0.08636) (xy 0.18669 -0.09525) (xy 0.17907 -0.10414)
						(xy 0.17272 -0.11303) (xy 0.1651 -0.12065) (xy 0.1651 -0.7366) (xy 0.16256 -0.76835) (xy 0.1524 -0.8001)
						(xy 0.13716 -0.82804) (xy 0.11684 -0.85344) (xy 0.09144 -0.87376) (xy 0.0635 -0.889) (xy 0.03175 -0.89916)
					)
					(width 0)
					(fill yes)
				)
			)
		)
		(pad "129" smd custom
			(at 9.150096 -4.100068)
			(size 0.1143 0.1143)
			(layers "B.Cu" "B.Mask" "B.Paste")
			(net "M_A_CS_N1")
			(options
				(clearance outline)
				(anchor circle)
			)
			(primitives
				(gr_poly
					(pts
						(xy 0 -0.9017) (xy -0.03175 -0.89916) (xy -0.0635 -0.889) (xy -0.09144 -0.87376) (xy -0.11684 -0.85344)
						(xy -0.13716 -0.82804) (xy -0.1524 -0.8001) (xy -0.16256 -0.76835) (xy -0.1651 -0.7366) (xy -0.1651 -0.44958)
						(xy -0.17272 -0.44196) (xy -0.19812 -0.4064) (xy -0.2032 -0.39624) (xy -0.20701 -0.38735) (xy -0.21209 -0.37719)
						(xy -0.2159 -0.36703) (xy -0.21844 -0.35687) (xy -0.22225 -0.34544) (xy -0.22352 -0.33528) (xy -0.22606 -0.32512)
						(xy -0.22733 -0.31369) (xy -0.22733 -0.30353) (xy -0.2286 -0.2921) (xy -0.22733 -0.28067) (xy -0.22733 -0.27051)
						(xy -0.22606 -0.25908) (xy -0.22352 -0.24892) (xy -0.22225 -0.23876) (xy -0.21844 -0.22733) (xy -0.2159 -0.21717)
						(xy -0.21209 -0.20701) (xy -0.20701 -0.19685) (xy -0.2032 -0.18796) (xy -0.19812 -0.1778) (xy -0.17272 -0.14224)
						(xy -0.1651 -0.13462) (xy -0.1651 0.7366) (xy -0.16256 0.76835) (xy -0.1524 0.8001) (xy -0.13716 0.82804)
						(xy -0.11684 0.85344) (xy -0.09144 0.87376) (xy -0.0635 0.889) (xy -0.03175 0.89916) (xy 0 0.9017)
						(xy 0.03175 0.89916) (xy 0.0635 0.889) (xy 0.09144 0.87376) (xy 0.11684 0.85344) (xy 0.13716 0.82804)
						(xy 0.1524 0.8001) (xy 0.16256 0.76835) (xy 0.1651 0.7366) (xy 0.1651 -0.13462) (xy 0.17272 -0.14224)
						(xy 0.19812 -0.1778) (xy 0.2032 -0.18796) (xy 0.20701 -0.19685) (xy 0.21209 -0.20701) (xy 0.2159 -0.21717)
						(xy 0.21844 -0.22733) (xy 0.22225 -0.23876) (xy 0.22352 -0.24892) (xy 0.22606 -0.25908) (xy 0.22733 -0.27051)
						(xy 0.22733 -0.28067) (xy 0.2286 -0.2921) (xy 0.22733 -0.30353) (xy 0.22733 -0.31369) (xy 0.22606 -0.32512)
						(xy 0.22352 -0.33528) (xy 0.22225 -0.34544) (xy 0.21844 -0.35687) (xy 0.2159 -0.36703) (xy 0.21209 -0.37719)
						(xy 0.20701 -0.38735) (xy 0.2032 -0.39624) (xy 0.19812 -0.4064) (xy 0.17272 -0.44196) (xy 0.1651 -0.44958)
						(xy 0.1651 -0.7366) (xy 0.16256 -0.76835) (xy 0.1524 -0.8001) (xy 0.13716 -0.82804) (xy 0.11684 -0.85344)
						(xy 0.09144 -0.87376) (xy 0.0635 -0.889) (xy 0.03175 -0.89916)
					)
					(width 0)
					(fill yes)
				)
			)
		)
		(pad "130" smd custom
			(at 9.45007 4.100068)
			(size 0.1143 0.1143)
			(layers "B.Cu" "B.Mask" "B.Paste")
			(net "M_A_MA13")
			(options
				(clearance outline)
				(anchor circle)
			)
			(primitives
				(gr_poly
					(pts
						(xy 0 -0.9017) (xy -0.03175 -0.89916) (xy -0.0635 -0.889) (xy -0.09144 -0.87376) (xy -0.11684 -0.85344)
						(xy -0.13716 -0.82804) (xy -0.1524 -0.8001) (xy -0.16256 -0.76835) (xy -0.1651 -0.7366) (xy -0.1651 0.13462)
						(xy -0.17272 0.14224) (xy -0.19812 0.1778) (xy -0.2032 0.18796) (xy -0.20701 0.19685) (xy -0.21209 0.20701)
						(xy -0.2159 0.21717) (xy -0.21844 0.22733) (xy -0.22225 0.23876) (xy -0.22352 0.24892) (xy -0.22606 0.25908)
						(xy -0.22733 0.27051) (xy -0.22733 0.28067) (xy -0.2286 0.2921) (xy -0.22733 0.30353) (xy -0.22733 0.31369)
						(xy -0.22606 0.32512) (xy -0.22352 0.33528) (xy -0.22225 0.34544) (xy -0.21844 0.35687) (xy -0.2159 0.36703)
						(xy -0.21209 0.37719) (xy -0.20701 0.38735) (xy -0.2032 0.39624) (xy -0.19812 0.4064) (xy -0.17272 0.44196)
						(xy -0.1651 0.44958) (xy -0.1651 0.7366) (xy -0.16256 0.76835) (xy -0.1524 0.8001) (xy -0.13716 0.82804)
						(xy -0.11684 0.85344) (xy -0.09144 0.87376) (xy -0.0635 0.889) (xy -0.03175 0.89916) (xy 0 0.9017)
						(xy 0.03175 0.89916) (xy 0.0635 0.889) (xy 0.09144 0.87376) (xy 0.11684 0.85344) (xy 0.13716 0.82804)
						(xy 0.1524 0.8001) (xy 0.16256 0.76835) (xy 0.1651 0.7366) (xy 0.1651 0.44958) (xy 0.17272 0.44196)
						(xy 0.19812 0.4064) (xy 0.2032 0.39624) (xy 0.20701 0.38735) (xy 0.21209 0.37719) (xy 0.2159 0.36703)
						(xy 0.21844 0.35687) (xy 0.22225 0.34544) (xy 0.22352 0.33528) (xy 0.22606 0.32512) (xy 0.22733 0.31369)
						(xy 0.22733 0.30353) (xy 0.2286 0.2921) (xy 0.22733 0.28067) (xy 0.22733 0.27051) (xy 0.22606 0.25908)
						(xy 0.22352 0.24892) (xy 0.22225 0.23876) (xy 0.21844 0.22733) (xy 0.2159 0.21717) (xy 0.21209 0.20701)
						(xy 0.20701 0.19685) (xy 0.2032 0.18796) (xy 0.19812 0.1778) (xy 0.17272 0.14224) (xy 0.1651 0.13462)
						(xy 0.1651 -0.7366) (xy 0.16256 -0.76835) (xy 0.1524 -0.8001) (xy 0.13716 -0.82804) (xy 0.11684 -0.85344)
						(xy 0.09144 -0.87376) (xy 0.0635 -0.889) (xy 0.03175 -0.89916)
					)
					(width 0)
					(fill yes)
				)
			)
		)
		(pad "131" smd custom
			(at 9.750044 -4.100068)
			(size 0.1143 0.1143)
			(layers "B.Cu" "B.Mask" "B.Paste")
			(net "PV_VDDR")
			(options
				(clearance outline)
				(anchor circle)
			)
			(primitives
				(gr_poly
					(pts
						(xy 0 -0.9017) (xy -0.03175 -0.89916) (xy -0.0635 -0.889) (xy -0.09144 -0.87376) (xy -0.11684 -0.85344)
						(xy -0.13716 -0.82804) (xy -0.1524 -0.8001) (xy -0.16256 -0.76835) (xy -0.1651 -0.7366) (xy -0.1651 -0.19685)
						(xy -0.17272 -0.18923) (xy -0.17907 -0.18034) (xy -0.18669 -0.17145) (xy -0.19177 -0.16256) (xy -0.19812 -0.15367)
						(xy -0.20828 -0.13335) (xy -0.21971 -0.10287) (xy -0.22225 -0.09271) (xy -0.22479 -0.08128) (xy -0.22606 -0.07112)
						(xy -0.2286 -0.05969) (xy -0.2286 -0.01651) (xy -0.22606 -0.00508) (xy -0.22479 0.00508) (xy -0.22225 0.01651)
						(xy -0.21971 0.02667) (xy -0.20828 0.05715) (xy -0.19812 0.07747) (xy -0.19177 0.08636) (xy -0.18669 0.09525)
						(xy -0.17907 0.10414) (xy -0.17272 0.11303) (xy -0.1651 0.12065) (xy -0.1651 0.7366) (xy -0.16256 0.76835)
						(xy -0.1524 0.8001) (xy -0.13716 0.82804) (xy -0.11684 0.85344) (xy -0.09144 0.87376) (xy -0.0635 0.889)
						(xy -0.03175 0.89916) (xy 0 0.9017) (xy 0.03175 0.89916) (xy 0.0635 0.889) (xy 0.09144 0.87376)
						(xy 0.11684 0.85344) (xy 0.13716 0.82804) (xy 0.1524 0.8001) (xy 0.16256 0.76835) (xy 0.1651 0.7366)
						(xy 0.1651 0.11938) (xy 0.17272 0.11176) (xy 0.19812 0.0762) (xy 0.2032 0.06604) (xy 0.20701 0.05715)
						(xy 0.21209 0.04699) (xy 0.2159 0.03683) (xy 0.21844 0.02667) (xy 0.22225 0.01524) (xy 0.22352 0.00508)
						(xy 0.22606 -0.00508) (xy 0.22733 -0.01651) (xy 0.22733 -0.02667) (xy 0.2286 -0.0381) (xy 0.22733 -0.04953)
						(xy 0.22733 -0.05969) (xy 0.22606 -0.07112) (xy 0.22352 -0.08128) (xy 0.22225 -0.09144) (xy 0.21844 -0.10287)
						(xy 0.2159 -0.11303) (xy 0.21209 -0.12319) (xy 0.20701 -0.13335) (xy 0.2032 -0.14224) (xy 0.19812 -0.1524)
						(xy 0.17272 -0.18796) (xy 0.1651 -0.19558) (xy 0.1651 -0.7366) (xy 0.16256 -0.76835) (xy 0.1524 -0.8001)
						(xy 0.13716 -0.82804) (xy 0.11684 -0.85344) (xy 0.09144 -0.87376) (xy 0.0635 -0.889) (xy 0.03175 -0.89916)
					)
					(width 0)
					(fill yes)
				)
			)
		)
		(pad "132" smd custom
			(at 10.050018 4.100068)
			(size 0.1143 0.1143)
			(layers "B.Cu" "B.Mask" "B.Paste")
			(net "PV_VDDR")
			(options
				(clearance outline)
				(anchor circle)
			)
			(primitives
				(gr_poly
					(pts
						(xy 0 -0.9017) (xy -0.03175 -0.89916) (xy -0.0635 -0.889) (xy -0.09144 -0.87376) (xy -0.11684 -0.85344)
						(xy -0.13716 -0.82804) (xy -0.1524 -0.8001) (xy -0.16256 -0.76835) (xy -0.1651 -0.7366) (xy -0.1651 -0.11938)
						(xy -0.17272 -0.11176) (xy -0.19812 -0.0762) (xy -0.2032 -0.06604) (xy -0.20701 -0.05715) (xy -0.21209 -0.04699)
						(xy -0.2159 -0.03683) (xy -0.21844 -0.02667) (xy -0.22225 -0.01524) (xy -0.22352 -0.00508) (xy -0.22606 0.00508)
						(xy -0.22733 0.01651) (xy -0.22733 0.02667) (xy -0.2286 0.0381) (xy -0.22733 0.04953) (xy -0.22733 0.05969)
						(xy -0.22606 0.07112) (xy -0.22352 0.08128) (xy -0.22225 0.09144) (xy -0.21844 0.10287) (xy -0.2159 0.11303)
						(xy -0.21209 0.12319) (xy -0.20701 0.13335) (xy -0.2032 0.14224) (xy -0.19812 0.1524) (xy -0.17272 0.18796)
						(xy -0.1651 0.19558) (xy -0.1651 0.7366) (xy -0.16256 0.76835) (xy -0.1524 0.8001) (xy -0.13716 0.82804)
						(xy -0.11684 0.85344) (xy -0.09144 0.87376) (xy -0.0635 0.889) (xy -0.03175 0.89916) (xy 0 0.9017)
						(xy 0.03175 0.89916) (xy 0.0635 0.889) (xy 0.09144 0.87376) (xy 0.11684 0.85344) (xy 0.13716 0.82804)
						(xy 0.1524 0.8001) (xy 0.16256 0.76835) (xy 0.1651 0.7366) (xy 0.1651 0.19685) (xy 0.17272 0.18923)
						(xy 0.17907 0.18034) (xy 0.18669 0.17145) (xy 0.19177 0.16256) (xy 0.19812 0.15367) (xy 0.20828 0.13335)
						(xy 0.21971 0.10287) (xy 0.22225 0.09271) (xy 0.22479 0.08128) (xy 0.22606 0.07112) (xy 0.2286 0.05969)
						(xy 0.2286 0.01651) (xy 0.22606 0.00508) (xy 0.22479 -0.00508) (xy 0.22225 -0.01651) (xy 0.21971 -0.02667)
						(xy 0.20828 -0.05715) (xy 0.19812 -0.07747) (xy 0.19177 -0.08636) (xy 0.18669 -0.09525) (xy 0.17907 -0.10414)
						(xy 0.17272 -0.11303) (xy 0.1651 -0.12065) (xy 0.1651 -0.7366) (xy 0.16256 -0.76835) (xy 0.1524 -0.8001)
						(xy 0.13716 -0.82804) (xy 0.11684 -0.85344) (xy 0.09144 -0.87376) (xy 0.0635 -0.889) (xy 0.03175 -0.89916)
					)
					(width 0)
					(fill yes)
				)
			)
		)
		(pad "133" smd custom
			(at 10.349992 -4.100068)
			(size 0.1143 0.1143)
			(layers "B.Cu" "B.Mask" "B.Paste")
			(net "M_A_DQ32")
			(options
				(clearance outline)
				(anchor circle)
			)
			(primitives
				(gr_poly
					(pts
						(xy 0 -0.9017) (xy -0.03175 -0.89916) (xy -0.0635 -0.889) (xy -0.09144 -0.87376) (xy -0.11684 -0.85344)
						(xy -0.13716 -0.82804) (xy -0.1524 -0.8001) (xy -0.16256 -0.76835) (xy -0.1651 -0.7366) (xy -0.1651 -0.44958)
						(xy -0.17272 -0.44196) (xy -0.19812 -0.4064) (xy -0.2032 -0.39624) (xy -0.20701 -0.38735) (xy -0.21209 -0.37719)
						(xy -0.2159 -0.36703) (xy -0.21844 -0.35687) (xy -0.22225 -0.34544) (xy -0.22352 -0.33528) (xy -0.22606 -0.32512)
						(xy -0.22733 -0.31369) (xy -0.22733 -0.30353) (xy -0.2286 -0.2921) (xy -0.22733 -0.28067) (xy -0.22733 -0.27051)
						(xy -0.22606 -0.25908) (xy -0.22352 -0.24892) (xy -0.22225 -0.23876) (xy -0.21844 -0.22733) (xy -0.2159 -0.21717)
						(xy -0.21209 -0.20701) (xy -0.20701 -0.19685) (xy -0.2032 -0.18796) (xy -0.19812 -0.1778) (xy -0.17272 -0.14224)
						(xy -0.1651 -0.13462) (xy -0.1651 0.7366) (xy -0.16256 0.76835) (xy -0.1524 0.8001) (xy -0.13716 0.82804)
						(xy -0.11684 0.85344) (xy -0.09144 0.87376) (xy -0.0635 0.889) (xy -0.03175 0.89916) (xy 0 0.9017)
						(xy 0.03175 0.89916) (xy 0.0635 0.889) (xy 0.09144 0.87376) (xy 0.11684 0.85344) (xy 0.13716 0.82804)
						(xy 0.1524 0.8001) (xy 0.16256 0.76835) (xy 0.1651 0.7366) (xy 0.1651 -0.13462) (xy 0.17272 -0.14224)
						(xy 0.19812 -0.1778) (xy 0.2032 -0.18796) (xy 0.20701 -0.19685) (xy 0.21209 -0.20701) (xy 0.2159 -0.21717)
						(xy 0.21844 -0.22733) (xy 0.22225 -0.23876) (xy 0.22352 -0.24892) (xy 0.22606 -0.25908) (xy 0.22733 -0.27051)
						(xy 0.22733 -0.28067) (xy 0.2286 -0.2921) (xy 0.22733 -0.30353) (xy 0.22733 -0.31369) (xy 0.22606 -0.32512)
						(xy 0.22352 -0.33528) (xy 0.22225 -0.34544) (xy 0.21844 -0.35687) (xy 0.2159 -0.36703) (xy 0.21209 -0.37719)
						(xy 0.20701 -0.38735) (xy 0.2032 -0.39624) (xy 0.19812 -0.4064) (xy 0.17272 -0.44196) (xy 0.1651 -0.44958)
						(xy 0.1651 -0.7366) (xy 0.16256 -0.76835) (xy 0.1524 -0.8001) (xy 0.13716 -0.82804) (xy 0.11684 -0.85344)
						(xy 0.09144 -0.87376) (xy 0.0635 -0.889) (xy 0.03175 -0.89916)
					)
					(width 0)
					(fill yes)
				)
			)
		)
		(pad "134" smd custom
			(at 10.649966 4.100068)
			(size 0.1143 0.1143)
			(layers "B.Cu" "B.Mask" "B.Paste")
			(net "M_A_DQ36")
			(options
				(clearance outline)
				(anchor circle)
			)
			(primitives
				(gr_poly
					(pts
						(xy 0 -0.9017) (xy -0.03175 -0.89916) (xy -0.0635 -0.889) (xy -0.09144 -0.87376) (xy -0.11684 -0.85344)
						(xy -0.13716 -0.82804) (xy -0.1524 -0.8001) (xy -0.16256 -0.76835) (xy -0.1651 -0.7366) (xy -0.1651 0.13462)
						(xy -0.17272 0.14224) (xy -0.19812 0.1778) (xy -0.2032 0.18796) (xy -0.20701 0.19685) (xy -0.21209 0.20701)
						(xy -0.2159 0.21717) (xy -0.21844 0.22733) (xy -0.22225 0.23876) (xy -0.22352 0.24892) (xy -0.22606 0.25908)
						(xy -0.22733 0.27051) (xy -0.22733 0.28067) (xy -0.2286 0.2921) (xy -0.22733 0.30353) (xy -0.22733 0.31369)
						(xy -0.22606 0.32512) (xy -0.22352 0.33528) (xy -0.22225 0.34544) (xy -0.21844 0.35687) (xy -0.2159 0.36703)
						(xy -0.21209 0.37719) (xy -0.20701 0.38735) (xy -0.2032 0.39624) (xy -0.19812 0.4064) (xy -0.17272 0.44196)
						(xy -0.1651 0.44958) (xy -0.1651 0.7366) (xy -0.16256 0.76835) (xy -0.1524 0.8001) (xy -0.13716 0.82804)
						(xy -0.11684 0.85344) (xy -0.09144 0.87376) (xy -0.0635 0.889) (xy -0.03175 0.89916) (xy 0 0.9017)
						(xy 0.03175 0.89916) (xy 0.0635 0.889) (xy 0.09144 0.87376) (xy 0.11684 0.85344) (xy 0.13716 0.82804)
						(xy 0.1524 0.8001) (xy 0.16256 0.76835) (xy 0.1651 0.7366) (xy 0.1651 0.44958) (xy 0.17272 0.44196)
						(xy 0.19812 0.4064) (xy 0.2032 0.39624) (xy 0.20701 0.38735) (xy 0.21209 0.37719) (xy 0.2159 0.36703)
						(xy 0.21844 0.35687) (xy 0.22225 0.34544) (xy 0.22352 0.33528) (xy 0.22606 0.32512) (xy 0.22733 0.31369)
						(xy 0.22733 0.30353) (xy 0.2286 0.2921) (xy 0.22733 0.28067) (xy 0.22733 0.27051) (xy 0.22606 0.25908)
						(xy 0.22352 0.24892) (xy 0.22225 0.23876) (xy 0.21844 0.22733) (xy 0.2159 0.21717) (xy 0.21209 0.20701)
						(xy 0.20701 0.19685) (xy 0.2032 0.18796) (xy 0.19812 0.1778) (xy 0.17272 0.14224) (xy 0.1651 0.13462)
						(xy 0.1651 -0.7366) (xy 0.16256 -0.76835) (xy 0.1524 -0.8001) (xy 0.13716 -0.82804) (xy 0.11684 -0.85344)
						(xy 0.09144 -0.87376) (xy 0.0635 -0.889) (xy 0.03175 -0.89916)
					)
					(width 0)
					(fill yes)
				)
			)
		)
		(pad "135" smd custom
			(at 10.94994 -4.100068)
			(size 0.1143 0.1143)
			(layers "B.Cu" "B.Mask" "B.Paste")
			(net "M_A_DQ33")
			(options
				(clearance outline)
				(anchor circle)
			)
			(primitives
				(gr_poly
					(pts
						(xy 0 -0.9017) (xy -0.03175 -0.89916) (xy -0.0635 -0.889) (xy -0.09144 -0.87376) (xy -0.11684 -0.85344)
						(xy -0.13716 -0.82804) (xy -0.1524 -0.8001) (xy -0.16256 -0.76835) (xy -0.1651 -0.7366) (xy -0.1651 -0.19685)
						(xy -0.17272 -0.18923) (xy -0.17907 -0.18034) (xy -0.18669 -0.17145) (xy -0.19177 -0.16256) (xy -0.19812 -0.15367)
						(xy -0.20828 -0.13335) (xy -0.21971 -0.10287) (xy -0.22225 -0.09271) (xy -0.22479 -0.08128) (xy -0.22606 -0.07112)
						(xy -0.2286 -0.05969) (xy -0.2286 -0.01651) (xy -0.22606 -0.00508) (xy -0.22479 0.00508) (xy -0.22225 0.01651)
						(xy -0.21971 0.02667) (xy -0.20828 0.05715) (xy -0.19812 0.07747) (xy -0.19177 0.08636) (xy -0.18669 0.09525)
						(xy -0.17907 0.10414) (xy -0.17272 0.11303) (xy -0.1651 0.12065) (xy -0.1651 0.7366) (xy -0.16256 0.76835)
						(xy -0.1524 0.8001) (xy -0.13716 0.82804) (xy -0.11684 0.85344) (xy -0.09144 0.87376) (xy -0.0635 0.889)
						(xy -0.03175 0.89916) (xy 0 0.9017) (xy 0.03175 0.89916) (xy 0.0635 0.889) (xy 0.09144 0.87376)
						(xy 0.11684 0.85344) (xy 0.13716 0.82804) (xy 0.1524 0.8001) (xy 0.16256 0.76835) (xy 0.1651 0.7366)
						(xy 0.1651 0.11938) (xy 0.17272 0.11176) (xy 0.19812 0.0762) (xy 0.2032 0.06604) (xy 0.20701 0.05715)
						(xy 0.21209 0.04699) (xy 0.2159 0.03683) (xy 0.21844 0.02667) (xy 0.22225 0.01524) (xy 0.22352 0.00508)
						(xy 0.22606 -0.00508) (xy 0.22733 -0.01651) (xy 0.22733 -0.02667) (xy 0.2286 -0.0381) (xy 0.22733 -0.04953)
						(xy 0.22733 -0.05969) (xy 0.22606 -0.07112) (xy 0.22352 -0.08128) (xy 0.22225 -0.09144) (xy 0.21844 -0.10287)
						(xy 0.2159 -0.11303) (xy 0.21209 -0.12319) (xy 0.20701 -0.13335) (xy 0.2032 -0.14224) (xy 0.19812 -0.1524)
						(xy 0.17272 -0.18796) (xy 0.1651 -0.19558) (xy 0.1651 -0.7366) (xy 0.16256 -0.76835) (xy 0.1524 -0.8001)
						(xy 0.13716 -0.82804) (xy 0.11684 -0.85344) (xy 0.09144 -0.87376) (xy 0.0635 -0.889) (xy 0.03175 -0.89916)
					)
					(width 0)
					(fill yes)
				)
			)
		)
		(pad "136" smd custom
			(at 11.249914 4.100068)
			(size 0.1143 0.1143)
			(layers "B.Cu" "B.Mask" "B.Paste")
			(net "M_A_DQ37")
			(options
				(clearance outline)
				(anchor circle)
			)
			(primitives
				(gr_poly
					(pts
						(xy 0 -0.9017) (xy -0.03175 -0.89916) (xy -0.0635 -0.889) (xy -0.09144 -0.87376) (xy -0.11684 -0.85344)
						(xy -0.13716 -0.82804) (xy -0.1524 -0.8001) (xy -0.16256 -0.76835) (xy -0.1651 -0.7366) (xy -0.1651 -0.11938)
						(xy -0.17272 -0.11176) (xy -0.19812 -0.0762) (xy -0.2032 -0.06604) (xy -0.20701 -0.05715) (xy -0.21209 -0.04699)
						(xy -0.2159 -0.03683) (xy -0.21844 -0.02667) (xy -0.22225 -0.01524) (xy -0.22352 -0.00508) (xy -0.22606 0.00508)
						(xy -0.22733 0.01651) (xy -0.22733 0.02667) (xy -0.2286 0.0381) (xy -0.22733 0.04953) (xy -0.22733 0.05969)
						(xy -0.22606 0.07112) (xy -0.22352 0.08128) (xy -0.22225 0.09144) (xy -0.21844 0.10287) (xy -0.2159 0.11303)
						(xy -0.21209 0.12319) (xy -0.20701 0.13335) (xy -0.2032 0.14224) (xy -0.19812 0.1524) (xy -0.17272 0.18796)
						(xy -0.1651 0.19558) (xy -0.1651 0.7366) (xy -0.16256 0.76835) (xy -0.1524 0.8001) (xy -0.13716 0.82804)
						(xy -0.11684 0.85344) (xy -0.09144 0.87376) (xy -0.0635 0.889) (xy -0.03175 0.89916) (xy 0 0.9017)
						(xy 0.03175 0.89916) (xy 0.0635 0.889) (xy 0.09144 0.87376) (xy 0.11684 0.85344) (xy 0.13716 0.82804)
						(xy 0.1524 0.8001) (xy 0.16256 0.76835) (xy 0.1651 0.7366) (xy 0.1651 0.19685) (xy 0.17272 0.18923)
						(xy 0.17907 0.18034) (xy 0.18669 0.17145) (xy 0.19177 0.16256) (xy 0.19812 0.15367) (xy 0.20828 0.13335)
						(xy 0.21971 0.10287) (xy 0.22225 0.09271) (xy 0.22479 0.08128) (xy 0.22606 0.07112) (xy 0.2286 0.05969)
						(xy 0.2286 0.01651) (xy 0.22606 0.00508) (xy 0.22479 -0.00508) (xy 0.22225 -0.01651) (xy 0.21971 -0.02667)
						(xy 0.20828 -0.05715) (xy 0.19812 -0.07747) (xy 0.19177 -0.08636) (xy 0.18669 -0.09525) (xy 0.17907 -0.10414)
						(xy 0.17272 -0.11303) (xy 0.1651 -0.12065) (xy 0.1651 -0.7366) (xy 0.16256 -0.76835) (xy 0.1524 -0.8001)
						(xy 0.13716 -0.82804) (xy 0.11684 -0.85344) (xy 0.09144 -0.87376) (xy 0.0635 -0.889) (xy 0.03175 -0.89916)
					)
					(width 0)
					(fill yes)
				)
			)
		)
		(pad "137" smd custom
			(at 11.549888 -4.100068)
			(size 0.1143 0.1143)
			(layers "B.Cu" "B.Mask" "B.Paste")
			(net "GND")
			(options
				(clearance outline)
				(anchor circle)
			)
			(primitives
				(gr_poly
					(pts
						(xy 0 -0.9017) (xy -0.03175 -0.89916) (xy -0.0635 -0.889) (xy -0.09144 -0.87376) (xy -0.11684 -0.85344)
						(xy -0.13716 -0.82804) (xy -0.1524 -0.8001) (xy -0.16256 -0.76835) (xy -0.1651 -0.7366) (xy -0.1651 -0.44958)
						(xy -0.17272 -0.44196) (xy -0.19812 -0.4064) (xy -0.2032 -0.39624) (xy -0.20701 -0.38735) (xy -0.21209 -0.37719)
						(xy -0.2159 -0.36703) (xy -0.21844 -0.35687) (xy -0.22225 -0.34544) (xy -0.22352 -0.33528) (xy -0.22606 -0.32512)
						(xy -0.22733 -0.31369) (xy -0.22733 -0.30353) (xy -0.2286 -0.2921) (xy -0.22733 -0.28067) (xy -0.22733 -0.27051)
						(xy -0.22606 -0.25908) (xy -0.22352 -0.24892) (xy -0.22225 -0.23876) (xy -0.21844 -0.22733) (xy -0.2159 -0.21717)
						(xy -0.21209 -0.20701) (xy -0.20701 -0.19685) (xy -0.2032 -0.18796) (xy -0.19812 -0.1778) (xy -0.17272 -0.14224)
						(xy -0.1651 -0.13462) (xy -0.1651 0.7366) (xy -0.16256 0.76835) (xy -0.1524 0.8001) (xy -0.13716 0.82804)
						(xy -0.11684 0.85344) (xy -0.09144 0.87376) (xy -0.0635 0.889) (xy -0.03175 0.89916) (xy 0 0.9017)
						(xy 0.03175 0.89916) (xy 0.0635 0.889) (xy 0.09144 0.87376) (xy 0.11684 0.85344) (xy 0.13716 0.82804)
						(xy 0.1524 0.8001) (xy 0.16256 0.76835) (xy 0.1651 0.7366) (xy 0.1651 -0.13462) (xy 0.17272 -0.14224)
						(xy 0.19812 -0.1778) (xy 0.2032 -0.18796) (xy 0.20701 -0.19685) (xy 0.21209 -0.20701) (xy 0.2159 -0.21717)
						(xy 0.21844 -0.22733) (xy 0.22225 -0.23876) (xy 0.22352 -0.24892) (xy 0.22606 -0.25908) (xy 0.22733 -0.27051)
						(xy 0.22733 -0.28067) (xy 0.2286 -0.2921) (xy 0.22733 -0.30353) (xy 0.22733 -0.31369) (xy 0.22606 -0.32512)
						(xy 0.22352 -0.33528) (xy 0.22225 -0.34544) (xy 0.21844 -0.35687) (xy 0.2159 -0.36703) (xy 0.21209 -0.37719)
						(xy 0.20701 -0.38735) (xy 0.2032 -0.39624) (xy 0.19812 -0.4064) (xy 0.17272 -0.44196) (xy 0.1651 -0.44958)
						(xy 0.1651 -0.7366) (xy 0.16256 -0.76835) (xy 0.1524 -0.8001) (xy 0.13716 -0.82804) (xy 0.11684 -0.85344)
						(xy 0.09144 -0.87376) (xy 0.0635 -0.889) (xy 0.03175 -0.89916)
					)
					(width 0)
					(fill yes)
				)
			)
		)
		(pad "138" smd custom
			(at 11.850116 4.100068)
			(size 0.1143 0.1143)
			(layers "B.Cu" "B.Mask" "B.Paste")
			(net "GND")
			(options
				(clearance outline)
				(anchor circle)
			)
			(primitives
				(gr_poly
					(pts
						(xy 0 -0.9017) (xy -0.03175 -0.89916) (xy -0.0635 -0.889) (xy -0.09144 -0.87376) (xy -0.11684 -0.85344)
						(xy -0.13716 -0.82804) (xy -0.1524 -0.8001) (xy -0.16256 -0.76835) (xy -0.1651 -0.7366) (xy -0.1651 0.13462)
						(xy -0.17272 0.14224) (xy -0.19812 0.1778) (xy -0.2032 0.18796) (xy -0.20701 0.19685) (xy -0.21209 0.20701)
						(xy -0.2159 0.21717) (xy -0.21844 0.22733) (xy -0.22225 0.23876) (xy -0.22352 0.24892) (xy -0.22606 0.25908)
						(xy -0.22733 0.27051) (xy -0.22733 0.28067) (xy -0.2286 0.2921) (xy -0.22733 0.30353) (xy -0.22733 0.31369)
						(xy -0.22606 0.32512) (xy -0.22352 0.33528) (xy -0.22225 0.34544) (xy -0.21844 0.35687) (xy -0.2159 0.36703)
						(xy -0.21209 0.37719) (xy -0.20701 0.38735) (xy -0.2032 0.39624) (xy -0.19812 0.4064) (xy -0.17272 0.44196)
						(xy -0.1651 0.44958) (xy -0.1651 0.7366) (xy -0.16256 0.76835) (xy -0.1524 0.8001) (xy -0.13716 0.82804)
						(xy -0.11684 0.85344) (xy -0.09144 0.87376) (xy -0.0635 0.889) (xy -0.03175 0.89916) (xy 0 0.9017)
						(xy 0.03175 0.89916) (xy 0.0635 0.889) (xy 0.09144 0.87376) (xy 0.11684 0.85344) (xy 0.13716 0.82804)
						(xy 0.1524 0.8001) (xy 0.16256 0.76835) (xy 0.1651 0.7366) (xy 0.1651 0.44958) (xy 0.17272 0.44196)
						(xy 0.19812 0.4064) (xy 0.2032 0.39624) (xy 0.20701 0.38735) (xy 0.21209 0.37719) (xy 0.2159 0.36703)
						(xy 0.21844 0.35687) (xy 0.22225 0.34544) (xy 0.22352 0.33528) (xy 0.22606 0.32512) (xy 0.22733 0.31369)
						(xy 0.22733 0.30353) (xy 0.2286 0.2921) (xy 0.22733 0.28067) (xy 0.22733 0.27051) (xy 0.22606 0.25908)
						(xy 0.22352 0.24892) (xy 0.22225 0.23876) (xy 0.21844 0.22733) (xy 0.2159 0.21717) (xy 0.21209 0.20701)
						(xy 0.20701 0.19685) (xy 0.2032 0.18796) (xy 0.19812 0.1778) (xy 0.17272 0.14224) (xy 0.1651 0.13462)
						(xy 0.1651 -0.7366) (xy 0.16256 -0.76835) (xy 0.1524 -0.8001) (xy 0.13716 -0.82804) (xy 0.11684 -0.85344)
						(xy 0.09144 -0.87376) (xy 0.0635 -0.889) (xy 0.03175 -0.89916)
					)
					(width 0)
					(fill yes)
				)
			)
		)
		(pad "139" smd custom
			(at 12.15009 -4.100068)
			(size 0.1143 0.1143)
			(layers "B.Cu" "B.Mask" "B.Paste")
			(net "M_A_DQS_DN4")
			(options
				(clearance outline)
				(anchor circle)
			)
			(primitives
				(gr_poly
					(pts
						(xy 0 -0.9017) (xy -0.03175 -0.89916) (xy -0.0635 -0.889) (xy -0.09144 -0.87376) (xy -0.11684 -0.85344)
						(xy -0.13716 -0.82804) (xy -0.1524 -0.8001) (xy -0.16256 -0.76835) (xy -0.1651 -0.7366) (xy -0.1651 -0.19685)
						(xy -0.17272 -0.18923) (xy -0.17907 -0.18034) (xy -0.18669 -0.17145) (xy -0.19177 -0.16256) (xy -0.19812 -0.15367)
						(xy -0.20828 -0.13335) (xy -0.21971 -0.10287) (xy -0.22225 -0.09271) (xy -0.22479 -0.08128) (xy -0.22606 -0.07112)
						(xy -0.2286 -0.05969) (xy -0.2286 -0.01651) (xy -0.22606 -0.00508) (xy -0.22479 0.00508) (xy -0.22225 0.01651)
						(xy -0.21971 0.02667) (xy -0.20828 0.05715) (xy -0.19812 0.07747) (xy -0.19177 0.08636) (xy -0.18669 0.09525)
						(xy -0.17907 0.10414) (xy -0.17272 0.11303) (xy -0.1651 0.12065) (xy -0.1651 0.7366) (xy -0.16256 0.76835)
						(xy -0.1524 0.8001) (xy -0.13716 0.82804) (xy -0.11684 0.85344) (xy -0.09144 0.87376) (xy -0.0635 0.889)
						(xy -0.03175 0.89916) (xy 0 0.9017) (xy 0.03175 0.89916) (xy 0.0635 0.889) (xy 0.09144 0.87376)
						(xy 0.11684 0.85344) (xy 0.13716 0.82804) (xy 0.1524 0.8001) (xy 0.16256 0.76835) (xy 0.1651 0.7366)
						(xy 0.1651 0.11938) (xy 0.17272 0.11176) (xy 0.19812 0.0762) (xy 0.2032 0.06604) (xy 0.20701 0.05715)
						(xy 0.21209 0.04699) (xy 0.2159 0.03683) (xy 0.21844 0.02667) (xy 0.22225 0.01524) (xy 0.22352 0.00508)
						(xy 0.22606 -0.00508) (xy 0.22733 -0.01651) (xy 0.22733 -0.02667) (xy 0.2286 -0.0381) (xy 0.22733 -0.04953)
						(xy 0.22733 -0.05969) (xy 0.22606 -0.07112) (xy 0.22352 -0.08128) (xy 0.22225 -0.09144) (xy 0.21844 -0.10287)
						(xy 0.2159 -0.11303) (xy 0.21209 -0.12319) (xy 0.20701 -0.13335) (xy 0.2032 -0.14224) (xy 0.19812 -0.1524)
						(xy 0.17272 -0.18796) (xy 0.1651 -0.19558) (xy 0.1651 -0.7366) (xy 0.16256 -0.76835) (xy 0.1524 -0.8001)
						(xy 0.13716 -0.82804) (xy 0.11684 -0.85344) (xy 0.09144 -0.87376) (xy 0.0635 -0.889) (xy 0.03175 -0.89916)
					)
					(width 0)
					(fill yes)
				)
			)
		)
		(pad "140" smd custom
			(at 12.450064 4.100068)
			(size 0.1143 0.1143)
			(layers "B.Cu" "B.Mask" "B.Paste")
			(net "GND")
			(options
				(clearance outline)
				(anchor circle)
			)
			(primitives
				(gr_poly
					(pts
						(xy 0 -0.9017) (xy -0.03175 -0.89916) (xy -0.0635 -0.889) (xy -0.09144 -0.87376) (xy -0.11684 -0.85344)
						(xy -0.13716 -0.82804) (xy -0.1524 -0.8001) (xy -0.16256 -0.76835) (xy -0.1651 -0.7366) (xy -0.1651 -0.11938)
						(xy -0.17272 -0.11176) (xy -0.19812 -0.0762) (xy -0.2032 -0.06604) (xy -0.20701 -0.05715) (xy -0.21209 -0.04699)
						(xy -0.2159 -0.03683) (xy -0.21844 -0.02667) (xy -0.22225 -0.01524) (xy -0.22352 -0.00508) (xy -0.22606 0.00508)
						(xy -0.22733 0.01651) (xy -0.22733 0.02667) (xy -0.2286 0.0381) (xy -0.22733 0.04953) (xy -0.22733 0.05969)
						(xy -0.22606 0.07112) (xy -0.22352 0.08128) (xy -0.22225 0.09144) (xy -0.21844 0.10287) (xy -0.2159 0.11303)
						(xy -0.21209 0.12319) (xy -0.20701 0.13335) (xy -0.2032 0.14224) (xy -0.19812 0.1524) (xy -0.17272 0.18796)
						(xy -0.1651 0.19558) (xy -0.1651 0.7366) (xy -0.16256 0.76835) (xy -0.1524 0.8001) (xy -0.13716 0.82804)
						(xy -0.11684 0.85344) (xy -0.09144 0.87376) (xy -0.0635 0.889) (xy -0.03175 0.89916) (xy 0 0.9017)
						(xy 0.03175 0.89916) (xy 0.0635 0.889) (xy 0.09144 0.87376) (xy 0.11684 0.85344) (xy 0.13716 0.82804)
						(xy 0.1524 0.8001) (xy 0.16256 0.76835) (xy 0.1651 0.7366) (xy 0.1651 0.19685) (xy 0.17272 0.18923)
						(xy 0.17907 0.18034) (xy 0.18669 0.17145) (xy 0.19177 0.16256) (xy 0.19812 0.15367) (xy 0.20828 0.13335)
						(xy 0.21971 0.10287) (xy 0.22225 0.09271) (xy 0.22479 0.08128) (xy 0.22606 0.07112) (xy 0.2286 0.05969)
						(xy 0.2286 0.01651) (xy 0.22606 0.00508) (xy 0.22479 -0.00508) (xy 0.22225 -0.01651) (xy 0.21971 -0.02667)
						(xy 0.20828 -0.05715) (xy 0.19812 -0.07747) (xy 0.19177 -0.08636) (xy 0.18669 -0.09525) (xy 0.17907 -0.10414)
						(xy 0.17272 -0.11303) (xy 0.1651 -0.12065) (xy 0.1651 -0.7366) (xy 0.16256 -0.76835) (xy 0.1524 -0.8001)
						(xy 0.13716 -0.82804) (xy 0.11684 -0.85344) (xy 0.09144 -0.87376) (xy 0.0635 -0.889) (xy 0.03175 -0.89916)
					)
					(width 0)
					(fill yes)
				)
			)
		)
		(pad "141" smd custom
			(at 12.750038 -4.100068)
			(size 0.1143 0.1143)
			(layers "B.Cu" "B.Mask" "B.Paste")
			(net "M_A_DQS_DP4")
			(options
				(clearance outline)
				(anchor circle)
			)
			(primitives
				(gr_poly
					(pts
						(xy 0 -0.9017) (xy -0.03175 -0.89916) (xy -0.0635 -0.889) (xy -0.09144 -0.87376) (xy -0.11684 -0.85344)
						(xy -0.13716 -0.82804) (xy -0.1524 -0.8001) (xy -0.16256 -0.76835) (xy -0.1651 -0.7366) (xy -0.1651 -0.44958)
						(xy -0.17272 -0.44196) (xy -0.19812 -0.4064) (xy -0.2032 -0.39624) (xy -0.20701 -0.38735) (xy -0.21209 -0.37719)
						(xy -0.2159 -0.36703) (xy -0.21844 -0.35687) (xy -0.22225 -0.34544) (xy -0.22352 -0.33528) (xy -0.22606 -0.32512)
						(xy -0.22733 -0.31369) (xy -0.22733 -0.30353) (xy -0.2286 -0.2921) (xy -0.22733 -0.28067) (xy -0.22733 -0.27051)
						(xy -0.22606 -0.25908) (xy -0.22352 -0.24892) (xy -0.22225 -0.23876) (xy -0.21844 -0.22733) (xy -0.2159 -0.21717)
						(xy -0.21209 -0.20701) (xy -0.20701 -0.19685) (xy -0.2032 -0.18796) (xy -0.19812 -0.1778) (xy -0.17272 -0.14224)
						(xy -0.1651 -0.13462) (xy -0.1651 0.7366) (xy -0.16256 0.76835) (xy -0.1524 0.8001) (xy -0.13716 0.82804)
						(xy -0.11684 0.85344) (xy -0.09144 0.87376) (xy -0.0635 0.889) (xy -0.03175 0.89916) (xy 0 0.9017)
						(xy 0.03175 0.89916) (xy 0.0635 0.889) (xy 0.09144 0.87376) (xy 0.11684 0.85344) (xy 0.13716 0.82804)
						(xy 0.1524 0.8001) (xy 0.16256 0.76835) (xy 0.1651 0.7366) (xy 0.1651 -0.13462) (xy 0.17272 -0.14224)
						(xy 0.19812 -0.1778) (xy 0.2032 -0.18796) (xy 0.20701 -0.19685) (xy 0.21209 -0.20701) (xy 0.2159 -0.21717)
						(xy 0.21844 -0.22733) (xy 0.22225 -0.23876) (xy 0.22352 -0.24892) (xy 0.22606 -0.25908) (xy 0.22733 -0.27051)
						(xy 0.22733 -0.28067) (xy 0.2286 -0.2921) (xy 0.22733 -0.30353) (xy 0.22733 -0.31369) (xy 0.22606 -0.32512)
						(xy 0.22352 -0.33528) (xy 0.22225 -0.34544) (xy 0.21844 -0.35687) (xy 0.2159 -0.36703) (xy 0.21209 -0.37719)
						(xy 0.20701 -0.38735) (xy 0.2032 -0.39624) (xy 0.19812 -0.4064) (xy 0.17272 -0.44196) (xy 0.1651 -0.44958)
						(xy 0.1651 -0.7366) (xy 0.16256 -0.76835) (xy 0.1524 -0.8001) (xy 0.13716 -0.82804) (xy 0.11684 -0.85344)
						(xy 0.09144 -0.87376) (xy 0.0635 -0.889) (xy 0.03175 -0.89916)
					)
					(width 0)
					(fill yes)
				)
			)
		)
		(pad "142" smd custom
			(at 13.050012 4.100068)
			(size 0.1143 0.1143)
			(layers "B.Cu" "B.Mask" "B.Paste")
			(net "M_A_DQ38")
			(options
				(clearance outline)
				(anchor circle)
			)
			(primitives
				(gr_poly
					(pts
						(xy 0 -0.9017) (xy -0.03175 -0.89916) (xy -0.0635 -0.889) (xy -0.09144 -0.87376) (xy -0.11684 -0.85344)
						(xy -0.13716 -0.82804) (xy -0.1524 -0.8001) (xy -0.16256 -0.76835) (xy -0.1651 -0.7366) (xy -0.1651 0.13462)
						(xy -0.17272 0.14224) (xy -0.19812 0.1778) (xy -0.2032 0.18796) (xy -0.20701 0.19685) (xy -0.21209 0.20701)
						(xy -0.2159 0.21717) (xy -0.21844 0.22733) (xy -0.22225 0.23876) (xy -0.22352 0.24892) (xy -0.22606 0.25908)
						(xy -0.22733 0.27051) (xy -0.22733 0.28067) (xy -0.2286 0.2921) (xy -0.22733 0.30353) (xy -0.22733 0.31369)
						(xy -0.22606 0.32512) (xy -0.22352 0.33528) (xy -0.22225 0.34544) (xy -0.21844 0.35687) (xy -0.2159 0.36703)
						(xy -0.21209 0.37719) (xy -0.20701 0.38735) (xy -0.2032 0.39624) (xy -0.19812 0.4064) (xy -0.17272 0.44196)
						(xy -0.1651 0.44958) (xy -0.1651 0.7366) (xy -0.16256 0.76835) (xy -0.1524 0.8001) (xy -0.13716 0.82804)
						(xy -0.11684 0.85344) (xy -0.09144 0.87376) (xy -0.0635 0.889) (xy -0.03175 0.89916) (xy 0 0.9017)
						(xy 0.03175 0.89916) (xy 0.0635 0.889) (xy 0.09144 0.87376) (xy 0.11684 0.85344) (xy 0.13716 0.82804)
						(xy 0.1524 0.8001) (xy 0.16256 0.76835) (xy 0.1651 0.7366) (xy 0.1651 0.44958) (xy 0.17272 0.44196)
						(xy 0.19812 0.4064) (xy 0.2032 0.39624) (xy 0.20701 0.38735) (xy 0.21209 0.37719) (xy 0.2159 0.36703)
						(xy 0.21844 0.35687) (xy 0.22225 0.34544) (xy 0.22352 0.33528) (xy 0.22606 0.32512) (xy 0.22733 0.31369)
						(xy 0.22733 0.30353) (xy 0.2286 0.2921) (xy 0.22733 0.28067) (xy 0.22733 0.27051) (xy 0.22606 0.25908)
						(xy 0.22352 0.24892) (xy 0.22225 0.23876) (xy 0.21844 0.22733) (xy 0.2159 0.21717) (xy 0.21209 0.20701)
						(xy 0.20701 0.19685) (xy 0.2032 0.18796) (xy 0.19812 0.1778) (xy 0.17272 0.14224) (xy 0.1651 0.13462)
						(xy 0.1651 -0.7366) (xy 0.16256 -0.76835) (xy 0.1524 -0.8001) (xy 0.13716 -0.82804) (xy 0.11684 -0.85344)
						(xy 0.09144 -0.87376) (xy 0.0635 -0.889) (xy 0.03175 -0.89916)
					)
					(width 0)
					(fill yes)
				)
			)
		)
		(pad "143" smd custom
			(at 13.349986 -4.100068)
			(size 0.1143 0.1143)
			(layers "B.Cu" "B.Mask" "B.Paste")
			(net "GND")
			(options
				(clearance outline)
				(anchor circle)
			)
			(primitives
				(gr_poly
					(pts
						(xy 0 -0.9017) (xy -0.03175 -0.89916) (xy -0.0635 -0.889) (xy -0.09144 -0.87376) (xy -0.11684 -0.85344)
						(xy -0.13716 -0.82804) (xy -0.1524 -0.8001) (xy -0.16256 -0.76835) (xy -0.1651 -0.7366) (xy -0.1651 -0.19685)
						(xy -0.17272 -0.18923) (xy -0.17907 -0.18034) (xy -0.18669 -0.17145) (xy -0.19177 -0.16256) (xy -0.19812 -0.15367)
						(xy -0.20828 -0.13335) (xy -0.21971 -0.10287) (xy -0.22225 -0.09271) (xy -0.22479 -0.08128) (xy -0.22606 -0.07112)
						(xy -0.2286 -0.05969) (xy -0.2286 -0.01651) (xy -0.22606 -0.00508) (xy -0.22479 0.00508) (xy -0.22225 0.01651)
						(xy -0.21971 0.02667) (xy -0.20828 0.05715) (xy -0.19812 0.07747) (xy -0.19177 0.08636) (xy -0.18669 0.09525)
						(xy -0.17907 0.10414) (xy -0.17272 0.11303) (xy -0.1651 0.12065) (xy -0.1651 0.7366) (xy -0.16256 0.76835)
						(xy -0.1524 0.8001) (xy -0.13716 0.82804) (xy -0.11684 0.85344) (xy -0.09144 0.87376) (xy -0.0635 0.889)
						(xy -0.03175 0.89916) (xy 0 0.9017) (xy 0.03175 0.89916) (xy 0.0635 0.889) (xy 0.09144 0.87376)
						(xy 0.11684 0.85344) (xy 0.13716 0.82804) (xy 0.1524 0.8001) (xy 0.16256 0.76835) (xy 0.1651 0.7366)
						(xy 0.1651 0.11938) (xy 0.17272 0.11176) (xy 0.19812 0.0762) (xy 0.2032 0.06604) (xy 0.20701 0.05715)
						(xy 0.21209 0.04699) (xy 0.2159 0.03683) (xy 0.21844 0.02667) (xy 0.22225 0.01524) (xy 0.22352 0.00508)
						(xy 0.22606 -0.00508) (xy 0.22733 -0.01651) (xy 0.22733 -0.02667) (xy 0.2286 -0.0381) (xy 0.22733 -0.04953)
						(xy 0.22733 -0.05969) (xy 0.22606 -0.07112) (xy 0.22352 -0.08128) (xy 0.22225 -0.09144) (xy 0.21844 -0.10287)
						(xy 0.2159 -0.11303) (xy 0.21209 -0.12319) (xy 0.20701 -0.13335) (xy 0.2032 -0.14224) (xy 0.19812 -0.1524)
						(xy 0.17272 -0.18796) (xy 0.1651 -0.19558) (xy 0.1651 -0.7366) (xy 0.16256 -0.76835) (xy 0.1524 -0.8001)
						(xy 0.13716 -0.82804) (xy 0.11684 -0.85344) (xy 0.09144 -0.87376) (xy 0.0635 -0.889) (xy 0.03175 -0.89916)
					)
					(width 0)
					(fill yes)
				)
			)
		)
		(pad "144" smd custom
			(at 13.64996 4.100068)
			(size 0.1143 0.1143)
			(layers "B.Cu" "B.Mask" "B.Paste")
			(net "M_A_DQ39")
			(options
				(clearance outline)
				(anchor circle)
			)
			(primitives
				(gr_poly
					(pts
						(xy 0 -0.9017) (xy -0.03175 -0.89916) (xy -0.0635 -0.889) (xy -0.09144 -0.87376) (xy -0.11684 -0.85344)
						(xy -0.13716 -0.82804) (xy -0.1524 -0.8001) (xy -0.16256 -0.76835) (xy -0.1651 -0.7366) (xy -0.1651 -0.11938)
						(xy -0.17272 -0.11176) (xy -0.19812 -0.0762) (xy -0.2032 -0.06604) (xy -0.20701 -0.05715) (xy -0.21209 -0.04699)
						(xy -0.2159 -0.03683) (xy -0.21844 -0.02667) (xy -0.22225 -0.01524) (xy -0.22352 -0.00508) (xy -0.22606 0.00508)
						(xy -0.22733 0.01651) (xy -0.22733 0.02667) (xy -0.2286 0.0381) (xy -0.22733 0.04953) (xy -0.22733 0.05969)
						(xy -0.22606 0.07112) (xy -0.22352 0.08128) (xy -0.22225 0.09144) (xy -0.21844 0.10287) (xy -0.2159 0.11303)
						(xy -0.21209 0.12319) (xy -0.20701 0.13335) (xy -0.2032 0.14224) (xy -0.19812 0.1524) (xy -0.17272 0.18796)
						(xy -0.1651 0.19558) (xy -0.1651 0.7366) (xy -0.16256 0.76835) (xy -0.1524 0.8001) (xy -0.13716 0.82804)
						(xy -0.11684 0.85344) (xy -0.09144 0.87376) (xy -0.0635 0.889) (xy -0.03175 0.89916) (xy 0 0.9017)
						(xy 0.03175 0.89916) (xy 0.0635 0.889) (xy 0.09144 0.87376) (xy 0.11684 0.85344) (xy 0.13716 0.82804)
						(xy 0.1524 0.8001) (xy 0.16256 0.76835) (xy 0.1651 0.7366) (xy 0.1651 0.19685) (xy 0.17272 0.18923)
						(xy 0.17907 0.18034) (xy 0.18669 0.17145) (xy 0.19177 0.16256) (xy 0.19812 0.15367) (xy 0.20828 0.13335)
						(xy 0.21971 0.10287) (xy 0.22225 0.09271) (xy 0.22479 0.08128) (xy 0.22606 0.07112) (xy 0.2286 0.05969)
						(xy 0.2286 0.01651) (xy 0.22606 0.00508) (xy 0.22479 -0.00508) (xy 0.22225 -0.01651) (xy 0.21971 -0.02667)
						(xy 0.20828 -0.05715) (xy 0.19812 -0.07747) (xy 0.19177 -0.08636) (xy 0.18669 -0.09525) (xy 0.17907 -0.10414)
						(xy 0.17272 -0.11303) (xy 0.1651 -0.12065) (xy 0.1651 -0.7366) (xy 0.16256 -0.76835) (xy 0.1524 -0.8001)
						(xy 0.13716 -0.82804) (xy 0.11684 -0.85344) (xy 0.09144 -0.87376) (xy 0.0635 -0.889) (xy 0.03175 -0.89916)
					)
					(width 0)
					(fill yes)
				)
			)
		)
		(pad "145" smd custom
			(at 13.949934 -4.100068)
			(size 0.1143 0.1143)
			(layers "B.Cu" "B.Mask" "B.Paste")
			(net "M_A_DQ34")
			(options
				(clearance outline)
				(anchor circle)
			)
			(primitives
				(gr_poly
					(pts
						(xy 0 -0.9017) (xy -0.03175 -0.89916) (xy -0.0635 -0.889) (xy -0.09144 -0.87376) (xy -0.11684 -0.85344)
						(xy -0.13716 -0.82804) (xy -0.1524 -0.8001) (xy -0.16256 -0.76835) (xy -0.1651 -0.7366) (xy -0.1651 -0.44958)
						(xy -0.17272 -0.44196) (xy -0.19812 -0.4064) (xy -0.2032 -0.39624) (xy -0.20701 -0.38735) (xy -0.21209 -0.37719)
						(xy -0.2159 -0.36703) (xy -0.21844 -0.35687) (xy -0.22225 -0.34544) (xy -0.22352 -0.33528) (xy -0.22606 -0.32512)
						(xy -0.22733 -0.31369) (xy -0.22733 -0.30353) (xy -0.2286 -0.2921) (xy -0.22733 -0.28067) (xy -0.22733 -0.27051)
						(xy -0.22606 -0.25908) (xy -0.22352 -0.24892) (xy -0.22225 -0.23876) (xy -0.21844 -0.22733) (xy -0.2159 -0.21717)
						(xy -0.21209 -0.20701) (xy -0.20701 -0.19685) (xy -0.2032 -0.18796) (xy -0.19812 -0.1778) (xy -0.17272 -0.14224)
						(xy -0.1651 -0.13462) (xy -0.1651 0.7366) (xy -0.16256 0.76835) (xy -0.1524 0.8001) (xy -0.13716 0.82804)
						(xy -0.11684 0.85344) (xy -0.09144 0.87376) (xy -0.0635 0.889) (xy -0.03175 0.89916) (xy 0 0.9017)
						(xy 0.03175 0.89916) (xy 0.0635 0.889) (xy 0.09144 0.87376) (xy 0.11684 0.85344) (xy 0.13716 0.82804)
						(xy 0.1524 0.8001) (xy 0.16256 0.76835) (xy 0.1651 0.7366) (xy 0.1651 -0.13462) (xy 0.17272 -0.14224)
						(xy 0.19812 -0.1778) (xy 0.2032 -0.18796) (xy 0.20701 -0.19685) (xy 0.21209 -0.20701) (xy 0.2159 -0.21717)
						(xy 0.21844 -0.22733) (xy 0.22225 -0.23876) (xy 0.22352 -0.24892) (xy 0.22606 -0.25908) (xy 0.22733 -0.27051)
						(xy 0.22733 -0.28067) (xy 0.2286 -0.2921) (xy 0.22733 -0.30353) (xy 0.22733 -0.31369) (xy 0.22606 -0.32512)
						(xy 0.22352 -0.33528) (xy 0.22225 -0.34544) (xy 0.21844 -0.35687) (xy 0.2159 -0.36703) (xy 0.21209 -0.37719)
						(xy 0.20701 -0.38735) (xy 0.2032 -0.39624) (xy 0.19812 -0.4064) (xy 0.17272 -0.44196) (xy 0.1651 -0.44958)
						(xy 0.1651 -0.7366) (xy 0.16256 -0.76835) (xy 0.1524 -0.8001) (xy 0.13716 -0.82804) (xy 0.11684 -0.85344)
						(xy 0.09144 -0.87376) (xy 0.0635 -0.889) (xy 0.03175 -0.89916)
					)
					(width 0)
					(fill yes)
				)
			)
		)
		(pad "146" smd custom
			(at 14.249908 4.100068)
			(size 0.1143 0.1143)
			(layers "B.Cu" "B.Mask" "B.Paste")
			(net "GND")
			(options
				(clearance outline)
				(anchor circle)
			)
			(primitives
				(gr_poly
					(pts
						(xy 0 -0.9017) (xy -0.03175 -0.89916) (xy -0.0635 -0.889) (xy -0.09144 -0.87376) (xy -0.11684 -0.85344)
						(xy -0.13716 -0.82804) (xy -0.1524 -0.8001) (xy -0.16256 -0.76835) (xy -0.1651 -0.7366) (xy -0.1651 0.13462)
						(xy -0.17272 0.14224) (xy -0.19812 0.1778) (xy -0.2032 0.18796) (xy -0.20701 0.19685) (xy -0.21209 0.20701)
						(xy -0.2159 0.21717) (xy -0.21844 0.22733) (xy -0.22225 0.23876) (xy -0.22352 0.24892) (xy -0.22606 0.25908)
						(xy -0.22733 0.27051) (xy -0.22733 0.28067) (xy -0.2286 0.2921) (xy -0.22733 0.30353) (xy -0.22733 0.31369)
						(xy -0.22606 0.32512) (xy -0.22352 0.33528) (xy -0.22225 0.34544) (xy -0.21844 0.35687) (xy -0.2159 0.36703)
						(xy -0.21209 0.37719) (xy -0.20701 0.38735) (xy -0.2032 0.39624) (xy -0.19812 0.4064) (xy -0.17272 0.44196)
						(xy -0.1651 0.44958) (xy -0.1651 0.7366) (xy -0.16256 0.76835) (xy -0.1524 0.8001) (xy -0.13716 0.82804)
						(xy -0.11684 0.85344) (xy -0.09144 0.87376) (xy -0.0635 0.889) (xy -0.03175 0.89916) (xy 0 0.9017)
						(xy 0.03175 0.89916) (xy 0.0635 0.889) (xy 0.09144 0.87376) (xy 0.11684 0.85344) (xy 0.13716 0.82804)
						(xy 0.1524 0.8001) (xy 0.16256 0.76835) (xy 0.1651 0.7366) (xy 0.1651 0.44958) (xy 0.17272 0.44196)
						(xy 0.19812 0.4064) (xy 0.2032 0.39624) (xy 0.20701 0.38735) (xy 0.21209 0.37719) (xy 0.2159 0.36703)
						(xy 0.21844 0.35687) (xy 0.22225 0.34544) (xy 0.22352 0.33528) (xy 0.22606 0.32512) (xy 0.22733 0.31369)
						(xy 0.22733 0.30353) (xy 0.2286 0.2921) (xy 0.22733 0.28067) (xy 0.22733 0.27051) (xy 0.22606 0.25908)
						(xy 0.22352 0.24892) (xy 0.22225 0.23876) (xy 0.21844 0.22733) (xy 0.2159 0.21717) (xy 0.21209 0.20701)
						(xy 0.20701 0.19685) (xy 0.2032 0.18796) (xy 0.19812 0.1778) (xy 0.17272 0.14224) (xy 0.1651 0.13462)
						(xy 0.1651 -0.7366) (xy 0.16256 -0.76835) (xy 0.1524 -0.8001) (xy 0.13716 -0.82804) (xy 0.11684 -0.85344)
						(xy 0.09144 -0.87376) (xy 0.0635 -0.889) (xy 0.03175 -0.89916)
					)
					(width 0)
					(fill yes)
				)
			)
		)
		(pad "147" smd custom
			(at 14.549882 -4.100068)
			(size 0.1143 0.1143)
			(layers "B.Cu" "B.Mask" "B.Paste")
			(net "M_A_DQ35")
			(options
				(clearance outline)
				(anchor circle)
			)
			(primitives
				(gr_poly
					(pts
						(xy 0 -0.9017) (xy -0.03175 -0.89916) (xy -0.0635 -0.889) (xy -0.09144 -0.87376) (xy -0.11684 -0.85344)
						(xy -0.13716 -0.82804) (xy -0.1524 -0.8001) (xy -0.16256 -0.76835) (xy -0.1651 -0.7366) (xy -0.1651 -0.19685)
						(xy -0.17272 -0.18923) (xy -0.17907 -0.18034) (xy -0.18669 -0.17145) (xy -0.19177 -0.16256) (xy -0.19812 -0.15367)
						(xy -0.20828 -0.13335) (xy -0.21971 -0.10287) (xy -0.22225 -0.09271) (xy -0.22479 -0.08128) (xy -0.22606 -0.07112)
						(xy -0.2286 -0.05969) (xy -0.2286 -0.01651) (xy -0.22606 -0.00508) (xy -0.22479 0.00508) (xy -0.22225 0.01651)
						(xy -0.21971 0.02667) (xy -0.20828 0.05715) (xy -0.19812 0.07747) (xy -0.19177 0.08636) (xy -0.18669 0.09525)
						(xy -0.17907 0.10414) (xy -0.17272 0.11303) (xy -0.1651 0.12065) (xy -0.1651 0.7366) (xy -0.16256 0.76835)
						(xy -0.1524 0.8001) (xy -0.13716 0.82804) (xy -0.11684 0.85344) (xy -0.09144 0.87376) (xy -0.0635 0.889)
						(xy -0.03175 0.89916) (xy 0 0.9017) (xy 0.03175 0.89916) (xy 0.0635 0.889) (xy 0.09144 0.87376)
						(xy 0.11684 0.85344) (xy 0.13716 0.82804) (xy 0.1524 0.8001) (xy 0.16256 0.76835) (xy 0.1651 0.7366)
						(xy 0.1651 0.11938) (xy 0.17272 0.11176) (xy 0.19812 0.0762) (xy 0.2032 0.06604) (xy 0.20701 0.05715)
						(xy 0.21209 0.04699) (xy 0.2159 0.03683) (xy 0.21844 0.02667) (xy 0.22225 0.01524) (xy 0.22352 0.00508)
						(xy 0.22606 -0.00508) (xy 0.22733 -0.01651) (xy 0.22733 -0.02667) (xy 0.2286 -0.0381) (xy 0.22733 -0.04953)
						(xy 0.22733 -0.05969) (xy 0.22606 -0.07112) (xy 0.22352 -0.08128) (xy 0.22225 -0.09144) (xy 0.21844 -0.10287)
						(xy 0.2159 -0.11303) (xy 0.21209 -0.12319) (xy 0.20701 -0.13335) (xy 0.2032 -0.14224) (xy 0.19812 -0.1524)
						(xy 0.17272 -0.18796) (xy 0.1651 -0.19558) (xy 0.1651 -0.7366) (xy 0.16256 -0.76835) (xy 0.1524 -0.8001)
						(xy 0.13716 -0.82804) (xy 0.11684 -0.85344) (xy 0.09144 -0.87376) (xy 0.0635 -0.889) (xy 0.03175 -0.89916)
					)
					(width 0)
					(fill yes)
				)
			)
		)
		(pad "148" smd custom
			(at 14.85011 4.100068)
			(size 0.1143 0.1143)
			(layers "B.Cu" "B.Mask" "B.Paste")
			(net "M_A_DQ44")
			(options
				(clearance outline)
				(anchor circle)
			)
			(primitives
				(gr_poly
					(pts
						(xy 0 -0.9017) (xy -0.03175 -0.89916) (xy -0.0635 -0.889) (xy -0.09144 -0.87376) (xy -0.11684 -0.85344)
						(xy -0.13716 -0.82804) (xy -0.1524 -0.8001) (xy -0.16256 -0.76835) (xy -0.1651 -0.7366) (xy -0.1651 -0.11938)
						(xy -0.17272 -0.11176) (xy -0.19812 -0.0762) (xy -0.2032 -0.06604) (xy -0.20701 -0.05715) (xy -0.21209 -0.04699)
						(xy -0.2159 -0.03683) (xy -0.21844 -0.02667) (xy -0.22225 -0.01524) (xy -0.22352 -0.00508) (xy -0.22606 0.00508)
						(xy -0.22733 0.01651) (xy -0.22733 0.02667) (xy -0.2286 0.0381) (xy -0.22733 0.04953) (xy -0.22733 0.05969)
						(xy -0.22606 0.07112) (xy -0.22352 0.08128) (xy -0.22225 0.09144) (xy -0.21844 0.10287) (xy -0.2159 0.11303)
						(xy -0.21209 0.12319) (xy -0.20701 0.13335) (xy -0.2032 0.14224) (xy -0.19812 0.1524) (xy -0.17272 0.18796)
						(xy -0.1651 0.19558) (xy -0.1651 0.7366) (xy -0.16256 0.76835) (xy -0.1524 0.8001) (xy -0.13716 0.82804)
						(xy -0.11684 0.85344) (xy -0.09144 0.87376) (xy -0.0635 0.889) (xy -0.03175 0.89916) (xy 0 0.9017)
						(xy 0.03175 0.89916) (xy 0.0635 0.889) (xy 0.09144 0.87376) (xy 0.11684 0.85344) (xy 0.13716 0.82804)
						(xy 0.1524 0.8001) (xy 0.16256 0.76835) (xy 0.1651 0.7366) (xy 0.1651 0.19685) (xy 0.17272 0.18923)
						(xy 0.17907 0.18034) (xy 0.18669 0.17145) (xy 0.19177 0.16256) (xy 0.19812 0.15367) (xy 0.20828 0.13335)
						(xy 0.21971 0.10287) (xy 0.22225 0.09271) (xy 0.22479 0.08128) (xy 0.22606 0.07112) (xy 0.2286 0.05969)
						(xy 0.2286 0.01651) (xy 0.22606 0.00508) (xy 0.22479 -0.00508) (xy 0.22225 -0.01651) (xy 0.21971 -0.02667)
						(xy 0.20828 -0.05715) (xy 0.19812 -0.07747) (xy 0.19177 -0.08636) (xy 0.18669 -0.09525) (xy 0.17907 -0.10414)
						(xy 0.17272 -0.11303) (xy 0.1651 -0.12065) (xy 0.1651 -0.7366) (xy 0.16256 -0.76835) (xy 0.1524 -0.8001)
						(xy 0.13716 -0.82804) (xy 0.11684 -0.85344) (xy 0.09144 -0.87376) (xy 0.0635 -0.889) (xy 0.03175 -0.89916)
					)
					(width 0)
					(fill yes)
				)
			)
		)
		(pad "149" smd custom
			(at 15.150084 -4.100068)
			(size 0.1143 0.1143)
			(layers "B.Cu" "B.Mask" "B.Paste")
			(net "GND")
			(options
				(clearance outline)
				(anchor circle)
			)
			(primitives
				(gr_poly
					(pts
						(xy 0 -0.9017) (xy -0.03175 -0.89916) (xy -0.0635 -0.889) (xy -0.09144 -0.87376) (xy -0.11684 -0.85344)
						(xy -0.13716 -0.82804) (xy -0.1524 -0.8001) (xy -0.16256 -0.76835) (xy -0.1651 -0.7366) (xy -0.1651 -0.44958)
						(xy -0.17272 -0.44196) (xy -0.19812 -0.4064) (xy -0.2032 -0.39624) (xy -0.20701 -0.38735) (xy -0.21209 -0.37719)
						(xy -0.2159 -0.36703) (xy -0.21844 -0.35687) (xy -0.22225 -0.34544) (xy -0.22352 -0.33528) (xy -0.22606 -0.32512)
						(xy -0.22733 -0.31369) (xy -0.22733 -0.30353) (xy -0.2286 -0.2921) (xy -0.22733 -0.28067) (xy -0.22733 -0.27051)
						(xy -0.22606 -0.25908) (xy -0.22352 -0.24892) (xy -0.22225 -0.23876) (xy -0.21844 -0.22733) (xy -0.2159 -0.21717)
						(xy -0.21209 -0.20701) (xy -0.20701 -0.19685) (xy -0.2032 -0.18796) (xy -0.19812 -0.1778) (xy -0.17272 -0.14224)
						(xy -0.1651 -0.13462) (xy -0.1651 0.7366) (xy -0.16256 0.76835) (xy -0.1524 0.8001) (xy -0.13716 0.82804)
						(xy -0.11684 0.85344) (xy -0.09144 0.87376) (xy -0.0635 0.889) (xy -0.03175 0.89916) (xy 0 0.9017)
						(xy 0.03175 0.89916) (xy 0.0635 0.889) (xy 0.09144 0.87376) (xy 0.11684 0.85344) (xy 0.13716 0.82804)
						(xy 0.1524 0.8001) (xy 0.16256 0.76835) (xy 0.1651 0.7366) (xy 0.1651 -0.13462) (xy 0.17272 -0.14224)
						(xy 0.19812 -0.1778) (xy 0.2032 -0.18796) (xy 0.20701 -0.19685) (xy 0.21209 -0.20701) (xy 0.2159 -0.21717)
						(xy 0.21844 -0.22733) (xy 0.22225 -0.23876) (xy 0.22352 -0.24892) (xy 0.22606 -0.25908) (xy 0.22733 -0.27051)
						(xy 0.22733 -0.28067) (xy 0.2286 -0.2921) (xy 0.22733 -0.30353) (xy 0.22733 -0.31369) (xy 0.22606 -0.32512)
						(xy 0.22352 -0.33528) (xy 0.22225 -0.34544) (xy 0.21844 -0.35687) (xy 0.2159 -0.36703) (xy 0.21209 -0.37719)
						(xy 0.20701 -0.38735) (xy 0.2032 -0.39624) (xy 0.19812 -0.4064) (xy 0.17272 -0.44196) (xy 0.1651 -0.44958)
						(xy 0.1651 -0.7366) (xy 0.16256 -0.76835) (xy 0.1524 -0.8001) (xy 0.13716 -0.82804) (xy 0.11684 -0.85344)
						(xy 0.09144 -0.87376) (xy 0.0635 -0.889) (xy 0.03175 -0.89916)
					)
					(width 0)
					(fill yes)
				)
			)
		)
		(pad "150" smd custom
			(at 15.450058 4.100068)
			(size 0.1143 0.1143)
			(layers "B.Cu" "B.Mask" "B.Paste")
			(net "M_A_DQ45")
			(options
				(clearance outline)
				(anchor circle)
			)
			(primitives
				(gr_poly
					(pts
						(xy 0 -0.9017) (xy -0.03175 -0.89916) (xy -0.0635 -0.889) (xy -0.09144 -0.87376) (xy -0.11684 -0.85344)
						(xy -0.13716 -0.82804) (xy -0.1524 -0.8001) (xy -0.16256 -0.76835) (xy -0.1651 -0.7366) (xy -0.1651 0.13462)
						(xy -0.17272 0.14224) (xy -0.19812 0.1778) (xy -0.2032 0.18796) (xy -0.20701 0.19685) (xy -0.21209 0.20701)
						(xy -0.2159 0.21717) (xy -0.21844 0.22733) (xy -0.22225 0.23876) (xy -0.22352 0.24892) (xy -0.22606 0.25908)
						(xy -0.22733 0.27051) (xy -0.22733 0.28067) (xy -0.2286 0.2921) (xy -0.22733 0.30353) (xy -0.22733 0.31369)
						(xy -0.22606 0.32512) (xy -0.22352 0.33528) (xy -0.22225 0.34544) (xy -0.21844 0.35687) (xy -0.2159 0.36703)
						(xy -0.21209 0.37719) (xy -0.20701 0.38735) (xy -0.2032 0.39624) (xy -0.19812 0.4064) (xy -0.17272 0.44196)
						(xy -0.1651 0.44958) (xy -0.1651 0.7366) (xy -0.16256 0.76835) (xy -0.1524 0.8001) (xy -0.13716 0.82804)
						(xy -0.11684 0.85344) (xy -0.09144 0.87376) (xy -0.0635 0.889) (xy -0.03175 0.89916) (xy 0 0.9017)
						(xy 0.03175 0.89916) (xy 0.0635 0.889) (xy 0.09144 0.87376) (xy 0.11684 0.85344) (xy 0.13716 0.82804)
						(xy 0.1524 0.8001) (xy 0.16256 0.76835) (xy 0.1651 0.7366) (xy 0.1651 0.44958) (xy 0.17272 0.44196)
						(xy 0.19812 0.4064) (xy 0.2032 0.39624) (xy 0.20701 0.38735) (xy 0.21209 0.37719) (xy 0.2159 0.36703)
						(xy 0.21844 0.35687) (xy 0.22225 0.34544) (xy 0.22352 0.33528) (xy 0.22606 0.32512) (xy 0.22733 0.31369)
						(xy 0.22733 0.30353) (xy 0.2286 0.2921) (xy 0.22733 0.28067) (xy 0.22733 0.27051) (xy 0.22606 0.25908)
						(xy 0.22352 0.24892) (xy 0.22225 0.23876) (xy 0.21844 0.22733) (xy 0.2159 0.21717) (xy 0.21209 0.20701)
						(xy 0.20701 0.19685) (xy 0.2032 0.18796) (xy 0.19812 0.1778) (xy 0.17272 0.14224) (xy 0.1651 0.13462)
						(xy 0.1651 -0.7366) (xy 0.16256 -0.76835) (xy 0.1524 -0.8001) (xy 0.13716 -0.82804) (xy 0.11684 -0.85344)
						(xy 0.09144 -0.87376) (xy 0.0635 -0.889) (xy 0.03175 -0.89916)
					)
					(width 0)
					(fill yes)
				)
			)
		)
		(pad "151" smd custom
			(at 15.750032 -4.100068)
			(size 0.1143 0.1143)
			(layers "B.Cu" "B.Mask" "B.Paste")
			(net "M_A_DQ40")
			(options
				(clearance outline)
				(anchor circle)
			)
			(primitives
				(gr_poly
					(pts
						(xy 0 -0.9017) (xy -0.03175 -0.89916) (xy -0.0635 -0.889) (xy -0.09144 -0.87376) (xy -0.11684 -0.85344)
						(xy -0.13716 -0.82804) (xy -0.1524 -0.8001) (xy -0.16256 -0.76835) (xy -0.1651 -0.7366) (xy -0.1651 -0.19685)
						(xy -0.17272 -0.18923) (xy -0.17907 -0.18034) (xy -0.18669 -0.17145) (xy -0.19177 -0.16256) (xy -0.19812 -0.15367)
						(xy -0.20828 -0.13335) (xy -0.21971 -0.10287) (xy -0.22225 -0.09271) (xy -0.22479 -0.08128) (xy -0.22606 -0.07112)
						(xy -0.2286 -0.05969) (xy -0.2286 -0.01651) (xy -0.22606 -0.00508) (xy -0.22479 0.00508) (xy -0.22225 0.01651)
						(xy -0.21971 0.02667) (xy -0.20828 0.05715) (xy -0.19812 0.07747) (xy -0.19177 0.08636) (xy -0.18669 0.09525)
						(xy -0.17907 0.10414) (xy -0.17272 0.11303) (xy -0.1651 0.12065) (xy -0.1651 0.7366) (xy -0.16256 0.76835)
						(xy -0.1524 0.8001) (xy -0.13716 0.82804) (xy -0.11684 0.85344) (xy -0.09144 0.87376) (xy -0.0635 0.889)
						(xy -0.03175 0.89916) (xy 0 0.9017) (xy 0.03175 0.89916) (xy 0.0635 0.889) (xy 0.09144 0.87376)
						(xy 0.11684 0.85344) (xy 0.13716 0.82804) (xy 0.1524 0.8001) (xy 0.16256 0.76835) (xy 0.1651 0.7366)
						(xy 0.1651 0.11938) (xy 0.17272 0.11176) (xy 0.19812 0.0762) (xy 0.2032 0.06604) (xy 0.20701 0.05715)
						(xy 0.21209 0.04699) (xy 0.2159 0.03683) (xy 0.21844 0.02667) (xy 0.22225 0.01524) (xy 0.22352 0.00508)
						(xy 0.22606 -0.00508) (xy 0.22733 -0.01651) (xy 0.22733 -0.02667) (xy 0.2286 -0.0381) (xy 0.22733 -0.04953)
						(xy 0.22733 -0.05969) (xy 0.22606 -0.07112) (xy 0.22352 -0.08128) (xy 0.22225 -0.09144) (xy 0.21844 -0.10287)
						(xy 0.2159 -0.11303) (xy 0.21209 -0.12319) (xy 0.20701 -0.13335) (xy 0.2032 -0.14224) (xy 0.19812 -0.1524)
						(xy 0.17272 -0.18796) (xy 0.1651 -0.19558) (xy 0.1651 -0.7366) (xy 0.16256 -0.76835) (xy 0.1524 -0.8001)
						(xy 0.13716 -0.82804) (xy 0.11684 -0.85344) (xy 0.09144 -0.87376) (xy 0.0635 -0.889) (xy 0.03175 -0.89916)
					)
					(width 0)
					(fill yes)
				)
			)
		)
		(pad "152" smd custom
			(at 16.050006 4.100068)
			(size 0.1143 0.1143)
			(layers "B.Cu" "B.Mask" "B.Paste")
			(net "GND")
			(options
				(clearance outline)
				(anchor circle)
			)
			(primitives
				(gr_poly
					(pts
						(xy 0 -0.9017) (xy -0.03175 -0.89916) (xy -0.0635 -0.889) (xy -0.09144 -0.87376) (xy -0.11684 -0.85344)
						(xy -0.13716 -0.82804) (xy -0.1524 -0.8001) (xy -0.16256 -0.76835) (xy -0.1651 -0.7366) (xy -0.1651 -0.11938)
						(xy -0.17272 -0.11176) (xy -0.19812 -0.0762) (xy -0.2032 -0.06604) (xy -0.20701 -0.05715) (xy -0.21209 -0.04699)
						(xy -0.2159 -0.03683) (xy -0.21844 -0.02667) (xy -0.22225 -0.01524) (xy -0.22352 -0.00508) (xy -0.22606 0.00508)
						(xy -0.22733 0.01651) (xy -0.22733 0.02667) (xy -0.2286 0.0381) (xy -0.22733 0.04953) (xy -0.22733 0.05969)
						(xy -0.22606 0.07112) (xy -0.22352 0.08128) (xy -0.22225 0.09144) (xy -0.21844 0.10287) (xy -0.2159 0.11303)
						(xy -0.21209 0.12319) (xy -0.20701 0.13335) (xy -0.2032 0.14224) (xy -0.19812 0.1524) (xy -0.17272 0.18796)
						(xy -0.1651 0.19558) (xy -0.1651 0.7366) (xy -0.16256 0.76835) (xy -0.1524 0.8001) (xy -0.13716 0.82804)
						(xy -0.11684 0.85344) (xy -0.09144 0.87376) (xy -0.0635 0.889) (xy -0.03175 0.89916) (xy 0 0.9017)
						(xy 0.03175 0.89916) (xy 0.0635 0.889) (xy 0.09144 0.87376) (xy 0.11684 0.85344) (xy 0.13716 0.82804)
						(xy 0.1524 0.8001) (xy 0.16256 0.76835) (xy 0.1651 0.7366) (xy 0.1651 0.19685) (xy 0.17272 0.18923)
						(xy 0.17907 0.18034) (xy 0.18669 0.17145) (xy 0.19177 0.16256) (xy 0.19812 0.15367) (xy 0.20828 0.13335)
						(xy 0.21971 0.10287) (xy 0.22225 0.09271) (xy 0.22479 0.08128) (xy 0.22606 0.07112) (xy 0.2286 0.05969)
						(xy 0.2286 0.01651) (xy 0.22606 0.00508) (xy 0.22479 -0.00508) (xy 0.22225 -0.01651) (xy 0.21971 -0.02667)
						(xy 0.20828 -0.05715) (xy 0.19812 -0.07747) (xy 0.19177 -0.08636) (xy 0.18669 -0.09525) (xy 0.17907 -0.10414)
						(xy 0.17272 -0.11303) (xy 0.1651 -0.12065) (xy 0.1651 -0.7366) (xy 0.16256 -0.76835) (xy 0.1524 -0.8001)
						(xy 0.13716 -0.82804) (xy 0.11684 -0.85344) (xy 0.09144 -0.87376) (xy 0.0635 -0.889) (xy 0.03175 -0.89916)
					)
					(width 0)
					(fill yes)
				)
			)
		)
		(pad "153" smd custom
			(at 16.34998 -4.100068)
			(size 0.1143 0.1143)
			(layers "B.Cu" "B.Mask" "B.Paste")
			(net "M_A_DQ41")
			(options
				(clearance outline)
				(anchor circle)
			)
			(primitives
				(gr_poly
					(pts
						(xy 0 -0.9017) (xy -0.03175 -0.89916) (xy -0.0635 -0.889) (xy -0.09144 -0.87376) (xy -0.11684 -0.85344)
						(xy -0.13716 -0.82804) (xy -0.1524 -0.8001) (xy -0.16256 -0.76835) (xy -0.1651 -0.7366) (xy -0.1651 -0.44958)
						(xy -0.17272 -0.44196) (xy -0.19812 -0.4064) (xy -0.2032 -0.39624) (xy -0.20701 -0.38735) (xy -0.21209 -0.37719)
						(xy -0.2159 -0.36703) (xy -0.21844 -0.35687) (xy -0.22225 -0.34544) (xy -0.22352 -0.33528) (xy -0.22606 -0.32512)
						(xy -0.22733 -0.31369) (xy -0.22733 -0.30353) (xy -0.2286 -0.2921) (xy -0.22733 -0.28067) (xy -0.22733 -0.27051)
						(xy -0.22606 -0.25908) (xy -0.22352 -0.24892) (xy -0.22225 -0.23876) (xy -0.21844 -0.22733) (xy -0.2159 -0.21717)
						(xy -0.21209 -0.20701) (xy -0.20701 -0.19685) (xy -0.2032 -0.18796) (xy -0.19812 -0.1778) (xy -0.17272 -0.14224)
						(xy -0.1651 -0.13462) (xy -0.1651 0.7366) (xy -0.16256 0.76835) (xy -0.1524 0.8001) (xy -0.13716 0.82804)
						(xy -0.11684 0.85344) (xy -0.09144 0.87376) (xy -0.0635 0.889) (xy -0.03175 0.89916) (xy 0 0.9017)
						(xy 0.03175 0.89916) (xy 0.0635 0.889) (xy 0.09144 0.87376) (xy 0.11684 0.85344) (xy 0.13716 0.82804)
						(xy 0.1524 0.8001) (xy 0.16256 0.76835) (xy 0.1651 0.7366) (xy 0.1651 -0.13462) (xy 0.17272 -0.14224)
						(xy 0.19812 -0.1778) (xy 0.2032 -0.18796) (xy 0.20701 -0.19685) (xy 0.21209 -0.20701) (xy 0.2159 -0.21717)
						(xy 0.21844 -0.22733) (xy 0.22225 -0.23876) (xy 0.22352 -0.24892) (xy 0.22606 -0.25908) (xy 0.22733 -0.27051)
						(xy 0.22733 -0.28067) (xy 0.2286 -0.2921) (xy 0.22733 -0.30353) (xy 0.22733 -0.31369) (xy 0.22606 -0.32512)
						(xy 0.22352 -0.33528) (xy 0.22225 -0.34544) (xy 0.21844 -0.35687) (xy 0.2159 -0.36703) (xy 0.21209 -0.37719)
						(xy 0.20701 -0.38735) (xy 0.2032 -0.39624) (xy 0.19812 -0.4064) (xy 0.17272 -0.44196) (xy 0.1651 -0.44958)
						(xy 0.1651 -0.7366) (xy 0.16256 -0.76835) (xy 0.1524 -0.8001) (xy 0.13716 -0.82804) (xy 0.11684 -0.85344)
						(xy 0.09144 -0.87376) (xy 0.0635 -0.889) (xy 0.03175 -0.89916)
					)
					(width 0)
					(fill yes)
				)
			)
		)
		(pad "154" smd custom
			(at 16.649954 4.100068)
			(size 0.1143 0.1143)
			(layers "B.Cu" "B.Mask" "B.Paste")
			(net "M_A_DQS_DN5")
			(options
				(clearance outline)
				(anchor circle)
			)
			(primitives
				(gr_poly
					(pts
						(xy 0 -0.9017) (xy -0.03175 -0.89916) (xy -0.0635 -0.889) (xy -0.09144 -0.87376) (xy -0.11684 -0.85344)
						(xy -0.13716 -0.82804) (xy -0.1524 -0.8001) (xy -0.16256 -0.76835) (xy -0.1651 -0.7366) (xy -0.1651 0.13462)
						(xy -0.17272 0.14224) (xy -0.19812 0.1778) (xy -0.2032 0.18796) (xy -0.20701 0.19685) (xy -0.21209 0.20701)
						(xy -0.2159 0.21717) (xy -0.21844 0.22733) (xy -0.22225 0.23876) (xy -0.22352 0.24892) (xy -0.22606 0.25908)
						(xy -0.22733 0.27051) (xy -0.22733 0.28067) (xy -0.2286 0.2921) (xy -0.22733 0.30353) (xy -0.22733 0.31369)
						(xy -0.22606 0.32512) (xy -0.22352 0.33528) (xy -0.22225 0.34544) (xy -0.21844 0.35687) (xy -0.2159 0.36703)
						(xy -0.21209 0.37719) (xy -0.20701 0.38735) (xy -0.2032 0.39624) (xy -0.19812 0.4064) (xy -0.17272 0.44196)
						(xy -0.1651 0.44958) (xy -0.1651 0.7366) (xy -0.16256 0.76835) (xy -0.1524 0.8001) (xy -0.13716 0.82804)
						(xy -0.11684 0.85344) (xy -0.09144 0.87376) (xy -0.0635 0.889) (xy -0.03175 0.89916) (xy 0 0.9017)
						(xy 0.03175 0.89916) (xy 0.0635 0.889) (xy 0.09144 0.87376) (xy 0.11684 0.85344) (xy 0.13716 0.82804)
						(xy 0.1524 0.8001) (xy 0.16256 0.76835) (xy 0.1651 0.7366) (xy 0.1651 0.44958) (xy 0.17272 0.44196)
						(xy 0.19812 0.4064) (xy 0.2032 0.39624) (xy 0.20701 0.38735) (xy 0.21209 0.37719) (xy 0.2159 0.36703)
						(xy 0.21844 0.35687) (xy 0.22225 0.34544) (xy 0.22352 0.33528) (xy 0.22606 0.32512) (xy 0.22733 0.31369)
						(xy 0.22733 0.30353) (xy 0.2286 0.2921) (xy 0.22733 0.28067) (xy 0.22733 0.27051) (xy 0.22606 0.25908)
						(xy 0.22352 0.24892) (xy 0.22225 0.23876) (xy 0.21844 0.22733) (xy 0.2159 0.21717) (xy 0.21209 0.20701)
						(xy 0.20701 0.19685) (xy 0.2032 0.18796) (xy 0.19812 0.1778) (xy 0.17272 0.14224) (xy 0.1651 0.13462)
						(xy 0.1651 -0.7366) (xy 0.16256 -0.76835) (xy 0.1524 -0.8001) (xy 0.13716 -0.82804) (xy 0.11684 -0.85344)
						(xy 0.09144 -0.87376) (xy 0.0635 -0.889) (xy 0.03175 -0.89916)
					)
					(width 0)
					(fill yes)
				)
			)
		)
		(pad "155" smd custom
			(at 16.949928 -4.100068)
			(size 0.1143 0.1143)
			(layers "B.Cu" "B.Mask" "B.Paste")
			(net "GND")
			(options
				(clearance outline)
				(anchor circle)
			)
			(primitives
				(gr_poly
					(pts
						(xy 0 -0.9017) (xy -0.03175 -0.89916) (xy -0.0635 -0.889) (xy -0.09144 -0.87376) (xy -0.11684 -0.85344)
						(xy -0.13716 -0.82804) (xy -0.1524 -0.8001) (xy -0.16256 -0.76835) (xy -0.1651 -0.7366) (xy -0.1651 -0.19685)
						(xy -0.17272 -0.18923) (xy -0.17907 -0.18034) (xy -0.18669 -0.17145) (xy -0.19177 -0.16256) (xy -0.19812 -0.15367)
						(xy -0.20828 -0.13335) (xy -0.21971 -0.10287) (xy -0.22225 -0.09271) (xy -0.22479 -0.08128) (xy -0.22606 -0.07112)
						(xy -0.2286 -0.05969) (xy -0.2286 -0.01651) (xy -0.22606 -0.00508) (xy -0.22479 0.00508) (xy -0.22225 0.01651)
						(xy -0.21971 0.02667) (xy -0.20828 0.05715) (xy -0.19812 0.07747) (xy -0.19177 0.08636) (xy -0.18669 0.09525)
						(xy -0.17907 0.10414) (xy -0.17272 0.11303) (xy -0.1651 0.12065) (xy -0.1651 0.7366) (xy -0.16256 0.76835)
						(xy -0.1524 0.8001) (xy -0.13716 0.82804) (xy -0.11684 0.85344) (xy -0.09144 0.87376) (xy -0.0635 0.889)
						(xy -0.03175 0.89916) (xy 0 0.9017) (xy 0.03175 0.89916) (xy 0.0635 0.889) (xy 0.09144 0.87376)
						(xy 0.11684 0.85344) (xy 0.13716 0.82804) (xy 0.1524 0.8001) (xy 0.16256 0.76835) (xy 0.1651 0.7366)
						(xy 0.1651 0.11938) (xy 0.17272 0.11176) (xy 0.19812 0.0762) (xy 0.2032 0.06604) (xy 0.20701 0.05715)
						(xy 0.21209 0.04699) (xy 0.2159 0.03683) (xy 0.21844 0.02667) (xy 0.22225 0.01524) (xy 0.22352 0.00508)
						(xy 0.22606 -0.00508) (xy 0.22733 -0.01651) (xy 0.22733 -0.02667) (xy 0.2286 -0.0381) (xy 0.22733 -0.04953)
						(xy 0.22733 -0.05969) (xy 0.22606 -0.07112) (xy 0.22352 -0.08128) (xy 0.22225 -0.09144) (xy 0.21844 -0.10287)
						(xy 0.2159 -0.11303) (xy 0.21209 -0.12319) (xy 0.20701 -0.13335) (xy 0.2032 -0.14224) (xy 0.19812 -0.1524)
						(xy 0.17272 -0.18796) (xy 0.1651 -0.19558) (xy 0.1651 -0.7366) (xy 0.16256 -0.76835) (xy 0.1524 -0.8001)
						(xy 0.13716 -0.82804) (xy 0.11684 -0.85344) (xy 0.09144 -0.87376) (xy 0.0635 -0.889) (xy 0.03175 -0.89916)
					)
					(width 0)
					(fill yes)
				)
			)
		)
		(pad "156" smd custom
			(at 17.249902 4.100068)
			(size 0.1143 0.1143)
			(layers "B.Cu" "B.Mask" "B.Paste")
			(net "M_A_DQS_DP5")
			(options
				(clearance outline)
				(anchor circle)
			)
			(primitives
				(gr_poly
					(pts
						(xy 0 -0.9017) (xy -0.03175 -0.89916) (xy -0.0635 -0.889) (xy -0.09144 -0.87376) (xy -0.11684 -0.85344)
						(xy -0.13716 -0.82804) (xy -0.1524 -0.8001) (xy -0.16256 -0.76835) (xy -0.1651 -0.7366) (xy -0.1651 -0.11938)
						(xy -0.17272 -0.11176) (xy -0.19812 -0.0762) (xy -0.2032 -0.06604) (xy -0.20701 -0.05715) (xy -0.21209 -0.04699)
						(xy -0.2159 -0.03683) (xy -0.21844 -0.02667) (xy -0.22225 -0.01524) (xy -0.22352 -0.00508) (xy -0.22606 0.00508)
						(xy -0.22733 0.01651) (xy -0.22733 0.02667) (xy -0.2286 0.0381) (xy -0.22733 0.04953) (xy -0.22733 0.05969)
						(xy -0.22606 0.07112) (xy -0.22352 0.08128) (xy -0.22225 0.09144) (xy -0.21844 0.10287) (xy -0.2159 0.11303)
						(xy -0.21209 0.12319) (xy -0.20701 0.13335) (xy -0.2032 0.14224) (xy -0.19812 0.1524) (xy -0.17272 0.18796)
						(xy -0.1651 0.19558) (xy -0.1651 0.7366) (xy -0.16256 0.76835) (xy -0.1524 0.8001) (xy -0.13716 0.82804)
						(xy -0.11684 0.85344) (xy -0.09144 0.87376) (xy -0.0635 0.889) (xy -0.03175 0.89916) (xy 0 0.9017)
						(xy 0.03175 0.89916) (xy 0.0635 0.889) (xy 0.09144 0.87376) (xy 0.11684 0.85344) (xy 0.13716 0.82804)
						(xy 0.1524 0.8001) (xy 0.16256 0.76835) (xy 0.1651 0.7366) (xy 0.1651 0.19685) (xy 0.17272 0.18923)
						(xy 0.17907 0.18034) (xy 0.18669 0.17145) (xy 0.19177 0.16256) (xy 0.19812 0.15367) (xy 0.20828 0.13335)
						(xy 0.21971 0.10287) (xy 0.22225 0.09271) (xy 0.22479 0.08128) (xy 0.22606 0.07112) (xy 0.2286 0.05969)
						(xy 0.2286 0.01651) (xy 0.22606 0.00508) (xy 0.22479 -0.00508) (xy 0.22225 -0.01651) (xy 0.21971 -0.02667)
						(xy 0.20828 -0.05715) (xy 0.19812 -0.07747) (xy 0.19177 -0.08636) (xy 0.18669 -0.09525) (xy 0.17907 -0.10414)
						(xy 0.17272 -0.11303) (xy 0.1651 -0.12065) (xy 0.1651 -0.7366) (xy 0.16256 -0.76835) (xy 0.1524 -0.8001)
						(xy 0.13716 -0.82804) (xy 0.11684 -0.85344) (xy 0.09144 -0.87376) (xy 0.0635 -0.889) (xy 0.03175 -0.89916)
					)
					(width 0)
					(fill yes)
				)
			)
		)
		(pad "157" smd custom
			(at 17.549876 -4.100068)
			(size 0.1143 0.1143)
			(layers "B.Cu" "B.Mask" "B.Paste")
			(net "GND")
			(options
				(clearance outline)
				(anchor circle)
			)
			(primitives
				(gr_poly
					(pts
						(xy 0 -0.9017) (xy -0.03175 -0.89916) (xy -0.0635 -0.889) (xy -0.09144 -0.87376) (xy -0.11684 -0.85344)
						(xy -0.13716 -0.82804) (xy -0.1524 -0.8001) (xy -0.16256 -0.76835) (xy -0.1651 -0.7366) (xy -0.1651 -0.44958)
						(xy -0.17272 -0.44196) (xy -0.19812 -0.4064) (xy -0.2032 -0.39624) (xy -0.20701 -0.38735) (xy -0.21209 -0.37719)
						(xy -0.2159 -0.36703) (xy -0.21844 -0.35687) (xy -0.22225 -0.34544) (xy -0.22352 -0.33528) (xy -0.22606 -0.32512)
						(xy -0.22733 -0.31369) (xy -0.22733 -0.30353) (xy -0.2286 -0.2921) (xy -0.22733 -0.28067) (xy -0.22733 -0.27051)
						(xy -0.22606 -0.25908) (xy -0.22352 -0.24892) (xy -0.22225 -0.23876) (xy -0.21844 -0.22733) (xy -0.2159 -0.21717)
						(xy -0.21209 -0.20701) (xy -0.20701 -0.19685) (xy -0.2032 -0.18796) (xy -0.19812 -0.1778) (xy -0.17272 -0.14224)
						(xy -0.1651 -0.13462) (xy -0.1651 0.7366) (xy -0.16256 0.76835) (xy -0.1524 0.8001) (xy -0.13716 0.82804)
						(xy -0.11684 0.85344) (xy -0.09144 0.87376) (xy -0.0635 0.889) (xy -0.03175 0.89916) (xy 0 0.9017)
						(xy 0.03175 0.89916) (xy 0.0635 0.889) (xy 0.09144 0.87376) (xy 0.11684 0.85344) (xy 0.13716 0.82804)
						(xy 0.1524 0.8001) (xy 0.16256 0.76835) (xy 0.1651 0.7366) (xy 0.1651 -0.13462) (xy 0.17272 -0.14224)
						(xy 0.19812 -0.1778) (xy 0.2032 -0.18796) (xy 0.20701 -0.19685) (xy 0.21209 -0.20701) (xy 0.2159 -0.21717)
						(xy 0.21844 -0.22733) (xy 0.22225 -0.23876) (xy 0.22352 -0.24892) (xy 0.22606 -0.25908) (xy 0.22733 -0.27051)
						(xy 0.22733 -0.28067) (xy 0.2286 -0.2921) (xy 0.22733 -0.30353) (xy 0.22733 -0.31369) (xy 0.22606 -0.32512)
						(xy 0.22352 -0.33528) (xy 0.22225 -0.34544) (xy 0.21844 -0.35687) (xy 0.2159 -0.36703) (xy 0.21209 -0.37719)
						(xy 0.20701 -0.38735) (xy 0.2032 -0.39624) (xy 0.19812 -0.4064) (xy 0.17272 -0.44196) (xy 0.1651 -0.44958)
						(xy 0.1651 -0.7366) (xy 0.16256 -0.76835) (xy 0.1524 -0.8001) (xy 0.13716 -0.82804) (xy 0.11684 -0.85344)
						(xy 0.09144 -0.87376) (xy 0.0635 -0.889) (xy 0.03175 -0.89916)
					)
					(width 0)
					(fill yes)
				)
			)
		)
		(pad "158" smd custom
			(at 17.850104 4.100068)
			(size 0.1143 0.1143)
			(layers "B.Cu" "B.Mask" "B.Paste")
			(net "GND")
			(options
				(clearance outline)
				(anchor circle)
			)
			(primitives
				(gr_poly
					(pts
						(xy 0 -0.9017) (xy -0.03175 -0.89916) (xy -0.0635 -0.889) (xy -0.09144 -0.87376) (xy -0.11684 -0.85344)
						(xy -0.13716 -0.82804) (xy -0.1524 -0.8001) (xy -0.16256 -0.76835) (xy -0.1651 -0.7366) (xy -0.1651 0.13462)
						(xy -0.17272 0.14224) (xy -0.19812 0.1778) (xy -0.2032 0.18796) (xy -0.20701 0.19685) (xy -0.21209 0.20701)
						(xy -0.2159 0.21717) (xy -0.21844 0.22733) (xy -0.22225 0.23876) (xy -0.22352 0.24892) (xy -0.22606 0.25908)
						(xy -0.22733 0.27051) (xy -0.22733 0.28067) (xy -0.2286 0.2921) (xy -0.22733 0.30353) (xy -0.22733 0.31369)
						(xy -0.22606 0.32512) (xy -0.22352 0.33528) (xy -0.22225 0.34544) (xy -0.21844 0.35687) (xy -0.2159 0.36703)
						(xy -0.21209 0.37719) (xy -0.20701 0.38735) (xy -0.2032 0.39624) (xy -0.19812 0.4064) (xy -0.17272 0.44196)
						(xy -0.1651 0.44958) (xy -0.1651 0.7366) (xy -0.16256 0.76835) (xy -0.1524 0.8001) (xy -0.13716 0.82804)
						(xy -0.11684 0.85344) (xy -0.09144 0.87376) (xy -0.0635 0.889) (xy -0.03175 0.89916) (xy 0 0.9017)
						(xy 0.03175 0.89916) (xy 0.0635 0.889) (xy 0.09144 0.87376) (xy 0.11684 0.85344) (xy 0.13716 0.82804)
						(xy 0.1524 0.8001) (xy 0.16256 0.76835) (xy 0.1651 0.7366) (xy 0.1651 0.44958) (xy 0.17272 0.44196)
						(xy 0.19812 0.4064) (xy 0.2032 0.39624) (xy 0.20701 0.38735) (xy 0.21209 0.37719) (xy 0.2159 0.36703)
						(xy 0.21844 0.35687) (xy 0.22225 0.34544) (xy 0.22352 0.33528) (xy 0.22606 0.32512) (xy 0.22733 0.31369)
						(xy 0.22733 0.30353) (xy 0.2286 0.2921) (xy 0.22733 0.28067) (xy 0.22733 0.27051) (xy 0.22606 0.25908)
						(xy 0.22352 0.24892) (xy 0.22225 0.23876) (xy 0.21844 0.22733) (xy 0.2159 0.21717) (xy 0.21209 0.20701)
						(xy 0.20701 0.19685) (xy 0.2032 0.18796) (xy 0.19812 0.1778) (xy 0.17272 0.14224) (xy 0.1651 0.13462)
						(xy 0.1651 -0.7366) (xy 0.16256 -0.76835) (xy 0.1524 -0.8001) (xy 0.13716 -0.82804) (xy 0.11684 -0.85344)
						(xy 0.09144 -0.87376) (xy 0.0635 -0.889) (xy 0.03175 -0.89916)
					)
					(width 0)
					(fill yes)
				)
			)
		)
		(pad "159" smd custom
			(at 18.150078 -4.100068)
			(size 0.1143 0.1143)
			(layers "B.Cu" "B.Mask" "B.Paste")
			(net "M_A_DQ42")
			(options
				(clearance outline)
				(anchor circle)
			)
			(primitives
				(gr_poly
					(pts
						(xy 0 -0.9017) (xy -0.03175 -0.89916) (xy -0.0635 -0.889) (xy -0.09144 -0.87376) (xy -0.11684 -0.85344)
						(xy -0.13716 -0.82804) (xy -0.1524 -0.8001) (xy -0.16256 -0.76835) (xy -0.1651 -0.7366) (xy -0.1651 -0.19685)
						(xy -0.17272 -0.18923) (xy -0.17907 -0.18034) (xy -0.18669 -0.17145) (xy -0.19177 -0.16256) (xy -0.19812 -0.15367)
						(xy -0.20828 -0.13335) (xy -0.21971 -0.10287) (xy -0.22225 -0.09271) (xy -0.22479 -0.08128) (xy -0.22606 -0.07112)
						(xy -0.2286 -0.05969) (xy -0.2286 -0.01651) (xy -0.22606 -0.00508) (xy -0.22479 0.00508) (xy -0.22225 0.01651)
						(xy -0.21971 0.02667) (xy -0.20828 0.05715) (xy -0.19812 0.07747) (xy -0.19177 0.08636) (xy -0.18669 0.09525)
						(xy -0.17907 0.10414) (xy -0.17272 0.11303) (xy -0.1651 0.12065) (xy -0.1651 0.7366) (xy -0.16256 0.76835)
						(xy -0.1524 0.8001) (xy -0.13716 0.82804) (xy -0.11684 0.85344) (xy -0.09144 0.87376) (xy -0.0635 0.889)
						(xy -0.03175 0.89916) (xy 0 0.9017) (xy 0.03175 0.89916) (xy 0.0635 0.889) (xy 0.09144 0.87376)
						(xy 0.11684 0.85344) (xy 0.13716 0.82804) (xy 0.1524 0.8001) (xy 0.16256 0.76835) (xy 0.1651 0.7366)
						(xy 0.1651 0.11938) (xy 0.17272 0.11176) (xy 0.19812 0.0762) (xy 0.2032 0.06604) (xy 0.20701 0.05715)
						(xy 0.21209 0.04699) (xy 0.2159 0.03683) (xy 0.21844 0.02667) (xy 0.22225 0.01524) (xy 0.22352 0.00508)
						(xy 0.22606 -0.00508) (xy 0.22733 -0.01651) (xy 0.22733 -0.02667) (xy 0.2286 -0.0381) (xy 0.22733 -0.04953)
						(xy 0.22733 -0.05969) (xy 0.22606 -0.07112) (xy 0.22352 -0.08128) (xy 0.22225 -0.09144) (xy 0.21844 -0.10287)
						(xy 0.2159 -0.11303) (xy 0.21209 -0.12319) (xy 0.20701 -0.13335) (xy 0.2032 -0.14224) (xy 0.19812 -0.1524)
						(xy 0.17272 -0.18796) (xy 0.1651 -0.19558) (xy 0.1651 -0.7366) (xy 0.16256 -0.76835) (xy 0.1524 -0.8001)
						(xy 0.13716 -0.82804) (xy 0.11684 -0.85344) (xy 0.09144 -0.87376) (xy 0.0635 -0.889) (xy 0.03175 -0.89916)
					)
					(width 0)
					(fill yes)
				)
			)
		)
		(pad "160" smd custom
			(at 18.450052 4.100068)
			(size 0.1143 0.1143)
			(layers "B.Cu" "B.Mask" "B.Paste")
			(net "M_A_DQ46")
			(options
				(clearance outline)
				(anchor circle)
			)
			(primitives
				(gr_poly
					(pts
						(xy 0 -0.9017) (xy -0.03175 -0.89916) (xy -0.0635 -0.889) (xy -0.09144 -0.87376) (xy -0.11684 -0.85344)
						(xy -0.13716 -0.82804) (xy -0.1524 -0.8001) (xy -0.16256 -0.76835) (xy -0.1651 -0.7366) (xy -0.1651 -0.11938)
						(xy -0.17272 -0.11176) (xy -0.19812 -0.0762) (xy -0.2032 -0.06604) (xy -0.20701 -0.05715) (xy -0.21209 -0.04699)
						(xy -0.2159 -0.03683) (xy -0.21844 -0.02667) (xy -0.22225 -0.01524) (xy -0.22352 -0.00508) (xy -0.22606 0.00508)
						(xy -0.22733 0.01651) (xy -0.22733 0.02667) (xy -0.2286 0.0381) (xy -0.22733 0.04953) (xy -0.22733 0.05969)
						(xy -0.22606 0.07112) (xy -0.22352 0.08128) (xy -0.22225 0.09144) (xy -0.21844 0.10287) (xy -0.2159 0.11303)
						(xy -0.21209 0.12319) (xy -0.20701 0.13335) (xy -0.2032 0.14224) (xy -0.19812 0.1524) (xy -0.17272 0.18796)
						(xy -0.1651 0.19558) (xy -0.1651 0.7366) (xy -0.16256 0.76835) (xy -0.1524 0.8001) (xy -0.13716 0.82804)
						(xy -0.11684 0.85344) (xy -0.09144 0.87376) (xy -0.0635 0.889) (xy -0.03175 0.89916) (xy 0 0.9017)
						(xy 0.03175 0.89916) (xy 0.0635 0.889) (xy 0.09144 0.87376) (xy 0.11684 0.85344) (xy 0.13716 0.82804)
						(xy 0.1524 0.8001) (xy 0.16256 0.76835) (xy 0.1651 0.7366) (xy 0.1651 0.19685) (xy 0.17272 0.18923)
						(xy 0.17907 0.18034) (xy 0.18669 0.17145) (xy 0.19177 0.16256) (xy 0.19812 0.15367) (xy 0.20828 0.13335)
						(xy 0.21971 0.10287) (xy 0.22225 0.09271) (xy 0.22479 0.08128) (xy 0.22606 0.07112) (xy 0.2286 0.05969)
						(xy 0.2286 0.01651) (xy 0.22606 0.00508) (xy 0.22479 -0.00508) (xy 0.22225 -0.01651) (xy 0.21971 -0.02667)
						(xy 0.20828 -0.05715) (xy 0.19812 -0.07747) (xy 0.19177 -0.08636) (xy 0.18669 -0.09525) (xy 0.17907 -0.10414)
						(xy 0.17272 -0.11303) (xy 0.1651 -0.12065) (xy 0.1651 -0.7366) (xy 0.16256 -0.76835) (xy 0.1524 -0.8001)
						(xy 0.13716 -0.82804) (xy 0.11684 -0.85344) (xy 0.09144 -0.87376) (xy 0.0635 -0.889) (xy 0.03175 -0.89916)
					)
					(width 0)
					(fill yes)
				)
			)
		)
		(pad "161" smd custom
			(at 18.750026 -4.100068)
			(size 0.1143 0.1143)
			(layers "B.Cu" "B.Mask" "B.Paste")
			(net "M_A_DQ43")
			(options
				(clearance outline)
				(anchor circle)
			)
			(primitives
				(gr_poly
					(pts
						(xy 0 -0.9017) (xy -0.03175 -0.89916) (xy -0.0635 -0.889) (xy -0.09144 -0.87376) (xy -0.11684 -0.85344)
						(xy -0.13716 -0.82804) (xy -0.1524 -0.8001) (xy -0.16256 -0.76835) (xy -0.1651 -0.7366) (xy -0.1651 -0.44958)
						(xy -0.17272 -0.44196) (xy -0.19812 -0.4064) (xy -0.2032 -0.39624) (xy -0.20701 -0.38735) (xy -0.21209 -0.37719)
						(xy -0.2159 -0.36703) (xy -0.21844 -0.35687) (xy -0.22225 -0.34544) (xy -0.22352 -0.33528) (xy -0.22606 -0.32512)
						(xy -0.22733 -0.31369) (xy -0.22733 -0.30353) (xy -0.2286 -0.2921) (xy -0.22733 -0.28067) (xy -0.22733 -0.27051)
						(xy -0.22606 -0.25908) (xy -0.22352 -0.24892) (xy -0.22225 -0.23876) (xy -0.21844 -0.22733) (xy -0.2159 -0.21717)
						(xy -0.21209 -0.20701) (xy -0.20701 -0.19685) (xy -0.2032 -0.18796) (xy -0.19812 -0.1778) (xy -0.17272 -0.14224)
						(xy -0.1651 -0.13462) (xy -0.1651 0.7366) (xy -0.16256 0.76835) (xy -0.1524 0.8001) (xy -0.13716 0.82804)
						(xy -0.11684 0.85344) (xy -0.09144 0.87376) (xy -0.0635 0.889) (xy -0.03175 0.89916) (xy 0 0.9017)
						(xy 0.03175 0.89916) (xy 0.0635 0.889) (xy 0.09144 0.87376) (xy 0.11684 0.85344) (xy 0.13716 0.82804)
						(xy 0.1524 0.8001) (xy 0.16256 0.76835) (xy 0.1651 0.7366) (xy 0.1651 -0.13462) (xy 0.17272 -0.14224)
						(xy 0.19812 -0.1778) (xy 0.2032 -0.18796) (xy 0.20701 -0.19685) (xy 0.21209 -0.20701) (xy 0.2159 -0.21717)
						(xy 0.21844 -0.22733) (xy 0.22225 -0.23876) (xy 0.22352 -0.24892) (xy 0.22606 -0.25908) (xy 0.22733 -0.27051)
						(xy 0.22733 -0.28067) (xy 0.2286 -0.2921) (xy 0.22733 -0.30353) (xy 0.22733 -0.31369) (xy 0.22606 -0.32512)
						(xy 0.22352 -0.33528) (xy 0.22225 -0.34544) (xy 0.21844 -0.35687) (xy 0.2159 -0.36703) (xy 0.21209 -0.37719)
						(xy 0.20701 -0.38735) (xy 0.2032 -0.39624) (xy 0.19812 -0.4064) (xy 0.17272 -0.44196) (xy 0.1651 -0.44958)
						(xy 0.1651 -0.7366) (xy 0.16256 -0.76835) (xy 0.1524 -0.8001) (xy 0.13716 -0.82804) (xy 0.11684 -0.85344)
						(xy 0.09144 -0.87376) (xy 0.0635 -0.889) (xy 0.03175 -0.89916)
					)
					(width 0)
					(fill yes)
				)
			)
		)
		(pad "162" smd custom
			(at 19.05 4.100068)
			(size 0.1143 0.1143)
			(layers "B.Cu" "B.Mask" "B.Paste")
			(net "M_A_DQ47")
			(options
				(clearance outline)
				(anchor circle)
			)
			(primitives
				(gr_poly
					(pts
						(xy 0 -0.9017) (xy -0.03175 -0.89916) (xy -0.0635 -0.889) (xy -0.09144 -0.87376) (xy -0.11684 -0.85344)
						(xy -0.13716 -0.82804) (xy -0.1524 -0.8001) (xy -0.16256 -0.76835) (xy -0.1651 -0.7366) (xy -0.1651 0.13462)
						(xy -0.17272 0.14224) (xy -0.19812 0.1778) (xy -0.2032 0.18796) (xy -0.20701 0.19685) (xy -0.21209 0.20701)
						(xy -0.2159 0.21717) (xy -0.21844 0.22733) (xy -0.22225 0.23876) (xy -0.22352 0.24892) (xy -0.22606 0.25908)
						(xy -0.22733 0.27051) (xy -0.22733 0.28067) (xy -0.2286 0.2921) (xy -0.22733 0.30353) (xy -0.22733 0.31369)
						(xy -0.22606 0.32512) (xy -0.22352 0.33528) (xy -0.22225 0.34544) (xy -0.21844 0.35687) (xy -0.2159 0.36703)
						(xy -0.21209 0.37719) (xy -0.20701 0.38735) (xy -0.2032 0.39624) (xy -0.19812 0.4064) (xy -0.17272 0.44196)
						(xy -0.1651 0.44958) (xy -0.1651 0.7366) (xy -0.16256 0.76835) (xy -0.1524 0.8001) (xy -0.13716 0.82804)
						(xy -0.11684 0.85344) (xy -0.09144 0.87376) (xy -0.0635 0.889) (xy -0.03175 0.89916) (xy 0 0.9017)
						(xy 0.03175 0.89916) (xy 0.0635 0.889) (xy 0.09144 0.87376) (xy 0.11684 0.85344) (xy 0.13716 0.82804)
						(xy 0.1524 0.8001) (xy 0.16256 0.76835) (xy 0.1651 0.7366) (xy 0.1651 0.44958) (xy 0.17272 0.44196)
						(xy 0.19812 0.4064) (xy 0.2032 0.39624) (xy 0.20701 0.38735) (xy 0.21209 0.37719) (xy 0.2159 0.36703)
						(xy 0.21844 0.35687) (xy 0.22225 0.34544) (xy 0.22352 0.33528) (xy 0.22606 0.32512) (xy 0.22733 0.31369)
						(xy 0.22733 0.30353) (xy 0.2286 0.2921) (xy 0.22733 0.28067) (xy 0.22733 0.27051) (xy 0.22606 0.25908)
						(xy 0.22352 0.24892) (xy 0.22225 0.23876) (xy 0.21844 0.22733) (xy 0.2159 0.21717) (xy 0.21209 0.20701)
						(xy 0.20701 0.19685) (xy 0.2032 0.18796) (xy 0.19812 0.1778) (xy 0.17272 0.14224) (xy 0.1651 0.13462)
						(xy 0.1651 -0.7366) (xy 0.16256 -0.76835) (xy 0.1524 -0.8001) (xy 0.13716 -0.82804) (xy 0.11684 -0.85344)
						(xy 0.09144 -0.87376) (xy 0.0635 -0.889) (xy 0.03175 -0.89916)
					)
					(width 0)
					(fill yes)
				)
			)
		)
		(pad "163" smd custom
			(at 19.349974 -4.100068)
			(size 0.1143 0.1143)
			(layers "B.Cu" "B.Mask" "B.Paste")
			(net "GND")
			(options
				(clearance outline)
				(anchor circle)
			)
			(primitives
				(gr_poly
					(pts
						(xy 0 -0.9017) (xy -0.03175 -0.89916) (xy -0.0635 -0.889) (xy -0.09144 -0.87376) (xy -0.11684 -0.85344)
						(xy -0.13716 -0.82804) (xy -0.1524 -0.8001) (xy -0.16256 -0.76835) (xy -0.1651 -0.7366) (xy -0.1651 -0.19685)
						(xy -0.17272 -0.18923) (xy -0.17907 -0.18034) (xy -0.18669 -0.17145) (xy -0.19177 -0.16256) (xy -0.19812 -0.15367)
						(xy -0.20828 -0.13335) (xy -0.21971 -0.10287) (xy -0.22225 -0.09271) (xy -0.22479 -0.08128) (xy -0.22606 -0.07112)
						(xy -0.2286 -0.05969) (xy -0.2286 -0.01651) (xy -0.22606 -0.00508) (xy -0.22479 0.00508) (xy -0.22225 0.01651)
						(xy -0.21971 0.02667) (xy -0.20828 0.05715) (xy -0.19812 0.07747) (xy -0.19177 0.08636) (xy -0.18669 0.09525)
						(xy -0.17907 0.10414) (xy -0.17272 0.11303) (xy -0.1651 0.12065) (xy -0.1651 0.7366) (xy -0.16256 0.76835)
						(xy -0.1524 0.8001) (xy -0.13716 0.82804) (xy -0.11684 0.85344) (xy -0.09144 0.87376) (xy -0.0635 0.889)
						(xy -0.03175 0.89916) (xy 0 0.9017) (xy 0.03175 0.89916) (xy 0.0635 0.889) (xy 0.09144 0.87376)
						(xy 0.11684 0.85344) (xy 0.13716 0.82804) (xy 0.1524 0.8001) (xy 0.16256 0.76835) (xy 0.1651 0.7366)
						(xy 0.1651 0.11938) (xy 0.17272 0.11176) (xy 0.19812 0.0762) (xy 0.2032 0.06604) (xy 0.20701 0.05715)
						(xy 0.21209 0.04699) (xy 0.2159 0.03683) (xy 0.21844 0.02667) (xy 0.22225 0.01524) (xy 0.22352 0.00508)
						(xy 0.22606 -0.00508) (xy 0.22733 -0.01651) (xy 0.22733 -0.02667) (xy 0.2286 -0.0381) (xy 0.22733 -0.04953)
						(xy 0.22733 -0.05969) (xy 0.22606 -0.07112) (xy 0.22352 -0.08128) (xy 0.22225 -0.09144) (xy 0.21844 -0.10287)
						(xy 0.2159 -0.11303) (xy 0.21209 -0.12319) (xy 0.20701 -0.13335) (xy 0.2032 -0.14224) (xy 0.19812 -0.1524)
						(xy 0.17272 -0.18796) (xy 0.1651 -0.19558) (xy 0.1651 -0.7366) (xy 0.16256 -0.76835) (xy 0.1524 -0.8001)
						(xy 0.13716 -0.82804) (xy 0.11684 -0.85344) (xy 0.09144 -0.87376) (xy 0.0635 -0.889) (xy 0.03175 -0.89916)
					)
					(width 0)
					(fill yes)
				)
			)
		)
		(pad "164" smd custom
			(at 19.649948 4.100068)
			(size 0.1143 0.1143)
			(layers "B.Cu" "B.Mask" "B.Paste")
			(net "GND")
			(options
				(clearance outline)
				(anchor circle)
			)
			(primitives
				(gr_poly
					(pts
						(xy 0 -0.9017) (xy -0.03175 -0.89916) (xy -0.0635 -0.889) (xy -0.09144 -0.87376) (xy -0.11684 -0.85344)
						(xy -0.13716 -0.82804) (xy -0.1524 -0.8001) (xy -0.16256 -0.76835) (xy -0.1651 -0.7366) (xy -0.1651 -0.11938)
						(xy -0.17272 -0.11176) (xy -0.19812 -0.0762) (xy -0.2032 -0.06604) (xy -0.20701 -0.05715) (xy -0.21209 -0.04699)
						(xy -0.2159 -0.03683) (xy -0.21844 -0.02667) (xy -0.22225 -0.01524) (xy -0.22352 -0.00508) (xy -0.22606 0.00508)
						(xy -0.22733 0.01651) (xy -0.22733 0.02667) (xy -0.2286 0.0381) (xy -0.22733 0.04953) (xy -0.22733 0.05969)
						(xy -0.22606 0.07112) (xy -0.22352 0.08128) (xy -0.22225 0.09144) (xy -0.21844 0.10287) (xy -0.2159 0.11303)
						(xy -0.21209 0.12319) (xy -0.20701 0.13335) (xy -0.2032 0.14224) (xy -0.19812 0.1524) (xy -0.17272 0.18796)
						(xy -0.1651 0.19558) (xy -0.1651 0.7366) (xy -0.16256 0.76835) (xy -0.1524 0.8001) (xy -0.13716 0.82804)
						(xy -0.11684 0.85344) (xy -0.09144 0.87376) (xy -0.0635 0.889) (xy -0.03175 0.89916) (xy 0 0.9017)
						(xy 0.03175 0.89916) (xy 0.0635 0.889) (xy 0.09144 0.87376) (xy 0.11684 0.85344) (xy 0.13716 0.82804)
						(xy 0.1524 0.8001) (xy 0.16256 0.76835) (xy 0.1651 0.7366) (xy 0.1651 0.19685) (xy 0.17272 0.18923)
						(xy 0.17907 0.18034) (xy 0.18669 0.17145) (xy 0.19177 0.16256) (xy 0.19812 0.15367) (xy 0.20828 0.13335)
						(xy 0.21971 0.10287) (xy 0.22225 0.09271) (xy 0.22479 0.08128) (xy 0.22606 0.07112) (xy 0.2286 0.05969)
						(xy 0.2286 0.01651) (xy 0.22606 0.00508) (xy 0.22479 -0.00508) (xy 0.22225 -0.01651) (xy 0.21971 -0.02667)
						(xy 0.20828 -0.05715) (xy 0.19812 -0.07747) (xy 0.19177 -0.08636) (xy 0.18669 -0.09525) (xy 0.17907 -0.10414)
						(xy 0.17272 -0.11303) (xy 0.1651 -0.12065) (xy 0.1651 -0.7366) (xy 0.16256 -0.76835) (xy 0.1524 -0.8001)
						(xy 0.13716 -0.82804) (xy 0.11684 -0.85344) (xy 0.09144 -0.87376) (xy 0.0635 -0.889) (xy 0.03175 -0.89916)
					)
					(width 0)
					(fill yes)
				)
			)
		)
		(pad "165" smd custom
			(at 19.949922 -4.100068)
			(size 0.1143 0.1143)
			(layers "B.Cu" "B.Mask" "B.Paste")
			(net "M_A_DQ48")
			(options
				(clearance outline)
				(anchor circle)
			)
			(primitives
				(gr_poly
					(pts
						(xy 0 -0.9017) (xy -0.03175 -0.89916) (xy -0.0635 -0.889) (xy -0.09144 -0.87376) (xy -0.11684 -0.85344)
						(xy -0.13716 -0.82804) (xy -0.1524 -0.8001) (xy -0.16256 -0.76835) (xy -0.1651 -0.7366) (xy -0.1651 -0.44958)
						(xy -0.17272 -0.44196) (xy -0.19812 -0.4064) (xy -0.2032 -0.39624) (xy -0.20701 -0.38735) (xy -0.21209 -0.37719)
						(xy -0.2159 -0.36703) (xy -0.21844 -0.35687) (xy -0.22225 -0.34544) (xy -0.22352 -0.33528) (xy -0.22606 -0.32512)
						(xy -0.22733 -0.31369) (xy -0.22733 -0.30353) (xy -0.2286 -0.2921) (xy -0.22733 -0.28067) (xy -0.22733 -0.27051)
						(xy -0.22606 -0.25908) (xy -0.22352 -0.24892) (xy -0.22225 -0.23876) (xy -0.21844 -0.22733) (xy -0.2159 -0.21717)
						(xy -0.21209 -0.20701) (xy -0.20701 -0.19685) (xy -0.2032 -0.18796) (xy -0.19812 -0.1778) (xy -0.17272 -0.14224)
						(xy -0.1651 -0.13462) (xy -0.1651 0.7366) (xy -0.16256 0.76835) (xy -0.1524 0.8001) (xy -0.13716 0.82804)
						(xy -0.11684 0.85344) (xy -0.09144 0.87376) (xy -0.0635 0.889) (xy -0.03175 0.89916) (xy 0 0.9017)
						(xy 0.03175 0.89916) (xy 0.0635 0.889) (xy 0.09144 0.87376) (xy 0.11684 0.85344) (xy 0.13716 0.82804)
						(xy 0.1524 0.8001) (xy 0.16256 0.76835) (xy 0.1651 0.7366) (xy 0.1651 -0.13462) (xy 0.17272 -0.14224)
						(xy 0.19812 -0.1778) (xy 0.2032 -0.18796) (xy 0.20701 -0.19685) (xy 0.21209 -0.20701) (xy 0.2159 -0.21717)
						(xy 0.21844 -0.22733) (xy 0.22225 -0.23876) (xy 0.22352 -0.24892) (xy 0.22606 -0.25908) (xy 0.22733 -0.27051)
						(xy 0.22733 -0.28067) (xy 0.2286 -0.2921) (xy 0.22733 -0.30353) (xy 0.22733 -0.31369) (xy 0.22606 -0.32512)
						(xy 0.22352 -0.33528) (xy 0.22225 -0.34544) (xy 0.21844 -0.35687) (xy 0.2159 -0.36703) (xy 0.21209 -0.37719)
						(xy 0.20701 -0.38735) (xy 0.2032 -0.39624) (xy 0.19812 -0.4064) (xy 0.17272 -0.44196) (xy 0.1651 -0.44958)
						(xy 0.1651 -0.7366) (xy 0.16256 -0.76835) (xy 0.1524 -0.8001) (xy 0.13716 -0.82804) (xy 0.11684 -0.85344)
						(xy 0.09144 -0.87376) (xy 0.0635 -0.889) (xy 0.03175 -0.89916)
					)
					(width 0)
					(fill yes)
				)
			)
		)
		(pad "166" smd custom
			(at 20.249896 4.100068)
			(size 0.1143 0.1143)
			(layers "B.Cu" "B.Mask" "B.Paste")
			(net "M_A_DQ52")
			(options
				(clearance outline)
				(anchor circle)
			)
			(primitives
				(gr_poly
					(pts
						(xy 0 -0.9017) (xy -0.03175 -0.89916) (xy -0.0635 -0.889) (xy -0.09144 -0.87376) (xy -0.11684 -0.85344)
						(xy -0.13716 -0.82804) (xy -0.1524 -0.8001) (xy -0.16256 -0.76835) (xy -0.1651 -0.7366) (xy -0.1651 0.13462)
						(xy -0.17272 0.14224) (xy -0.19812 0.1778) (xy -0.2032 0.18796) (xy -0.20701 0.19685) (xy -0.21209 0.20701)
						(xy -0.2159 0.21717) (xy -0.21844 0.22733) (xy -0.22225 0.23876) (xy -0.22352 0.24892) (xy -0.22606 0.25908)
						(xy -0.22733 0.27051) (xy -0.22733 0.28067) (xy -0.2286 0.2921) (xy -0.22733 0.30353) (xy -0.22733 0.31369)
						(xy -0.22606 0.32512) (xy -0.22352 0.33528) (xy -0.22225 0.34544) (xy -0.21844 0.35687) (xy -0.2159 0.36703)
						(xy -0.21209 0.37719) (xy -0.20701 0.38735) (xy -0.2032 0.39624) (xy -0.19812 0.4064) (xy -0.17272 0.44196)
						(xy -0.1651 0.44958) (xy -0.1651 0.7366) (xy -0.16256 0.76835) (xy -0.1524 0.8001) (xy -0.13716 0.82804)
						(xy -0.11684 0.85344) (xy -0.09144 0.87376) (xy -0.0635 0.889) (xy -0.03175 0.89916) (xy 0 0.9017)
						(xy 0.03175 0.89916) (xy 0.0635 0.889) (xy 0.09144 0.87376) (xy 0.11684 0.85344) (xy 0.13716 0.82804)
						(xy 0.1524 0.8001) (xy 0.16256 0.76835) (xy 0.1651 0.7366) (xy 0.1651 0.44958) (xy 0.17272 0.44196)
						(xy 0.19812 0.4064) (xy 0.2032 0.39624) (xy 0.20701 0.38735) (xy 0.21209 0.37719) (xy 0.2159 0.36703)
						(xy 0.21844 0.35687) (xy 0.22225 0.34544) (xy 0.22352 0.33528) (xy 0.22606 0.32512) (xy 0.22733 0.31369)
						(xy 0.22733 0.30353) (xy 0.2286 0.2921) (xy 0.22733 0.28067) (xy 0.22733 0.27051) (xy 0.22606 0.25908)
						(xy 0.22352 0.24892) (xy 0.22225 0.23876) (xy 0.21844 0.22733) (xy 0.2159 0.21717) (xy 0.21209 0.20701)
						(xy 0.20701 0.19685) (xy 0.2032 0.18796) (xy 0.19812 0.1778) (xy 0.17272 0.14224) (xy 0.1651 0.13462)
						(xy 0.1651 -0.7366) (xy 0.16256 -0.76835) (xy 0.1524 -0.8001) (xy 0.13716 -0.82804) (xy 0.11684 -0.85344)
						(xy 0.09144 -0.87376) (xy 0.0635 -0.889) (xy 0.03175 -0.89916)
					)
					(width 0)
					(fill yes)
				)
			)
		)
		(pad "167" smd custom
			(at 20.550124 -4.100068)
			(size 0.1143 0.1143)
			(layers "B.Cu" "B.Mask" "B.Paste")
			(net "M_A_DQ49")
			(options
				(clearance outline)
				(anchor circle)
			)
			(primitives
				(gr_poly
					(pts
						(xy 0 -0.9017) (xy -0.03175 -0.89916) (xy -0.0635 -0.889) (xy -0.09144 -0.87376) (xy -0.11684 -0.85344)
						(xy -0.13716 -0.82804) (xy -0.1524 -0.8001) (xy -0.16256 -0.76835) (xy -0.1651 -0.7366) (xy -0.1651 -0.19685)
						(xy -0.17272 -0.18923) (xy -0.17907 -0.18034) (xy -0.18669 -0.17145) (xy -0.19177 -0.16256) (xy -0.19812 -0.15367)
						(xy -0.20828 -0.13335) (xy -0.21971 -0.10287) (xy -0.22225 -0.09271) (xy -0.22479 -0.08128) (xy -0.22606 -0.07112)
						(xy -0.2286 -0.05969) (xy -0.2286 -0.01651) (xy -0.22606 -0.00508) (xy -0.22479 0.00508) (xy -0.22225 0.01651)
						(xy -0.21971 0.02667) (xy -0.20828 0.05715) (xy -0.19812 0.07747) (xy -0.19177 0.08636) (xy -0.18669 0.09525)
						(xy -0.17907 0.10414) (xy -0.17272 0.11303) (xy -0.1651 0.12065) (xy -0.1651 0.7366) (xy -0.16256 0.76835)
						(xy -0.1524 0.8001) (xy -0.13716 0.82804) (xy -0.11684 0.85344) (xy -0.09144 0.87376) (xy -0.0635 0.889)
						(xy -0.03175 0.89916) (xy 0 0.9017) (xy 0.03175 0.89916) (xy 0.0635 0.889) (xy 0.09144 0.87376)
						(xy 0.11684 0.85344) (xy 0.13716 0.82804) (xy 0.1524 0.8001) (xy 0.16256 0.76835) (xy 0.1651 0.7366)
						(xy 0.1651 0.11938) (xy 0.17272 0.11176) (xy 0.19812 0.0762) (xy 0.2032 0.06604) (xy 0.20701 0.05715)
						(xy 0.21209 0.04699) (xy 0.2159 0.03683) (xy 0.21844 0.02667) (xy 0.22225 0.01524) (xy 0.22352 0.00508)
						(xy 0.22606 -0.00508) (xy 0.22733 -0.01651) (xy 0.22733 -0.02667) (xy 0.2286 -0.0381) (xy 0.22733 -0.04953)
						(xy 0.22733 -0.05969) (xy 0.22606 -0.07112) (xy 0.22352 -0.08128) (xy 0.22225 -0.09144) (xy 0.21844 -0.10287)
						(xy 0.2159 -0.11303) (xy 0.21209 -0.12319) (xy 0.20701 -0.13335) (xy 0.2032 -0.14224) (xy 0.19812 -0.1524)
						(xy 0.17272 -0.18796) (xy 0.1651 -0.19558) (xy 0.1651 -0.7366) (xy 0.16256 -0.76835) (xy 0.1524 -0.8001)
						(xy 0.13716 -0.82804) (xy 0.11684 -0.85344) (xy 0.09144 -0.87376) (xy 0.0635 -0.889) (xy 0.03175 -0.89916)
					)
					(width 0)
					(fill yes)
				)
			)
		)
		(pad "168" smd custom
			(at 20.850098 4.100068)
			(size 0.1143 0.1143)
			(layers "B.Cu" "B.Mask" "B.Paste")
			(net "M_A_DQ53")
			(options
				(clearance outline)
				(anchor circle)
			)
			(primitives
				(gr_poly
					(pts
						(xy 0 -0.9017) (xy -0.03175 -0.89916) (xy -0.0635 -0.889) (xy -0.09144 -0.87376) (xy -0.11684 -0.85344)
						(xy -0.13716 -0.82804) (xy -0.1524 -0.8001) (xy -0.16256 -0.76835) (xy -0.1651 -0.7366) (xy -0.1651 -0.11938)
						(xy -0.17272 -0.11176) (xy -0.19812 -0.0762) (xy -0.2032 -0.06604) (xy -0.20701 -0.05715) (xy -0.21209 -0.04699)
						(xy -0.2159 -0.03683) (xy -0.21844 -0.02667) (xy -0.22225 -0.01524) (xy -0.22352 -0.00508) (xy -0.22606 0.00508)
						(xy -0.22733 0.01651) (xy -0.22733 0.02667) (xy -0.2286 0.0381) (xy -0.22733 0.04953) (xy -0.22733 0.05969)
						(xy -0.22606 0.07112) (xy -0.22352 0.08128) (xy -0.22225 0.09144) (xy -0.21844 0.10287) (xy -0.2159 0.11303)
						(xy -0.21209 0.12319) (xy -0.20701 0.13335) (xy -0.2032 0.14224) (xy -0.19812 0.1524) (xy -0.17272 0.18796)
						(xy -0.1651 0.19558) (xy -0.1651 0.7366) (xy -0.16256 0.76835) (xy -0.1524 0.8001) (xy -0.13716 0.82804)
						(xy -0.11684 0.85344) (xy -0.09144 0.87376) (xy -0.0635 0.889) (xy -0.03175 0.89916) (xy 0 0.9017)
						(xy 0.03175 0.89916) (xy 0.0635 0.889) (xy 0.09144 0.87376) (xy 0.11684 0.85344) (xy 0.13716 0.82804)
						(xy 0.1524 0.8001) (xy 0.16256 0.76835) (xy 0.1651 0.7366) (xy 0.1651 0.19685) (xy 0.17272 0.18923)
						(xy 0.17907 0.18034) (xy 0.18669 0.17145) (xy 0.19177 0.16256) (xy 0.19812 0.15367) (xy 0.20828 0.13335)
						(xy 0.21971 0.10287) (xy 0.22225 0.09271) (xy 0.22479 0.08128) (xy 0.22606 0.07112) (xy 0.2286 0.05969)
						(xy 0.2286 0.01651) (xy 0.22606 0.00508) (xy 0.22479 -0.00508) (xy 0.22225 -0.01651) (xy 0.21971 -0.02667)
						(xy 0.20828 -0.05715) (xy 0.19812 -0.07747) (xy 0.19177 -0.08636) (xy 0.18669 -0.09525) (xy 0.17907 -0.10414)
						(xy 0.17272 -0.11303) (xy 0.1651 -0.12065) (xy 0.1651 -0.7366) (xy 0.16256 -0.76835) (xy 0.1524 -0.8001)
						(xy 0.13716 -0.82804) (xy 0.11684 -0.85344) (xy 0.09144 -0.87376) (xy 0.0635 -0.889) (xy 0.03175 -0.89916)
					)
					(width 0)
					(fill yes)
				)
			)
		)
		(pad "169" smd custom
			(at 21.150072 -4.100068)
			(size 0.1143 0.1143)
			(layers "B.Cu" "B.Mask" "B.Paste")
			(net "GND")
			(options
				(clearance outline)
				(anchor circle)
			)
			(primitives
				(gr_poly
					(pts
						(xy 0 -0.9017) (xy -0.03175 -0.89916) (xy -0.0635 -0.889) (xy -0.09144 -0.87376) (xy -0.11684 -0.85344)
						(xy -0.13716 -0.82804) (xy -0.1524 -0.8001) (xy -0.16256 -0.76835) (xy -0.1651 -0.7366) (xy -0.1651 -0.44958)
						(xy -0.17272 -0.44196) (xy -0.19812 -0.4064) (xy -0.2032 -0.39624) (xy -0.20701 -0.38735) (xy -0.21209 -0.37719)
						(xy -0.2159 -0.36703) (xy -0.21844 -0.35687) (xy -0.22225 -0.34544) (xy -0.22352 -0.33528) (xy -0.22606 -0.32512)
						(xy -0.22733 -0.31369) (xy -0.22733 -0.30353) (xy -0.2286 -0.2921) (xy -0.22733 -0.28067) (xy -0.22733 -0.27051)
						(xy -0.22606 -0.25908) (xy -0.22352 -0.24892) (xy -0.22225 -0.23876) (xy -0.21844 -0.22733) (xy -0.2159 -0.21717)
						(xy -0.21209 -0.20701) (xy -0.20701 -0.19685) (xy -0.2032 -0.18796) (xy -0.19812 -0.1778) (xy -0.17272 -0.14224)
						(xy -0.1651 -0.13462) (xy -0.1651 0.7366) (xy -0.16256 0.76835) (xy -0.1524 0.8001) (xy -0.13716 0.82804)
						(xy -0.11684 0.85344) (xy -0.09144 0.87376) (xy -0.0635 0.889) (xy -0.03175 0.89916) (xy 0 0.9017)
						(xy 0.03175 0.89916) (xy 0.0635 0.889) (xy 0.09144 0.87376) (xy 0.11684 0.85344) (xy 0.13716 0.82804)
						(xy 0.1524 0.8001) (xy 0.16256 0.76835) (xy 0.1651 0.7366) (xy 0.1651 -0.13462) (xy 0.17272 -0.14224)
						(xy 0.19812 -0.1778) (xy 0.2032 -0.18796) (xy 0.20701 -0.19685) (xy 0.21209 -0.20701) (xy 0.2159 -0.21717)
						(xy 0.21844 -0.22733) (xy 0.22225 -0.23876) (xy 0.22352 -0.24892) (xy 0.22606 -0.25908) (xy 0.22733 -0.27051)
						(xy 0.22733 -0.28067) (xy 0.2286 -0.2921) (xy 0.22733 -0.30353) (xy 0.22733 -0.31369) (xy 0.22606 -0.32512)
						(xy 0.22352 -0.33528) (xy 0.22225 -0.34544) (xy 0.21844 -0.35687) (xy 0.2159 -0.36703) (xy 0.21209 -0.37719)
						(xy 0.20701 -0.38735) (xy 0.2032 -0.39624) (xy 0.19812 -0.4064) (xy 0.17272 -0.44196) (xy 0.1651 -0.44958)
						(xy 0.1651 -0.7366) (xy 0.16256 -0.76835) (xy 0.1524 -0.8001) (xy 0.13716 -0.82804) (xy 0.11684 -0.85344)
						(xy 0.09144 -0.87376) (xy 0.0635 -0.889) (xy 0.03175 -0.89916)
					)
					(width 0)
					(fill yes)
				)
			)
		)
		(pad "170" smd custom
			(at 21.450046 4.100068)
			(size 0.1143 0.1143)
			(layers "B.Cu" "B.Mask" "B.Paste")
			(net "GND")
			(options
				(clearance outline)
				(anchor circle)
			)
			(primitives
				(gr_poly
					(pts
						(xy 0 -0.9017) (xy -0.03175 -0.89916) (xy -0.0635 -0.889) (xy -0.09144 -0.87376) (xy -0.11684 -0.85344)
						(xy -0.13716 -0.82804) (xy -0.1524 -0.8001) (xy -0.16256 -0.76835) (xy -0.1651 -0.7366) (xy -0.1651 0.13462)
						(xy -0.17272 0.14224) (xy -0.19812 0.1778) (xy -0.2032 0.18796) (xy -0.20701 0.19685) (xy -0.21209 0.20701)
						(xy -0.2159 0.21717) (xy -0.21844 0.22733) (xy -0.22225 0.23876) (xy -0.22352 0.24892) (xy -0.22606 0.25908)
						(xy -0.22733 0.27051) (xy -0.22733 0.28067) (xy -0.2286 0.2921) (xy -0.22733 0.30353) (xy -0.22733 0.31369)
						(xy -0.22606 0.32512) (xy -0.22352 0.33528) (xy -0.22225 0.34544) (xy -0.21844 0.35687) (xy -0.2159 0.36703)
						(xy -0.21209 0.37719) (xy -0.20701 0.38735) (xy -0.2032 0.39624) (xy -0.19812 0.4064) (xy -0.17272 0.44196)
						(xy -0.1651 0.44958) (xy -0.1651 0.7366) (xy -0.16256 0.76835) (xy -0.1524 0.8001) (xy -0.13716 0.82804)
						(xy -0.11684 0.85344) (xy -0.09144 0.87376) (xy -0.0635 0.889) (xy -0.03175 0.89916) (xy 0 0.9017)
						(xy 0.03175 0.89916) (xy 0.0635 0.889) (xy 0.09144 0.87376) (xy 0.11684 0.85344) (xy 0.13716 0.82804)
						(xy 0.1524 0.8001) (xy 0.16256 0.76835) (xy 0.1651 0.7366) (xy 0.1651 0.44958) (xy 0.17272 0.44196)
						(xy 0.19812 0.4064) (xy 0.2032 0.39624) (xy 0.20701 0.38735) (xy 0.21209 0.37719) (xy 0.2159 0.36703)
						(xy 0.21844 0.35687) (xy 0.22225 0.34544) (xy 0.22352 0.33528) (xy 0.22606 0.32512) (xy 0.22733 0.31369)
						(xy 0.22733 0.30353) (xy 0.2286 0.2921) (xy 0.22733 0.28067) (xy 0.22733 0.27051) (xy 0.22606 0.25908)
						(xy 0.22352 0.24892) (xy 0.22225 0.23876) (xy 0.21844 0.22733) (xy 0.2159 0.21717) (xy 0.21209 0.20701)
						(xy 0.20701 0.19685) (xy 0.2032 0.18796) (xy 0.19812 0.1778) (xy 0.17272 0.14224) (xy 0.1651 0.13462)
						(xy 0.1651 -0.7366) (xy 0.16256 -0.76835) (xy 0.1524 -0.8001) (xy 0.13716 -0.82804) (xy 0.11684 -0.85344)
						(xy 0.09144 -0.87376) (xy 0.0635 -0.889) (xy 0.03175 -0.89916)
					)
					(width 0)
					(fill yes)
				)
			)
		)
		(pad "171" smd custom
			(at 21.75002 -4.100068)
			(size 0.1143 0.1143)
			(layers "B.Cu" "B.Mask" "B.Paste")
			(net "M_A_DQS_DN6")
			(options
				(clearance outline)
				(anchor circle)
			)
			(primitives
				(gr_poly
					(pts
						(xy 0 -0.9017) (xy -0.03175 -0.89916) (xy -0.0635 -0.889) (xy -0.09144 -0.87376) (xy -0.11684 -0.85344)
						(xy -0.13716 -0.82804) (xy -0.1524 -0.8001) (xy -0.16256 -0.76835) (xy -0.1651 -0.7366) (xy -0.1651 -0.19685)
						(xy -0.17272 -0.18923) (xy -0.17907 -0.18034) (xy -0.18669 -0.17145) (xy -0.19177 -0.16256) (xy -0.19812 -0.15367)
						(xy -0.20828 -0.13335) (xy -0.21971 -0.10287) (xy -0.22225 -0.09271) (xy -0.22479 -0.08128) (xy -0.22606 -0.07112)
						(xy -0.2286 -0.05969) (xy -0.2286 -0.01651) (xy -0.22606 -0.00508) (xy -0.22479 0.00508) (xy -0.22225 0.01651)
						(xy -0.21971 0.02667) (xy -0.20828 0.05715) (xy -0.19812 0.07747) (xy -0.19177 0.08636) (xy -0.18669 0.09525)
						(xy -0.17907 0.10414) (xy -0.17272 0.11303) (xy -0.1651 0.12065) (xy -0.1651 0.7366) (xy -0.16256 0.76835)
						(xy -0.1524 0.8001) (xy -0.13716 0.82804) (xy -0.11684 0.85344) (xy -0.09144 0.87376) (xy -0.0635 0.889)
						(xy -0.03175 0.89916) (xy 0 0.9017) (xy 0.03175 0.89916) (xy 0.0635 0.889) (xy 0.09144 0.87376)
						(xy 0.11684 0.85344) (xy 0.13716 0.82804) (xy 0.1524 0.8001) (xy 0.16256 0.76835) (xy 0.1651 0.7366)
						(xy 0.1651 0.11938) (xy 0.17272 0.11176) (xy 0.19812 0.0762) (xy 0.2032 0.06604) (xy 0.20701 0.05715)
						(xy 0.21209 0.04699) (xy 0.2159 0.03683) (xy 0.21844 0.02667) (xy 0.22225 0.01524) (xy 0.22352 0.00508)
						(xy 0.22606 -0.00508) (xy 0.22733 -0.01651) (xy 0.22733 -0.02667) (xy 0.2286 -0.0381) (xy 0.22733 -0.04953)
						(xy 0.22733 -0.05969) (xy 0.22606 -0.07112) (xy 0.22352 -0.08128) (xy 0.22225 -0.09144) (xy 0.21844 -0.10287)
						(xy 0.2159 -0.11303) (xy 0.21209 -0.12319) (xy 0.20701 -0.13335) (xy 0.2032 -0.14224) (xy 0.19812 -0.1524)
						(xy 0.17272 -0.18796) (xy 0.1651 -0.19558) (xy 0.1651 -0.7366) (xy 0.16256 -0.76835) (xy 0.1524 -0.8001)
						(xy 0.13716 -0.82804) (xy 0.11684 -0.85344) (xy 0.09144 -0.87376) (xy 0.0635 -0.889) (xy 0.03175 -0.89916)
					)
					(width 0)
					(fill yes)
				)
			)
		)
		(pad "172" smd custom
			(at 22.049994 4.100068)
			(size 0.1143 0.1143)
			(layers "B.Cu" "B.Mask" "B.Paste")
			(net "GND")
			(options
				(clearance outline)
				(anchor circle)
			)
			(primitives
				(gr_poly
					(pts
						(xy 0 -0.9017) (xy -0.03175 -0.89916) (xy -0.0635 -0.889) (xy -0.09144 -0.87376) (xy -0.11684 -0.85344)
						(xy -0.13716 -0.82804) (xy -0.1524 -0.8001) (xy -0.16256 -0.76835) (xy -0.1651 -0.7366) (xy -0.1651 -0.11938)
						(xy -0.17272 -0.11176) (xy -0.19812 -0.0762) (xy -0.2032 -0.06604) (xy -0.20701 -0.05715) (xy -0.21209 -0.04699)
						(xy -0.2159 -0.03683) (xy -0.21844 -0.02667) (xy -0.22225 -0.01524) (xy -0.22352 -0.00508) (xy -0.22606 0.00508)
						(xy -0.22733 0.01651) (xy -0.22733 0.02667) (xy -0.2286 0.0381) (xy -0.22733 0.04953) (xy -0.22733 0.05969)
						(xy -0.22606 0.07112) (xy -0.22352 0.08128) (xy -0.22225 0.09144) (xy -0.21844 0.10287) (xy -0.2159 0.11303)
						(xy -0.21209 0.12319) (xy -0.20701 0.13335) (xy -0.2032 0.14224) (xy -0.19812 0.1524) (xy -0.17272 0.18796)
						(xy -0.1651 0.19558) (xy -0.1651 0.7366) (xy -0.16256 0.76835) (xy -0.1524 0.8001) (xy -0.13716 0.82804)
						(xy -0.11684 0.85344) (xy -0.09144 0.87376) (xy -0.0635 0.889) (xy -0.03175 0.89916) (xy 0 0.9017)
						(xy 0.03175 0.89916) (xy 0.0635 0.889) (xy 0.09144 0.87376) (xy 0.11684 0.85344) (xy 0.13716 0.82804)
						(xy 0.1524 0.8001) (xy 0.16256 0.76835) (xy 0.1651 0.7366) (xy 0.1651 0.19685) (xy 0.17272 0.18923)
						(xy 0.17907 0.18034) (xy 0.18669 0.17145) (xy 0.19177 0.16256) (xy 0.19812 0.15367) (xy 0.20828 0.13335)
						(xy 0.21971 0.10287) (xy 0.22225 0.09271) (xy 0.22479 0.08128) (xy 0.22606 0.07112) (xy 0.2286 0.05969)
						(xy 0.2286 0.01651) (xy 0.22606 0.00508) (xy 0.22479 -0.00508) (xy 0.22225 -0.01651) (xy 0.21971 -0.02667)
						(xy 0.20828 -0.05715) (xy 0.19812 -0.07747) (xy 0.19177 -0.08636) (xy 0.18669 -0.09525) (xy 0.17907 -0.10414)
						(xy 0.17272 -0.11303) (xy 0.1651 -0.12065) (xy 0.1651 -0.7366) (xy 0.16256 -0.76835) (xy 0.1524 -0.8001)
						(xy 0.13716 -0.82804) (xy 0.11684 -0.85344) (xy 0.09144 -0.87376) (xy 0.0635 -0.889) (xy 0.03175 -0.89916)
					)
					(width 0)
					(fill yes)
				)
			)
		)
		(pad "173" smd custom
			(at 22.349968 -4.100068)
			(size 0.1143 0.1143)
			(layers "B.Cu" "B.Mask" "B.Paste")
			(net "M_A_DQS_DP6")
			(options
				(clearance outline)
				(anchor circle)
			)
			(primitives
				(gr_poly
					(pts
						(xy 0 -0.9017) (xy -0.03175 -0.89916) (xy -0.0635 -0.889) (xy -0.09144 -0.87376) (xy -0.11684 -0.85344)
						(xy -0.13716 -0.82804) (xy -0.1524 -0.8001) (xy -0.16256 -0.76835) (xy -0.1651 -0.7366) (xy -0.1651 -0.44958)
						(xy -0.17272 -0.44196) (xy -0.19812 -0.4064) (xy -0.2032 -0.39624) (xy -0.20701 -0.38735) (xy -0.21209 -0.37719)
						(xy -0.2159 -0.36703) (xy -0.21844 -0.35687) (xy -0.22225 -0.34544) (xy -0.22352 -0.33528) (xy -0.22606 -0.32512)
						(xy -0.22733 -0.31369) (xy -0.22733 -0.30353) (xy -0.2286 -0.2921) (xy -0.22733 -0.28067) (xy -0.22733 -0.27051)
						(xy -0.22606 -0.25908) (xy -0.22352 -0.24892) (xy -0.22225 -0.23876) (xy -0.21844 -0.22733) (xy -0.2159 -0.21717)
						(xy -0.21209 -0.20701) (xy -0.20701 -0.19685) (xy -0.2032 -0.18796) (xy -0.19812 -0.1778) (xy -0.17272 -0.14224)
						(xy -0.1651 -0.13462) (xy -0.1651 0.7366) (xy -0.16256 0.76835) (xy -0.1524 0.8001) (xy -0.13716 0.82804)
						(xy -0.11684 0.85344) (xy -0.09144 0.87376) (xy -0.0635 0.889) (xy -0.03175 0.89916) (xy 0 0.9017)
						(xy 0.03175 0.89916) (xy 0.0635 0.889) (xy 0.09144 0.87376) (xy 0.11684 0.85344) (xy 0.13716 0.82804)
						(xy 0.1524 0.8001) (xy 0.16256 0.76835) (xy 0.1651 0.7366) (xy 0.1651 -0.13462) (xy 0.17272 -0.14224)
						(xy 0.19812 -0.1778) (xy 0.2032 -0.18796) (xy 0.20701 -0.19685) (xy 0.21209 -0.20701) (xy 0.2159 -0.21717)
						(xy 0.21844 -0.22733) (xy 0.22225 -0.23876) (xy 0.22352 -0.24892) (xy 0.22606 -0.25908) (xy 0.22733 -0.27051)
						(xy 0.22733 -0.28067) (xy 0.2286 -0.2921) (xy 0.22733 -0.30353) (xy 0.22733 -0.31369) (xy 0.22606 -0.32512)
						(xy 0.22352 -0.33528) (xy 0.22225 -0.34544) (xy 0.21844 -0.35687) (xy 0.2159 -0.36703) (xy 0.21209 -0.37719)
						(xy 0.20701 -0.38735) (xy 0.2032 -0.39624) (xy 0.19812 -0.4064) (xy 0.17272 -0.44196) (xy 0.1651 -0.44958)
						(xy 0.1651 -0.7366) (xy 0.16256 -0.76835) (xy 0.1524 -0.8001) (xy 0.13716 -0.82804) (xy 0.11684 -0.85344)
						(xy 0.09144 -0.87376) (xy 0.0635 -0.889) (xy 0.03175 -0.89916)
					)
					(width 0)
					(fill yes)
				)
			)
		)
		(pad "174" smd custom
			(at 22.649942 4.100068)
			(size 0.1143 0.1143)
			(layers "B.Cu" "B.Mask" "B.Paste")
			(net "M_A_DQ54")
			(options
				(clearance outline)
				(anchor circle)
			)
			(primitives
				(gr_poly
					(pts
						(xy 0 -0.9017) (xy -0.03175 -0.89916) (xy -0.0635 -0.889) (xy -0.09144 -0.87376) (xy -0.11684 -0.85344)
						(xy -0.13716 -0.82804) (xy -0.1524 -0.8001) (xy -0.16256 -0.76835) (xy -0.1651 -0.7366) (xy -0.1651 0.13462)
						(xy -0.17272 0.14224) (xy -0.19812 0.1778) (xy -0.2032 0.18796) (xy -0.20701 0.19685) (xy -0.21209 0.20701)
						(xy -0.2159 0.21717) (xy -0.21844 0.22733) (xy -0.22225 0.23876) (xy -0.22352 0.24892) (xy -0.22606 0.25908)
						(xy -0.22733 0.27051) (xy -0.22733 0.28067) (xy -0.2286 0.2921) (xy -0.22733 0.30353) (xy -0.22733 0.31369)
						(xy -0.22606 0.32512) (xy -0.22352 0.33528) (xy -0.22225 0.34544) (xy -0.21844 0.35687) (xy -0.2159 0.36703)
						(xy -0.21209 0.37719) (xy -0.20701 0.38735) (xy -0.2032 0.39624) (xy -0.19812 0.4064) (xy -0.17272 0.44196)
						(xy -0.1651 0.44958) (xy -0.1651 0.7366) (xy -0.16256 0.76835) (xy -0.1524 0.8001) (xy -0.13716 0.82804)
						(xy -0.11684 0.85344) (xy -0.09144 0.87376) (xy -0.0635 0.889) (xy -0.03175 0.89916) (xy 0 0.9017)
						(xy 0.03175 0.89916) (xy 0.0635 0.889) (xy 0.09144 0.87376) (xy 0.11684 0.85344) (xy 0.13716 0.82804)
						(xy 0.1524 0.8001) (xy 0.16256 0.76835) (xy 0.1651 0.7366) (xy 0.1651 0.44958) (xy 0.17272 0.44196)
						(xy 0.19812 0.4064) (xy 0.2032 0.39624) (xy 0.20701 0.38735) (xy 0.21209 0.37719) (xy 0.2159 0.36703)
						(xy 0.21844 0.35687) (xy 0.22225 0.34544) (xy 0.22352 0.33528) (xy 0.22606 0.32512) (xy 0.22733 0.31369)
						(xy 0.22733 0.30353) (xy 0.2286 0.2921) (xy 0.22733 0.28067) (xy 0.22733 0.27051) (xy 0.22606 0.25908)
						(xy 0.22352 0.24892) (xy 0.22225 0.23876) (xy 0.21844 0.22733) (xy 0.2159 0.21717) (xy 0.21209 0.20701)
						(xy 0.20701 0.19685) (xy 0.2032 0.18796) (xy 0.19812 0.1778) (xy 0.17272 0.14224) (xy 0.1651 0.13462)
						(xy 0.1651 -0.7366) (xy 0.16256 -0.76835) (xy 0.1524 -0.8001) (xy 0.13716 -0.82804) (xy 0.11684 -0.85344)
						(xy 0.09144 -0.87376) (xy 0.0635 -0.889) (xy 0.03175 -0.89916)
					)
					(width 0)
					(fill yes)
				)
			)
		)
		(pad "175" smd custom
			(at 22.949916 -4.100068)
			(size 0.1143 0.1143)
			(layers "B.Cu" "B.Mask" "B.Paste")
			(net "GND")
			(options
				(clearance outline)
				(anchor circle)
			)
			(primitives
				(gr_poly
					(pts
						(xy 0 -0.9017) (xy -0.03175 -0.89916) (xy -0.0635 -0.889) (xy -0.09144 -0.87376) (xy -0.11684 -0.85344)
						(xy -0.13716 -0.82804) (xy -0.1524 -0.8001) (xy -0.16256 -0.76835) (xy -0.1651 -0.7366) (xy -0.1651 -0.19685)
						(xy -0.17272 -0.18923) (xy -0.17907 -0.18034) (xy -0.18669 -0.17145) (xy -0.19177 -0.16256) (xy -0.19812 -0.15367)
						(xy -0.20828 -0.13335) (xy -0.21971 -0.10287) (xy -0.22225 -0.09271) (xy -0.22479 -0.08128) (xy -0.22606 -0.07112)
						(xy -0.2286 -0.05969) (xy -0.2286 -0.01651) (xy -0.22606 -0.00508) (xy -0.22479 0.00508) (xy -0.22225 0.01651)
						(xy -0.21971 0.02667) (xy -0.20828 0.05715) (xy -0.19812 0.07747) (xy -0.19177 0.08636) (xy -0.18669 0.09525)
						(xy -0.17907 0.10414) (xy -0.17272 0.11303) (xy -0.1651 0.12065) (xy -0.1651 0.7366) (xy -0.16256 0.76835)
						(xy -0.1524 0.8001) (xy -0.13716 0.82804) (xy -0.11684 0.85344) (xy -0.09144 0.87376) (xy -0.0635 0.889)
						(xy -0.03175 0.89916) (xy 0 0.9017) (xy 0.03175 0.89916) (xy 0.0635 0.889) (xy 0.09144 0.87376)
						(xy 0.11684 0.85344) (xy 0.13716 0.82804) (xy 0.1524 0.8001) (xy 0.16256 0.76835) (xy 0.1651 0.7366)
						(xy 0.1651 0.11938) (xy 0.17272 0.11176) (xy 0.19812 0.0762) (xy 0.2032 0.06604) (xy 0.20701 0.05715)
						(xy 0.21209 0.04699) (xy 0.2159 0.03683) (xy 0.21844 0.02667) (xy 0.22225 0.01524) (xy 0.22352 0.00508)
						(xy 0.22606 -0.00508) (xy 0.22733 -0.01651) (xy 0.22733 -0.02667) (xy 0.2286 -0.0381) (xy 0.22733 -0.04953)
						(xy 0.22733 -0.05969) (xy 0.22606 -0.07112) (xy 0.22352 -0.08128) (xy 0.22225 -0.09144) (xy 0.21844 -0.10287)
						(xy 0.2159 -0.11303) (xy 0.21209 -0.12319) (xy 0.20701 -0.13335) (xy 0.2032 -0.14224) (xy 0.19812 -0.1524)
						(xy 0.17272 -0.18796) (xy 0.1651 -0.19558) (xy 0.1651 -0.7366) (xy 0.16256 -0.76835) (xy 0.1524 -0.8001)
						(xy 0.13716 -0.82804) (xy 0.11684 -0.85344) (xy 0.09144 -0.87376) (xy 0.0635 -0.889) (xy 0.03175 -0.89916)
					)
					(width 0)
					(fill yes)
				)
			)
		)
		(pad "176" smd custom
			(at 23.24989 4.100068)
			(size 0.1143 0.1143)
			(layers "B.Cu" "B.Mask" "B.Paste")
			(net "M_A_DQ55")
			(options
				(clearance outline)
				(anchor circle)
			)
			(primitives
				(gr_poly
					(pts
						(xy 0 -0.9017) (xy -0.03175 -0.89916) (xy -0.0635 -0.889) (xy -0.09144 -0.87376) (xy -0.11684 -0.85344)
						(xy -0.13716 -0.82804) (xy -0.1524 -0.8001) (xy -0.16256 -0.76835) (xy -0.1651 -0.7366) (xy -0.1651 -0.11938)
						(xy -0.17272 -0.11176) (xy -0.19812 -0.0762) (xy -0.2032 -0.06604) (xy -0.20701 -0.05715) (xy -0.21209 -0.04699)
						(xy -0.2159 -0.03683) (xy -0.21844 -0.02667) (xy -0.22225 -0.01524) (xy -0.22352 -0.00508) (xy -0.22606 0.00508)
						(xy -0.22733 0.01651) (xy -0.22733 0.02667) (xy -0.2286 0.0381) (xy -0.22733 0.04953) (xy -0.22733 0.05969)
						(xy -0.22606 0.07112) (xy -0.22352 0.08128) (xy -0.22225 0.09144) (xy -0.21844 0.10287) (xy -0.2159 0.11303)
						(xy -0.21209 0.12319) (xy -0.20701 0.13335) (xy -0.2032 0.14224) (xy -0.19812 0.1524) (xy -0.17272 0.18796)
						(xy -0.1651 0.19558) (xy -0.1651 0.7366) (xy -0.16256 0.76835) (xy -0.1524 0.8001) (xy -0.13716 0.82804)
						(xy -0.11684 0.85344) (xy -0.09144 0.87376) (xy -0.0635 0.889) (xy -0.03175 0.89916) (xy 0 0.9017)
						(xy 0.03175 0.89916) (xy 0.0635 0.889) (xy 0.09144 0.87376) (xy 0.11684 0.85344) (xy 0.13716 0.82804)
						(xy 0.1524 0.8001) (xy 0.16256 0.76835) (xy 0.1651 0.7366) (xy 0.1651 0.19685) (xy 0.17272 0.18923)
						(xy 0.17907 0.18034) (xy 0.18669 0.17145) (xy 0.19177 0.16256) (xy 0.19812 0.15367) (xy 0.20828 0.13335)
						(xy 0.21971 0.10287) (xy 0.22225 0.09271) (xy 0.22479 0.08128) (xy 0.22606 0.07112) (xy 0.2286 0.05969)
						(xy 0.2286 0.01651) (xy 0.22606 0.00508) (xy 0.22479 -0.00508) (xy 0.22225 -0.01651) (xy 0.21971 -0.02667)
						(xy 0.20828 -0.05715) (xy 0.19812 -0.07747) (xy 0.19177 -0.08636) (xy 0.18669 -0.09525) (xy 0.17907 -0.10414)
						(xy 0.17272 -0.11303) (xy 0.1651 -0.12065) (xy 0.1651 -0.7366) (xy 0.16256 -0.76835) (xy 0.1524 -0.8001)
						(xy 0.13716 -0.82804) (xy 0.11684 -0.85344) (xy 0.09144 -0.87376) (xy 0.0635 -0.889) (xy 0.03175 -0.89916)
					)
					(width 0)
					(fill yes)
				)
			)
		)
		(pad "177" smd custom
			(at 23.550118 -4.100068)
			(size 0.1143 0.1143)
			(layers "B.Cu" "B.Mask" "B.Paste")
			(net "M_A_DQ50")
			(options
				(clearance outline)
				(anchor circle)
			)
			(primitives
				(gr_poly
					(pts
						(xy 0 -0.9017) (xy -0.03175 -0.89916) (xy -0.0635 -0.889) (xy -0.09144 -0.87376) (xy -0.11684 -0.85344)
						(xy -0.13716 -0.82804) (xy -0.1524 -0.8001) (xy -0.16256 -0.76835) (xy -0.1651 -0.7366) (xy -0.1651 -0.44958)
						(xy -0.17272 -0.44196) (xy -0.19812 -0.4064) (xy -0.2032 -0.39624) (xy -0.20701 -0.38735) (xy -0.21209 -0.37719)
						(xy -0.2159 -0.36703) (xy -0.21844 -0.35687) (xy -0.22225 -0.34544) (xy -0.22352 -0.33528) (xy -0.22606 -0.32512)
						(xy -0.22733 -0.31369) (xy -0.22733 -0.30353) (xy -0.2286 -0.2921) (xy -0.22733 -0.28067) (xy -0.22733 -0.27051)
						(xy -0.22606 -0.25908) (xy -0.22352 -0.24892) (xy -0.22225 -0.23876) (xy -0.21844 -0.22733) (xy -0.2159 -0.21717)
						(xy -0.21209 -0.20701) (xy -0.20701 -0.19685) (xy -0.2032 -0.18796) (xy -0.19812 -0.1778) (xy -0.17272 -0.14224)
						(xy -0.1651 -0.13462) (xy -0.1651 0.7366) (xy -0.16256 0.76835) (xy -0.1524 0.8001) (xy -0.13716 0.82804)
						(xy -0.11684 0.85344) (xy -0.09144 0.87376) (xy -0.0635 0.889) (xy -0.03175 0.89916) (xy 0 0.9017)
						(xy 0.03175 0.89916) (xy 0.0635 0.889) (xy 0.09144 0.87376) (xy 0.11684 0.85344) (xy 0.13716 0.82804)
						(xy 0.1524 0.8001) (xy 0.16256 0.76835) (xy 0.1651 0.7366) (xy 0.1651 -0.13462) (xy 0.17272 -0.14224)
						(xy 0.19812 -0.1778) (xy 0.2032 -0.18796) (xy 0.20701 -0.19685) (xy 0.21209 -0.20701) (xy 0.2159 -0.21717)
						(xy 0.21844 -0.22733) (xy 0.22225 -0.23876) (xy 0.22352 -0.24892) (xy 0.22606 -0.25908) (xy 0.22733 -0.27051)
						(xy 0.22733 -0.28067) (xy 0.2286 -0.2921) (xy 0.22733 -0.30353) (xy 0.22733 -0.31369) (xy 0.22606 -0.32512)
						(xy 0.22352 -0.33528) (xy 0.22225 -0.34544) (xy 0.21844 -0.35687) (xy 0.2159 -0.36703) (xy 0.21209 -0.37719)
						(xy 0.20701 -0.38735) (xy 0.2032 -0.39624) (xy 0.19812 -0.4064) (xy 0.17272 -0.44196) (xy 0.1651 -0.44958)
						(xy 0.1651 -0.7366) (xy 0.16256 -0.76835) (xy 0.1524 -0.8001) (xy 0.13716 -0.82804) (xy 0.11684 -0.85344)
						(xy 0.09144 -0.87376) (xy 0.0635 -0.889) (xy 0.03175 -0.89916)
					)
					(width 0)
					(fill yes)
				)
			)
		)
		(pad "178" smd custom
			(at 23.850092 4.100068)
			(size 0.1143 0.1143)
			(layers "B.Cu" "B.Mask" "B.Paste")
			(net "GND")
			(options
				(clearance outline)
				(anchor circle)
			)
			(primitives
				(gr_poly
					(pts
						(xy 0 -0.9017) (xy -0.03175 -0.89916) (xy -0.0635 -0.889) (xy -0.09144 -0.87376) (xy -0.11684 -0.85344)
						(xy -0.13716 -0.82804) (xy -0.1524 -0.8001) (xy -0.16256 -0.76835) (xy -0.1651 -0.7366) (xy -0.1651 0.13462)
						(xy -0.17272 0.14224) (xy -0.19812 0.1778) (xy -0.2032 0.18796) (xy -0.20701 0.19685) (xy -0.21209 0.20701)
						(xy -0.2159 0.21717) (xy -0.21844 0.22733) (xy -0.22225 0.23876) (xy -0.22352 0.24892) (xy -0.22606 0.25908)
						(xy -0.22733 0.27051) (xy -0.22733 0.28067) (xy -0.2286 0.2921) (xy -0.22733 0.30353) (xy -0.22733 0.31369)
						(xy -0.22606 0.32512) (xy -0.22352 0.33528) (xy -0.22225 0.34544) (xy -0.21844 0.35687) (xy -0.2159 0.36703)
						(xy -0.21209 0.37719) (xy -0.20701 0.38735) (xy -0.2032 0.39624) (xy -0.19812 0.4064) (xy -0.17272 0.44196)
						(xy -0.1651 0.44958) (xy -0.1651 0.7366) (xy -0.16256 0.76835) (xy -0.1524 0.8001) (xy -0.13716 0.82804)
						(xy -0.11684 0.85344) (xy -0.09144 0.87376) (xy -0.0635 0.889) (xy -0.03175 0.89916) (xy 0 0.9017)
						(xy 0.03175 0.89916) (xy 0.0635 0.889) (xy 0.09144 0.87376) (xy 0.11684 0.85344) (xy 0.13716 0.82804)
						(xy 0.1524 0.8001) (xy 0.16256 0.76835) (xy 0.1651 0.7366) (xy 0.1651 0.44958) (xy 0.17272 0.44196)
						(xy 0.19812 0.4064) (xy 0.2032 0.39624) (xy 0.20701 0.38735) (xy 0.21209 0.37719) (xy 0.2159 0.36703)
						(xy 0.21844 0.35687) (xy 0.22225 0.34544) (xy 0.22352 0.33528) (xy 0.22606 0.32512) (xy 0.22733 0.31369)
						(xy 0.22733 0.30353) (xy 0.2286 0.2921) (xy 0.22733 0.28067) (xy 0.22733 0.27051) (xy 0.22606 0.25908)
						(xy 0.22352 0.24892) (xy 0.22225 0.23876) (xy 0.21844 0.22733) (xy 0.2159 0.21717) (xy 0.21209 0.20701)
						(xy 0.20701 0.19685) (xy 0.2032 0.18796) (xy 0.19812 0.1778) (xy 0.17272 0.14224) (xy 0.1651 0.13462)
						(xy 0.1651 -0.7366) (xy 0.16256 -0.76835) (xy 0.1524 -0.8001) (xy 0.13716 -0.82804) (xy 0.11684 -0.85344)
						(xy 0.09144 -0.87376) (xy 0.0635 -0.889) (xy 0.03175 -0.89916)
					)
					(width 0)
					(fill yes)
				)
			)
		)
		(pad "179" smd custom
			(at 24.150066 -4.100068)
			(size 0.1143 0.1143)
			(layers "B.Cu" "B.Mask" "B.Paste")
			(net "M_A_DQ51")
			(options
				(clearance outline)
				(anchor circle)
			)
			(primitives
				(gr_poly
					(pts
						(xy 0 -0.9017) (xy -0.03175 -0.89916) (xy -0.0635 -0.889) (xy -0.09144 -0.87376) (xy -0.11684 -0.85344)
						(xy -0.13716 -0.82804) (xy -0.1524 -0.8001) (xy -0.16256 -0.76835) (xy -0.1651 -0.7366) (xy -0.1651 -0.19685)
						(xy -0.17272 -0.18923) (xy -0.17907 -0.18034) (xy -0.18669 -0.17145) (xy -0.19177 -0.16256) (xy -0.19812 -0.15367)
						(xy -0.20828 -0.13335) (xy -0.21971 -0.10287) (xy -0.22225 -0.09271) (xy -0.22479 -0.08128) (xy -0.22606 -0.07112)
						(xy -0.2286 -0.05969) (xy -0.2286 -0.01651) (xy -0.22606 -0.00508) (xy -0.22479 0.00508) (xy -0.22225 0.01651)
						(xy -0.21971 0.02667) (xy -0.20828 0.05715) (xy -0.19812 0.07747) (xy -0.19177 0.08636) (xy -0.18669 0.09525)
						(xy -0.17907 0.10414) (xy -0.17272 0.11303) (xy -0.1651 0.12065) (xy -0.1651 0.7366) (xy -0.16256 0.76835)
						(xy -0.1524 0.8001) (xy -0.13716 0.82804) (xy -0.11684 0.85344) (xy -0.09144 0.87376) (xy -0.0635 0.889)
						(xy -0.03175 0.89916) (xy 0 0.9017) (xy 0.03175 0.89916) (xy 0.0635 0.889) (xy 0.09144 0.87376)
						(xy 0.11684 0.85344) (xy 0.13716 0.82804) (xy 0.1524 0.8001) (xy 0.16256 0.76835) (xy 0.1651 0.7366)
						(xy 0.1651 0.11938) (xy 0.17272 0.11176) (xy 0.19812 0.0762) (xy 0.2032 0.06604) (xy 0.20701 0.05715)
						(xy 0.21209 0.04699) (xy 0.2159 0.03683) (xy 0.21844 0.02667) (xy 0.22225 0.01524) (xy 0.22352 0.00508)
						(xy 0.22606 -0.00508) (xy 0.22733 -0.01651) (xy 0.22733 -0.02667) (xy 0.2286 -0.0381) (xy 0.22733 -0.04953)
						(xy 0.22733 -0.05969) (xy 0.22606 -0.07112) (xy 0.22352 -0.08128) (xy 0.22225 -0.09144) (xy 0.21844 -0.10287)
						(xy 0.2159 -0.11303) (xy 0.21209 -0.12319) (xy 0.20701 -0.13335) (xy 0.2032 -0.14224) (xy 0.19812 -0.1524)
						(xy 0.17272 -0.18796) (xy 0.1651 -0.19558) (xy 0.1651 -0.7366) (xy 0.16256 -0.76835) (xy 0.1524 -0.8001)
						(xy 0.13716 -0.82804) (xy 0.11684 -0.85344) (xy 0.09144 -0.87376) (xy 0.0635 -0.889) (xy 0.03175 -0.89916)
					)
					(width 0)
					(fill yes)
				)
			)
		)
		(pad "180" smd custom
			(at 24.45004 4.100068)
			(size 0.1143 0.1143)
			(layers "B.Cu" "B.Mask" "B.Paste")
			(net "M_A_DQ60")
			(options
				(clearance outline)
				(anchor circle)
			)
			(primitives
				(gr_poly
					(pts
						(xy 0 -0.9017) (xy -0.03175 -0.89916) (xy -0.0635 -0.889) (xy -0.09144 -0.87376) (xy -0.11684 -0.85344)
						(xy -0.13716 -0.82804) (xy -0.1524 -0.8001) (xy -0.16256 -0.76835) (xy -0.1651 -0.7366) (xy -0.1651 -0.11938)
						(xy -0.17272 -0.11176) (xy -0.19812 -0.0762) (xy -0.2032 -0.06604) (xy -0.20701 -0.05715) (xy -0.21209 -0.04699)
						(xy -0.2159 -0.03683) (xy -0.21844 -0.02667) (xy -0.22225 -0.01524) (xy -0.22352 -0.00508) (xy -0.22606 0.00508)
						(xy -0.22733 0.01651) (xy -0.22733 0.02667) (xy -0.2286 0.0381) (xy -0.22733 0.04953) (xy -0.22733 0.05969)
						(xy -0.22606 0.07112) (xy -0.22352 0.08128) (xy -0.22225 0.09144) (xy -0.21844 0.10287) (xy -0.2159 0.11303)
						(xy -0.21209 0.12319) (xy -0.20701 0.13335) (xy -0.2032 0.14224) (xy -0.19812 0.1524) (xy -0.17272 0.18796)
						(xy -0.1651 0.19558) (xy -0.1651 0.7366) (xy -0.16256 0.76835) (xy -0.1524 0.8001) (xy -0.13716 0.82804)
						(xy -0.11684 0.85344) (xy -0.09144 0.87376) (xy -0.0635 0.889) (xy -0.03175 0.89916) (xy 0 0.9017)
						(xy 0.03175 0.89916) (xy 0.0635 0.889) (xy 0.09144 0.87376) (xy 0.11684 0.85344) (xy 0.13716 0.82804)
						(xy 0.1524 0.8001) (xy 0.16256 0.76835) (xy 0.1651 0.7366) (xy 0.1651 0.19685) (xy 0.17272 0.18923)
						(xy 0.17907 0.18034) (xy 0.18669 0.17145) (xy 0.19177 0.16256) (xy 0.19812 0.15367) (xy 0.20828 0.13335)
						(xy 0.21971 0.10287) (xy 0.22225 0.09271) (xy 0.22479 0.08128) (xy 0.22606 0.07112) (xy 0.2286 0.05969)
						(xy 0.2286 0.01651) (xy 0.22606 0.00508) (xy 0.22479 -0.00508) (xy 0.22225 -0.01651) (xy 0.21971 -0.02667)
						(xy 0.20828 -0.05715) (xy 0.19812 -0.07747) (xy 0.19177 -0.08636) (xy 0.18669 -0.09525) (xy 0.17907 -0.10414)
						(xy 0.17272 -0.11303) (xy 0.1651 -0.12065) (xy 0.1651 -0.7366) (xy 0.16256 -0.76835) (xy 0.1524 -0.8001)
						(xy 0.13716 -0.82804) (xy 0.11684 -0.85344) (xy 0.09144 -0.87376) (xy 0.0635 -0.889) (xy 0.03175 -0.89916)
					)
					(width 0)
					(fill yes)
				)
			)
		)
		(pad "181" smd custom
			(at 24.750014 -4.100068)
			(size 0.1143 0.1143)
			(layers "B.Cu" "B.Mask" "B.Paste")
			(net "GND")
			(options
				(clearance outline)
				(anchor circle)
			)
			(primitives
				(gr_poly
					(pts
						(xy 0 -0.9017) (xy -0.03175 -0.89916) (xy -0.0635 -0.889) (xy -0.09144 -0.87376) (xy -0.11684 -0.85344)
						(xy -0.13716 -0.82804) (xy -0.1524 -0.8001) (xy -0.16256 -0.76835) (xy -0.1651 -0.7366) (xy -0.1651 -0.44958)
						(xy -0.17272 -0.44196) (xy -0.19812 -0.4064) (xy -0.2032 -0.39624) (xy -0.20701 -0.38735) (xy -0.21209 -0.37719)
						(xy -0.2159 -0.36703) (xy -0.21844 -0.35687) (xy -0.22225 -0.34544) (xy -0.22352 -0.33528) (xy -0.22606 -0.32512)
						(xy -0.22733 -0.31369) (xy -0.22733 -0.30353) (xy -0.2286 -0.2921) (xy -0.22733 -0.28067) (xy -0.22733 -0.27051)
						(xy -0.22606 -0.25908) (xy -0.22352 -0.24892) (xy -0.22225 -0.23876) (xy -0.21844 -0.22733) (xy -0.2159 -0.21717)
						(xy -0.21209 -0.20701) (xy -0.20701 -0.19685) (xy -0.2032 -0.18796) (xy -0.19812 -0.1778) (xy -0.17272 -0.14224)
						(xy -0.1651 -0.13462) (xy -0.1651 0.7366) (xy -0.16256 0.76835) (xy -0.1524 0.8001) (xy -0.13716 0.82804)
						(xy -0.11684 0.85344) (xy -0.09144 0.87376) (xy -0.0635 0.889) (xy -0.03175 0.89916) (xy 0 0.9017)
						(xy 0.03175 0.89916) (xy 0.0635 0.889) (xy 0.09144 0.87376) (xy 0.11684 0.85344) (xy 0.13716 0.82804)
						(xy 0.1524 0.8001) (xy 0.16256 0.76835) (xy 0.1651 0.7366) (xy 0.1651 -0.13462) (xy 0.17272 -0.14224)
						(xy 0.19812 -0.1778) (xy 0.2032 -0.18796) (xy 0.20701 -0.19685) (xy 0.21209 -0.20701) (xy 0.2159 -0.21717)
						(xy 0.21844 -0.22733) (xy 0.22225 -0.23876) (xy 0.22352 -0.24892) (xy 0.22606 -0.25908) (xy 0.22733 -0.27051)
						(xy 0.22733 -0.28067) (xy 0.2286 -0.2921) (xy 0.22733 -0.30353) (xy 0.22733 -0.31369) (xy 0.22606 -0.32512)
						(xy 0.22352 -0.33528) (xy 0.22225 -0.34544) (xy 0.21844 -0.35687) (xy 0.2159 -0.36703) (xy 0.21209 -0.37719)
						(xy 0.20701 -0.38735) (xy 0.2032 -0.39624) (xy 0.19812 -0.4064) (xy 0.17272 -0.44196) (xy 0.1651 -0.44958)
						(xy 0.1651 -0.7366) (xy 0.16256 -0.76835) (xy 0.1524 -0.8001) (xy 0.13716 -0.82804) (xy 0.11684 -0.85344)
						(xy 0.09144 -0.87376) (xy 0.0635 -0.889) (xy 0.03175 -0.89916)
					)
					(width 0)
					(fill yes)
				)
			)
		)
		(pad "182" smd custom
			(at 25.049988 4.100068)
			(size 0.1143 0.1143)
			(layers "B.Cu" "B.Mask" "B.Paste")
			(net "M_A_DQ61")
			(options
				(clearance outline)
				(anchor circle)
			)
			(primitives
				(gr_poly
					(pts
						(xy 0 -0.9017) (xy -0.03175 -0.89916) (xy -0.0635 -0.889) (xy -0.09144 -0.87376) (xy -0.11684 -0.85344)
						(xy -0.13716 -0.82804) (xy -0.1524 -0.8001) (xy -0.16256 -0.76835) (xy -0.1651 -0.7366) (xy -0.1651 0.13462)
						(xy -0.17272 0.14224) (xy -0.19812 0.1778) (xy -0.2032 0.18796) (xy -0.20701 0.19685) (xy -0.21209 0.20701)
						(xy -0.2159 0.21717) (xy -0.21844 0.22733) (xy -0.22225 0.23876) (xy -0.22352 0.24892) (xy -0.22606 0.25908)
						(xy -0.22733 0.27051) (xy -0.22733 0.28067) (xy -0.2286 0.2921) (xy -0.22733 0.30353) (xy -0.22733 0.31369)
						(xy -0.22606 0.32512) (xy -0.22352 0.33528) (xy -0.22225 0.34544) (xy -0.21844 0.35687) (xy -0.2159 0.36703)
						(xy -0.21209 0.37719) (xy -0.20701 0.38735) (xy -0.2032 0.39624) (xy -0.19812 0.4064) (xy -0.17272 0.44196)
						(xy -0.1651 0.44958) (xy -0.1651 0.7366) (xy -0.16256 0.76835) (xy -0.1524 0.8001) (xy -0.13716 0.82804)
						(xy -0.11684 0.85344) (xy -0.09144 0.87376) (xy -0.0635 0.889) (xy -0.03175 0.89916) (xy 0 0.9017)
						(xy 0.03175 0.89916) (xy 0.0635 0.889) (xy 0.09144 0.87376) (xy 0.11684 0.85344) (xy 0.13716 0.82804)
						(xy 0.1524 0.8001) (xy 0.16256 0.76835) (xy 0.1651 0.7366) (xy 0.1651 0.44958) (xy 0.17272 0.44196)
						(xy 0.19812 0.4064) (xy 0.2032 0.39624) (xy 0.20701 0.38735) (xy 0.21209 0.37719) (xy 0.2159 0.36703)
						(xy 0.21844 0.35687) (xy 0.22225 0.34544) (xy 0.22352 0.33528) (xy 0.22606 0.32512) (xy 0.22733 0.31369)
						(xy 0.22733 0.30353) (xy 0.2286 0.2921) (xy 0.22733 0.28067) (xy 0.22733 0.27051) (xy 0.22606 0.25908)
						(xy 0.22352 0.24892) (xy 0.22225 0.23876) (xy 0.21844 0.22733) (xy 0.2159 0.21717) (xy 0.21209 0.20701)
						(xy 0.20701 0.19685) (xy 0.2032 0.18796) (xy 0.19812 0.1778) (xy 0.17272 0.14224) (xy 0.1651 0.13462)
						(xy 0.1651 -0.7366) (xy 0.16256 -0.76835) (xy 0.1524 -0.8001) (xy 0.13716 -0.82804) (xy 0.11684 -0.85344)
						(xy 0.09144 -0.87376) (xy 0.0635 -0.889) (xy 0.03175 -0.89916)
					)
					(width 0)
					(fill yes)
				)
			)
		)
		(pad "183" smd custom
			(at 25.349962 -4.100068)
			(size 0.1143 0.1143)
			(layers "B.Cu" "B.Mask" "B.Paste")
			(net "M_A_DQ56")
			(options
				(clearance outline)
				(anchor circle)
			)
			(primitives
				(gr_poly
					(pts
						(xy 0 -0.9017) (xy -0.03175 -0.89916) (xy -0.0635 -0.889) (xy -0.09144 -0.87376) (xy -0.11684 -0.85344)
						(xy -0.13716 -0.82804) (xy -0.1524 -0.8001) (xy -0.16256 -0.76835) (xy -0.1651 -0.7366) (xy -0.1651 -0.19685)
						(xy -0.17272 -0.18923) (xy -0.17907 -0.18034) (xy -0.18669 -0.17145) (xy -0.19177 -0.16256) (xy -0.19812 -0.15367)
						(xy -0.20828 -0.13335) (xy -0.21971 -0.10287) (xy -0.22225 -0.09271) (xy -0.22479 -0.08128) (xy -0.22606 -0.07112)
						(xy -0.2286 -0.05969) (xy -0.2286 -0.01651) (xy -0.22606 -0.00508) (xy -0.22479 0.00508) (xy -0.22225 0.01651)
						(xy -0.21971 0.02667) (xy -0.20828 0.05715) (xy -0.19812 0.07747) (xy -0.19177 0.08636) (xy -0.18669 0.09525)
						(xy -0.17907 0.10414) (xy -0.17272 0.11303) (xy -0.1651 0.12065) (xy -0.1651 0.7366) (xy -0.16256 0.76835)
						(xy -0.1524 0.8001) (xy -0.13716 0.82804) (xy -0.11684 0.85344) (xy -0.09144 0.87376) (xy -0.0635 0.889)
						(xy -0.03175 0.89916) (xy 0 0.9017) (xy 0.03175 0.89916) (xy 0.0635 0.889) (xy 0.09144 0.87376)
						(xy 0.11684 0.85344) (xy 0.13716 0.82804) (xy 0.1524 0.8001) (xy 0.16256 0.76835) (xy 0.1651 0.7366)
						(xy 0.1651 0.11938) (xy 0.17272 0.11176) (xy 0.19812 0.0762) (xy 0.2032 0.06604) (xy 0.20701 0.05715)
						(xy 0.21209 0.04699) (xy 0.2159 0.03683) (xy 0.21844 0.02667) (xy 0.22225 0.01524) (xy 0.22352 0.00508)
						(xy 0.22606 -0.00508) (xy 0.22733 -0.01651) (xy 0.22733 -0.02667) (xy 0.2286 -0.0381) (xy 0.22733 -0.04953)
						(xy 0.22733 -0.05969) (xy 0.22606 -0.07112) (xy 0.22352 -0.08128) (xy 0.22225 -0.09144) (xy 0.21844 -0.10287)
						(xy 0.2159 -0.11303) (xy 0.21209 -0.12319) (xy 0.20701 -0.13335) (xy 0.2032 -0.14224) (xy 0.19812 -0.1524)
						(xy 0.17272 -0.18796) (xy 0.1651 -0.19558) (xy 0.1651 -0.7366) (xy 0.16256 -0.76835) (xy 0.1524 -0.8001)
						(xy 0.13716 -0.82804) (xy 0.11684 -0.85344) (xy 0.09144 -0.87376) (xy 0.0635 -0.889) (xy 0.03175 -0.89916)
					)
					(width 0)
					(fill yes)
				)
			)
		)
		(pad "184" smd custom
			(at 25.649936 4.100068)
			(size 0.1143 0.1143)
			(layers "B.Cu" "B.Mask" "B.Paste")
			(net "GND")
			(options
				(clearance outline)
				(anchor circle)
			)
			(primitives
				(gr_poly
					(pts
						(xy 0 -0.9017) (xy -0.03175 -0.89916) (xy -0.0635 -0.889) (xy -0.09144 -0.87376) (xy -0.11684 -0.85344)
						(xy -0.13716 -0.82804) (xy -0.1524 -0.8001) (xy -0.16256 -0.76835) (xy -0.1651 -0.7366) (xy -0.1651 -0.11938)
						(xy -0.17272 -0.11176) (xy -0.19812 -0.0762) (xy -0.2032 -0.06604) (xy -0.20701 -0.05715) (xy -0.21209 -0.04699)
						(xy -0.2159 -0.03683) (xy -0.21844 -0.02667) (xy -0.22225 -0.01524) (xy -0.22352 -0.00508) (xy -0.22606 0.00508)
						(xy -0.22733 0.01651) (xy -0.22733 0.02667) (xy -0.2286 0.0381) (xy -0.22733 0.04953) (xy -0.22733 0.05969)
						(xy -0.22606 0.07112) (xy -0.22352 0.08128) (xy -0.22225 0.09144) (xy -0.21844 0.10287) (xy -0.2159 0.11303)
						(xy -0.21209 0.12319) (xy -0.20701 0.13335) (xy -0.2032 0.14224) (xy -0.19812 0.1524) (xy -0.17272 0.18796)
						(xy -0.1651 0.19558) (xy -0.1651 0.7366) (xy -0.16256 0.76835) (xy -0.1524 0.8001) (xy -0.13716 0.82804)
						(xy -0.11684 0.85344) (xy -0.09144 0.87376) (xy -0.0635 0.889) (xy -0.03175 0.89916) (xy 0 0.9017)
						(xy 0.03175 0.89916) (xy 0.0635 0.889) (xy 0.09144 0.87376) (xy 0.11684 0.85344) (xy 0.13716 0.82804)
						(xy 0.1524 0.8001) (xy 0.16256 0.76835) (xy 0.1651 0.7366) (xy 0.1651 0.19685) (xy 0.17272 0.18923)
						(xy 0.17907 0.18034) (xy 0.18669 0.17145) (xy 0.19177 0.16256) (xy 0.19812 0.15367) (xy 0.20828 0.13335)
						(xy 0.21971 0.10287) (xy 0.22225 0.09271) (xy 0.22479 0.08128) (xy 0.22606 0.07112) (xy 0.2286 0.05969)
						(xy 0.2286 0.01651) (xy 0.22606 0.00508) (xy 0.22479 -0.00508) (xy 0.22225 -0.01651) (xy 0.21971 -0.02667)
						(xy 0.20828 -0.05715) (xy 0.19812 -0.07747) (xy 0.19177 -0.08636) (xy 0.18669 -0.09525) (xy 0.17907 -0.10414)
						(xy 0.17272 -0.11303) (xy 0.1651 -0.12065) (xy 0.1651 -0.7366) (xy 0.16256 -0.76835) (xy 0.1524 -0.8001)
						(xy 0.13716 -0.82804) (xy 0.11684 -0.85344) (xy 0.09144 -0.87376) (xy 0.0635 -0.889) (xy 0.03175 -0.89916)
					)
					(width 0)
					(fill yes)
				)
			)
		)
		(pad "185" smd custom
			(at 25.94991 -4.100068)
			(size 0.1143 0.1143)
			(layers "B.Cu" "B.Mask" "B.Paste")
			(net "M_A_DQ57")
			(options
				(clearance outline)
				(anchor circle)
			)
			(primitives
				(gr_poly
					(pts
						(xy 0 -0.9017) (xy -0.03175 -0.89916) (xy -0.0635 -0.889) (xy -0.09144 -0.87376) (xy -0.11684 -0.85344)
						(xy -0.13716 -0.82804) (xy -0.1524 -0.8001) (xy -0.16256 -0.76835) (xy -0.1651 -0.7366) (xy -0.1651 -0.44958)
						(xy -0.17272 -0.44196) (xy -0.19812 -0.4064) (xy -0.2032 -0.39624) (xy -0.20701 -0.38735) (xy -0.21209 -0.37719)
						(xy -0.2159 -0.36703) (xy -0.21844 -0.35687) (xy -0.22225 -0.34544) (xy -0.22352 -0.33528) (xy -0.22606 -0.32512)
						(xy -0.22733 -0.31369) (xy -0.22733 -0.30353) (xy -0.2286 -0.2921) (xy -0.22733 -0.28067) (xy -0.22733 -0.27051)
						(xy -0.22606 -0.25908) (xy -0.22352 -0.24892) (xy -0.22225 -0.23876) (xy -0.21844 -0.22733) (xy -0.2159 -0.21717)
						(xy -0.21209 -0.20701) (xy -0.20701 -0.19685) (xy -0.2032 -0.18796) (xy -0.19812 -0.1778) (xy -0.17272 -0.14224)
						(xy -0.1651 -0.13462) (xy -0.1651 0.7366) (xy -0.16256 0.76835) (xy -0.1524 0.8001) (xy -0.13716 0.82804)
						(xy -0.11684 0.85344) (xy -0.09144 0.87376) (xy -0.0635 0.889) (xy -0.03175 0.89916) (xy 0 0.9017)
						(xy 0.03175 0.89916) (xy 0.0635 0.889) (xy 0.09144 0.87376) (xy 0.11684 0.85344) (xy 0.13716 0.82804)
						(xy 0.1524 0.8001) (xy 0.16256 0.76835) (xy 0.1651 0.7366) (xy 0.1651 -0.13462) (xy 0.17272 -0.14224)
						(xy 0.19812 -0.1778) (xy 0.2032 -0.18796) (xy 0.20701 -0.19685) (xy 0.21209 -0.20701) (xy 0.2159 -0.21717)
						(xy 0.21844 -0.22733) (xy 0.22225 -0.23876) (xy 0.22352 -0.24892) (xy 0.22606 -0.25908) (xy 0.22733 -0.27051)
						(xy 0.22733 -0.28067) (xy 0.2286 -0.2921) (xy 0.22733 -0.30353) (xy 0.22733 -0.31369) (xy 0.22606 -0.32512)
						(xy 0.22352 -0.33528) (xy 0.22225 -0.34544) (xy 0.21844 -0.35687) (xy 0.2159 -0.36703) (xy 0.21209 -0.37719)
						(xy 0.20701 -0.38735) (xy 0.2032 -0.39624) (xy 0.19812 -0.4064) (xy 0.17272 -0.44196) (xy 0.1651 -0.44958)
						(xy 0.1651 -0.7366) (xy 0.16256 -0.76835) (xy 0.1524 -0.8001) (xy 0.13716 -0.82804) (xy 0.11684 -0.85344)
						(xy 0.09144 -0.87376) (xy 0.0635 -0.889) (xy 0.03175 -0.89916)
					)
					(width 0)
					(fill yes)
				)
			)
		)
		(pad "186" smd custom
			(at 26.249884 4.100068)
			(size 0.1143 0.1143)
			(layers "B.Cu" "B.Mask" "B.Paste")
			(net "M_A_DQS_DN7")
			(options
				(clearance outline)
				(anchor circle)
			)
			(primitives
				(gr_poly
					(pts
						(xy 0 -0.9017) (xy -0.03175 -0.89916) (xy -0.0635 -0.889) (xy -0.09144 -0.87376) (xy -0.11684 -0.85344)
						(xy -0.13716 -0.82804) (xy -0.1524 -0.8001) (xy -0.16256 -0.76835) (xy -0.1651 -0.7366) (xy -0.1651 0.13462)
						(xy -0.17272 0.14224) (xy -0.19812 0.1778) (xy -0.2032 0.18796) (xy -0.20701 0.19685) (xy -0.21209 0.20701)
						(xy -0.2159 0.21717) (xy -0.21844 0.22733) (xy -0.22225 0.23876) (xy -0.22352 0.24892) (xy -0.22606 0.25908)
						(xy -0.22733 0.27051) (xy -0.22733 0.28067) (xy -0.2286 0.2921) (xy -0.22733 0.30353) (xy -0.22733 0.31369)
						(xy -0.22606 0.32512) (xy -0.22352 0.33528) (xy -0.22225 0.34544) (xy -0.21844 0.35687) (xy -0.2159 0.36703)
						(xy -0.21209 0.37719) (xy -0.20701 0.38735) (xy -0.2032 0.39624) (xy -0.19812 0.4064) (xy -0.17272 0.44196)
						(xy -0.1651 0.44958) (xy -0.1651 0.7366) (xy -0.16256 0.76835) (xy -0.1524 0.8001) (xy -0.13716 0.82804)
						(xy -0.11684 0.85344) (xy -0.09144 0.87376) (xy -0.0635 0.889) (xy -0.03175 0.89916) (xy 0 0.9017)
						(xy 0.03175 0.89916) (xy 0.0635 0.889) (xy 0.09144 0.87376) (xy 0.11684 0.85344) (xy 0.13716 0.82804)
						(xy 0.1524 0.8001) (xy 0.16256 0.76835) (xy 0.1651 0.7366) (xy 0.1651 0.44958) (xy 0.17272 0.44196)
						(xy 0.19812 0.4064) (xy 0.2032 0.39624) (xy 0.20701 0.38735) (xy 0.21209 0.37719) (xy 0.2159 0.36703)
						(xy 0.21844 0.35687) (xy 0.22225 0.34544) (xy 0.22352 0.33528) (xy 0.22606 0.32512) (xy 0.22733 0.31369)
						(xy 0.22733 0.30353) (xy 0.2286 0.2921) (xy 0.22733 0.28067) (xy 0.22733 0.27051) (xy 0.22606 0.25908)
						(xy 0.22352 0.24892) (xy 0.22225 0.23876) (xy 0.21844 0.22733) (xy 0.2159 0.21717) (xy 0.21209 0.20701)
						(xy 0.20701 0.19685) (xy 0.2032 0.18796) (xy 0.19812 0.1778) (xy 0.17272 0.14224) (xy 0.1651 0.13462)
						(xy 0.1651 -0.7366) (xy 0.16256 -0.76835) (xy 0.1524 -0.8001) (xy 0.13716 -0.82804) (xy 0.11684 -0.85344)
						(xy 0.09144 -0.87376) (xy 0.0635 -0.889) (xy 0.03175 -0.89916)
					)
					(width 0)
					(fill yes)
				)
			)
		)
		(pad "187" smd custom
			(at 26.550112 -4.100068)
			(size 0.1143 0.1143)
			(layers "B.Cu" "B.Mask" "B.Paste")
			(net "GND")
			(options
				(clearance outline)
				(anchor circle)
			)
			(primitives
				(gr_poly
					(pts
						(xy 0 -0.9017) (xy -0.03175 -0.89916) (xy -0.0635 -0.889) (xy -0.09144 -0.87376) (xy -0.11684 -0.85344)
						(xy -0.13716 -0.82804) (xy -0.1524 -0.8001) (xy -0.16256 -0.76835) (xy -0.1651 -0.7366) (xy -0.1651 -0.19685)
						(xy -0.17272 -0.18923) (xy -0.17907 -0.18034) (xy -0.18669 -0.17145) (xy -0.19177 -0.16256) (xy -0.19812 -0.15367)
						(xy -0.20828 -0.13335) (xy -0.21971 -0.10287) (xy -0.22225 -0.09271) (xy -0.22479 -0.08128) (xy -0.22606 -0.07112)
						(xy -0.2286 -0.05969) (xy -0.2286 -0.01651) (xy -0.22606 -0.00508) (xy -0.22479 0.00508) (xy -0.22225 0.01651)
						(xy -0.21971 0.02667) (xy -0.20828 0.05715) (xy -0.19812 0.07747) (xy -0.19177 0.08636) (xy -0.18669 0.09525)
						(xy -0.17907 0.10414) (xy -0.17272 0.11303) (xy -0.1651 0.12065) (xy -0.1651 0.7366) (xy -0.16256 0.76835)
						(xy -0.1524 0.8001) (xy -0.13716 0.82804) (xy -0.11684 0.85344) (xy -0.09144 0.87376) (xy -0.0635 0.889)
						(xy -0.03175 0.89916) (xy 0 0.9017) (xy 0.03175 0.89916) (xy 0.0635 0.889) (xy 0.09144 0.87376)
						(xy 0.11684 0.85344) (xy 0.13716 0.82804) (xy 0.1524 0.8001) (xy 0.16256 0.76835) (xy 0.1651 0.7366)
						(xy 0.1651 0.11938) (xy 0.17272 0.11176) (xy 0.19812 0.0762) (xy 0.2032 0.06604) (xy 0.20701 0.05715)
						(xy 0.21209 0.04699) (xy 0.2159 0.03683) (xy 0.21844 0.02667) (xy 0.22225 0.01524) (xy 0.22352 0.00508)
						(xy 0.22606 -0.00508) (xy 0.22733 -0.01651) (xy 0.22733 -0.02667) (xy 0.2286 -0.0381) (xy 0.22733 -0.04953)
						(xy 0.22733 -0.05969) (xy 0.22606 -0.07112) (xy 0.22352 -0.08128) (xy 0.22225 -0.09144) (xy 0.21844 -0.10287)
						(xy 0.2159 -0.11303) (xy 0.21209 -0.12319) (xy 0.20701 -0.13335) (xy 0.2032 -0.14224) (xy 0.19812 -0.1524)
						(xy 0.17272 -0.18796) (xy 0.1651 -0.19558) (xy 0.1651 -0.7366) (xy 0.16256 -0.76835) (xy 0.1524 -0.8001)
						(xy 0.13716 -0.82804) (xy 0.11684 -0.85344) (xy 0.09144 -0.87376) (xy 0.0635 -0.889) (xy 0.03175 -0.89916)
					)
					(width 0)
					(fill yes)
				)
			)
		)
		(pad "188" smd custom
			(at 26.850086 4.100068)
			(size 0.1143 0.1143)
			(layers "B.Cu" "B.Mask" "B.Paste")
			(net "M_A_DQS_DP7")
			(options
				(clearance outline)
				(anchor circle)
			)
			(primitives
				(gr_poly
					(pts
						(xy 0 -0.9017) (xy -0.03175 -0.89916) (xy -0.0635 -0.889) (xy -0.09144 -0.87376) (xy -0.11684 -0.85344)
						(xy -0.13716 -0.82804) (xy -0.1524 -0.8001) (xy -0.16256 -0.76835) (xy -0.1651 -0.7366) (xy -0.1651 -0.11938)
						(xy -0.17272 -0.11176) (xy -0.19812 -0.0762) (xy -0.2032 -0.06604) (xy -0.20701 -0.05715) (xy -0.21209 -0.04699)
						(xy -0.2159 -0.03683) (xy -0.21844 -0.02667) (xy -0.22225 -0.01524) (xy -0.22352 -0.00508) (xy -0.22606 0.00508)
						(xy -0.22733 0.01651) (xy -0.22733 0.02667) (xy -0.2286 0.0381) (xy -0.22733 0.04953) (xy -0.22733 0.05969)
						(xy -0.22606 0.07112) (xy -0.22352 0.08128) (xy -0.22225 0.09144) (xy -0.21844 0.10287) (xy -0.2159 0.11303)
						(xy -0.21209 0.12319) (xy -0.20701 0.13335) (xy -0.2032 0.14224) (xy -0.19812 0.1524) (xy -0.17272 0.18796)
						(xy -0.1651 0.19558) (xy -0.1651 0.7366) (xy -0.16256 0.76835) (xy -0.1524 0.8001) (xy -0.13716 0.82804)
						(xy -0.11684 0.85344) (xy -0.09144 0.87376) (xy -0.0635 0.889) (xy -0.03175 0.89916) (xy 0 0.9017)
						(xy 0.03175 0.89916) (xy 0.0635 0.889) (xy 0.09144 0.87376) (xy 0.11684 0.85344) (xy 0.13716 0.82804)
						(xy 0.1524 0.8001) (xy 0.16256 0.76835) (xy 0.1651 0.7366) (xy 0.1651 0.19685) (xy 0.17272 0.18923)
						(xy 0.17907 0.18034) (xy 0.18669 0.17145) (xy 0.19177 0.16256) (xy 0.19812 0.15367) (xy 0.20828 0.13335)
						(xy 0.21971 0.10287) (xy 0.22225 0.09271) (xy 0.22479 0.08128) (xy 0.22606 0.07112) (xy 0.2286 0.05969)
						(xy 0.2286 0.01651) (xy 0.22606 0.00508) (xy 0.22479 -0.00508) (xy 0.22225 -0.01651) (xy 0.21971 -0.02667)
						(xy 0.20828 -0.05715) (xy 0.19812 -0.07747) (xy 0.19177 -0.08636) (xy 0.18669 -0.09525) (xy 0.17907 -0.10414)
						(xy 0.17272 -0.11303) (xy 0.1651 -0.12065) (xy 0.1651 -0.7366) (xy 0.16256 -0.76835) (xy 0.1524 -0.8001)
						(xy 0.13716 -0.82804) (xy 0.11684 -0.85344) (xy 0.09144 -0.87376) (xy 0.0635 -0.889) (xy 0.03175 -0.89916)
					)
					(width 0)
					(fill yes)
				)
			)
		)
		(pad "189" smd custom
			(at 27.15006 -4.100068)
			(size 0.1143 0.1143)
			(layers "B.Cu" "B.Mask" "B.Paste")
			(net "GND")
			(options
				(clearance outline)
				(anchor circle)
			)
			(primitives
				(gr_poly
					(pts
						(xy 0 -0.9017) (xy -0.03175 -0.89916) (xy -0.0635 -0.889) (xy -0.09144 -0.87376) (xy -0.11684 -0.85344)
						(xy -0.13716 -0.82804) (xy -0.1524 -0.8001) (xy -0.16256 -0.76835) (xy -0.1651 -0.7366) (xy -0.1651 -0.44958)
						(xy -0.17272 -0.44196) (xy -0.19812 -0.4064) (xy -0.2032 -0.39624) (xy -0.20701 -0.38735) (xy -0.21209 -0.37719)
						(xy -0.2159 -0.36703) (xy -0.21844 -0.35687) (xy -0.22225 -0.34544) (xy -0.22352 -0.33528) (xy -0.22606 -0.32512)
						(xy -0.22733 -0.31369) (xy -0.22733 -0.30353) (xy -0.2286 -0.2921) (xy -0.22733 -0.28067) (xy -0.22733 -0.27051)
						(xy -0.22606 -0.25908) (xy -0.22352 -0.24892) (xy -0.22225 -0.23876) (xy -0.21844 -0.22733) (xy -0.2159 -0.21717)
						(xy -0.21209 -0.20701) (xy -0.20701 -0.19685) (xy -0.2032 -0.18796) (xy -0.19812 -0.1778) (xy -0.17272 -0.14224)
						(xy -0.1651 -0.13462) (xy -0.1651 0.7366) (xy -0.16256 0.76835) (xy -0.1524 0.8001) (xy -0.13716 0.82804)
						(xy -0.11684 0.85344) (xy -0.09144 0.87376) (xy -0.0635 0.889) (xy -0.03175 0.89916) (xy 0 0.9017)
						(xy 0.03175 0.89916) (xy 0.0635 0.889) (xy 0.09144 0.87376) (xy 0.11684 0.85344) (xy 0.13716 0.82804)
						(xy 0.1524 0.8001) (xy 0.16256 0.76835) (xy 0.1651 0.7366) (xy 0.1651 -0.13462) (xy 0.17272 -0.14224)
						(xy 0.19812 -0.1778) (xy 0.2032 -0.18796) (xy 0.20701 -0.19685) (xy 0.21209 -0.20701) (xy 0.2159 -0.21717)
						(xy 0.21844 -0.22733) (xy 0.22225 -0.23876) (xy 0.22352 -0.24892) (xy 0.22606 -0.25908) (xy 0.22733 -0.27051)
						(xy 0.22733 -0.28067) (xy 0.2286 -0.2921) (xy 0.22733 -0.30353) (xy 0.22733 -0.31369) (xy 0.22606 -0.32512)
						(xy 0.22352 -0.33528) (xy 0.22225 -0.34544) (xy 0.21844 -0.35687) (xy 0.2159 -0.36703) (xy 0.21209 -0.37719)
						(xy 0.20701 -0.38735) (xy 0.2032 -0.39624) (xy 0.19812 -0.4064) (xy 0.17272 -0.44196) (xy 0.1651 -0.44958)
						(xy 0.1651 -0.7366) (xy 0.16256 -0.76835) (xy 0.1524 -0.8001) (xy 0.13716 -0.82804) (xy 0.11684 -0.85344)
						(xy 0.09144 -0.87376) (xy 0.0635 -0.889) (xy 0.03175 -0.89916)
					)
					(width 0)
					(fill yes)
				)
			)
		)
		(pad "190" smd custom
			(at 27.450034 4.100068)
			(size 0.1143 0.1143)
			(layers "B.Cu" "B.Mask" "B.Paste")
			(net "GND")
			(options
				(clearance outline)
				(anchor circle)
			)
			(primitives
				(gr_poly
					(pts
						(xy 0 -0.9017) (xy -0.03175 -0.89916) (xy -0.0635 -0.889) (xy -0.09144 -0.87376) (xy -0.11684 -0.85344)
						(xy -0.13716 -0.82804) (xy -0.1524 -0.8001) (xy -0.16256 -0.76835) (xy -0.1651 -0.7366) (xy -0.1651 0.13462)
						(xy -0.17272 0.14224) (xy -0.19812 0.1778) (xy -0.2032 0.18796) (xy -0.20701 0.19685) (xy -0.21209 0.20701)
						(xy -0.2159 0.21717) (xy -0.21844 0.22733) (xy -0.22225 0.23876) (xy -0.22352 0.24892) (xy -0.22606 0.25908)
						(xy -0.22733 0.27051) (xy -0.22733 0.28067) (xy -0.2286 0.2921) (xy -0.22733 0.30353) (xy -0.22733 0.31369)
						(xy -0.22606 0.32512) (xy -0.22352 0.33528) (xy -0.22225 0.34544) (xy -0.21844 0.35687) (xy -0.2159 0.36703)
						(xy -0.21209 0.37719) (xy -0.20701 0.38735) (xy -0.2032 0.39624) (xy -0.19812 0.4064) (xy -0.17272 0.44196)
						(xy -0.1651 0.44958) (xy -0.1651 0.7366) (xy -0.16256 0.76835) (xy -0.1524 0.8001) (xy -0.13716 0.82804)
						(xy -0.11684 0.85344) (xy -0.09144 0.87376) (xy -0.0635 0.889) (xy -0.03175 0.89916) (xy 0 0.9017)
						(xy 0.03175 0.89916) (xy 0.0635 0.889) (xy 0.09144 0.87376) (xy 0.11684 0.85344) (xy 0.13716 0.82804)
						(xy 0.1524 0.8001) (xy 0.16256 0.76835) (xy 0.1651 0.7366) (xy 0.1651 0.44958) (xy 0.17272 0.44196)
						(xy 0.19812 0.4064) (xy 0.2032 0.39624) (xy 0.20701 0.38735) (xy 0.21209 0.37719) (xy 0.2159 0.36703)
						(xy 0.21844 0.35687) (xy 0.22225 0.34544) (xy 0.22352 0.33528) (xy 0.22606 0.32512) (xy 0.22733 0.31369)
						(xy 0.22733 0.30353) (xy 0.2286 0.2921) (xy 0.22733 0.28067) (xy 0.22733 0.27051) (xy 0.22606 0.25908)
						(xy 0.22352 0.24892) (xy 0.22225 0.23876) (xy 0.21844 0.22733) (xy 0.2159 0.21717) (xy 0.21209 0.20701)
						(xy 0.20701 0.19685) (xy 0.2032 0.18796) (xy 0.19812 0.1778) (xy 0.17272 0.14224) (xy 0.1651 0.13462)
						(xy 0.1651 -0.7366) (xy 0.16256 -0.76835) (xy 0.1524 -0.8001) (xy 0.13716 -0.82804) (xy 0.11684 -0.85344)
						(xy 0.09144 -0.87376) (xy 0.0635 -0.889) (xy 0.03175 -0.89916)
					)
					(width 0)
					(fill yes)
				)
			)
		)
		(pad "191" smd custom
			(at 27.750008 -4.100068)
			(size 0.1143 0.1143)
			(layers "B.Cu" "B.Mask" "B.Paste")
			(net "M_A_DQ58")
			(options
				(clearance outline)
				(anchor circle)
			)
			(primitives
				(gr_poly
					(pts
						(xy 0 -0.9017) (xy -0.03175 -0.89916) (xy -0.0635 -0.889) (xy -0.09144 -0.87376) (xy -0.11684 -0.85344)
						(xy -0.13716 -0.82804) (xy -0.1524 -0.8001) (xy -0.16256 -0.76835) (xy -0.1651 -0.7366) (xy -0.1651 -0.19685)
						(xy -0.17272 -0.18923) (xy -0.17907 -0.18034) (xy -0.18669 -0.17145) (xy -0.19177 -0.16256) (xy -0.19812 -0.15367)
						(xy -0.20828 -0.13335) (xy -0.21971 -0.10287) (xy -0.22225 -0.09271) (xy -0.22479 -0.08128) (xy -0.22606 -0.07112)
						(xy -0.2286 -0.05969) (xy -0.2286 -0.01651) (xy -0.22606 -0.00508) (xy -0.22479 0.00508) (xy -0.22225 0.01651)
						(xy -0.21971 0.02667) (xy -0.20828 0.05715) (xy -0.19812 0.07747) (xy -0.19177 0.08636) (xy -0.18669 0.09525)
						(xy -0.17907 0.10414) (xy -0.17272 0.11303) (xy -0.1651 0.12065) (xy -0.1651 0.7366) (xy -0.16256 0.76835)
						(xy -0.1524 0.8001) (xy -0.13716 0.82804) (xy -0.11684 0.85344) (xy -0.09144 0.87376) (xy -0.0635 0.889)
						(xy -0.03175 0.89916) (xy 0 0.9017) (xy 0.03175 0.89916) (xy 0.0635 0.889) (xy 0.09144 0.87376)
						(xy 0.11684 0.85344) (xy 0.13716 0.82804) (xy 0.1524 0.8001) (xy 0.16256 0.76835) (xy 0.1651 0.7366)
						(xy 0.1651 0.11938) (xy 0.17272 0.11176) (xy 0.19812 0.0762) (xy 0.2032 0.06604) (xy 0.20701 0.05715)
						(xy 0.21209 0.04699) (xy 0.2159 0.03683) (xy 0.21844 0.02667) (xy 0.22225 0.01524) (xy 0.22352 0.00508)
						(xy 0.22606 -0.00508) (xy 0.22733 -0.01651) (xy 0.22733 -0.02667) (xy 0.2286 -0.0381) (xy 0.22733 -0.04953)
						(xy 0.22733 -0.05969) (xy 0.22606 -0.07112) (xy 0.22352 -0.08128) (xy 0.22225 -0.09144) (xy 0.21844 -0.10287)
						(xy 0.2159 -0.11303) (xy 0.21209 -0.12319) (xy 0.20701 -0.13335) (xy 0.2032 -0.14224) (xy 0.19812 -0.1524)
						(xy 0.17272 -0.18796) (xy 0.1651 -0.19558) (xy 0.1651 -0.7366) (xy 0.16256 -0.76835) (xy 0.1524 -0.8001)
						(xy 0.13716 -0.82804) (xy 0.11684 -0.85344) (xy 0.09144 -0.87376) (xy 0.0635 -0.889) (xy 0.03175 -0.89916)
					)
					(width 0)
					(fill yes)
				)
			)
		)
		(pad "192" smd custom
			(at 28.049982 4.100068)
			(size 0.1143 0.1143)
			(layers "B.Cu" "B.Mask" "B.Paste")
			(net "M_A_DQ62")
			(options
				(clearance outline)
				(anchor circle)
			)
			(primitives
				(gr_poly
					(pts
						(xy 0 -0.9017) (xy -0.03175 -0.89916) (xy -0.0635 -0.889) (xy -0.09144 -0.87376) (xy -0.11684 -0.85344)
						(xy -0.13716 -0.82804) (xy -0.1524 -0.8001) (xy -0.16256 -0.76835) (xy -0.1651 -0.7366) (xy -0.1651 -0.11938)
						(xy -0.17272 -0.11176) (xy -0.19812 -0.0762) (xy -0.2032 -0.06604) (xy -0.20701 -0.05715) (xy -0.21209 -0.04699)
						(xy -0.2159 -0.03683) (xy -0.21844 -0.02667) (xy -0.22225 -0.01524) (xy -0.22352 -0.00508) (xy -0.22606 0.00508)
						(xy -0.22733 0.01651) (xy -0.22733 0.02667) (xy -0.2286 0.0381) (xy -0.22733 0.04953) (xy -0.22733 0.05969)
						(xy -0.22606 0.07112) (xy -0.22352 0.08128) (xy -0.22225 0.09144) (xy -0.21844 0.10287) (xy -0.2159 0.11303)
						(xy -0.21209 0.12319) (xy -0.20701 0.13335) (xy -0.2032 0.14224) (xy -0.19812 0.1524) (xy -0.17272 0.18796)
						(xy -0.1651 0.19558) (xy -0.1651 0.7366) (xy -0.16256 0.76835) (xy -0.1524 0.8001) (xy -0.13716 0.82804)
						(xy -0.11684 0.85344) (xy -0.09144 0.87376) (xy -0.0635 0.889) (xy -0.03175 0.89916) (xy 0 0.9017)
						(xy 0.03175 0.89916) (xy 0.0635 0.889) (xy 0.09144 0.87376) (xy 0.11684 0.85344) (xy 0.13716 0.82804)
						(xy 0.1524 0.8001) (xy 0.16256 0.76835) (xy 0.1651 0.7366) (xy 0.1651 0.19685) (xy 0.17272 0.18923)
						(xy 0.17907 0.18034) (xy 0.18669 0.17145) (xy 0.19177 0.16256) (xy 0.19812 0.15367) (xy 0.20828 0.13335)
						(xy 0.21971 0.10287) (xy 0.22225 0.09271) (xy 0.22479 0.08128) (xy 0.22606 0.07112) (xy 0.2286 0.05969)
						(xy 0.2286 0.01651) (xy 0.22606 0.00508) (xy 0.22479 -0.00508) (xy 0.22225 -0.01651) (xy 0.21971 -0.02667)
						(xy 0.20828 -0.05715) (xy 0.19812 -0.07747) (xy 0.19177 -0.08636) (xy 0.18669 -0.09525) (xy 0.17907 -0.10414)
						(xy 0.17272 -0.11303) (xy 0.1651 -0.12065) (xy 0.1651 -0.7366) (xy 0.16256 -0.76835) (xy 0.1524 -0.8001)
						(xy 0.13716 -0.82804) (xy 0.11684 -0.85344) (xy 0.09144 -0.87376) (xy 0.0635 -0.889) (xy 0.03175 -0.89916)
					)
					(width 0)
					(fill yes)
				)
			)
		)
		(pad "193" smd custom
			(at 28.349956 -4.100068)
			(size 0.1143 0.1143)
			(layers "B.Cu" "B.Mask" "B.Paste")
			(net "M_A_DQ59")
			(options
				(clearance outline)
				(anchor circle)
			)
			(primitives
				(gr_poly
					(pts
						(xy 0 -0.9017) (xy -0.03175 -0.89916) (xy -0.0635 -0.889) (xy -0.09144 -0.87376) (xy -0.11684 -0.85344)
						(xy -0.13716 -0.82804) (xy -0.1524 -0.8001) (xy -0.16256 -0.76835) (xy -0.1651 -0.7366) (xy -0.1651 -0.44958)
						(xy -0.17272 -0.44196) (xy -0.19812 -0.4064) (xy -0.2032 -0.39624) (xy -0.20701 -0.38735) (xy -0.21209 -0.37719)
						(xy -0.2159 -0.36703) (xy -0.21844 -0.35687) (xy -0.22225 -0.34544) (xy -0.22352 -0.33528) (xy -0.22606 -0.32512)
						(xy -0.22733 -0.31369) (xy -0.22733 -0.30353) (xy -0.2286 -0.2921) (xy -0.22733 -0.28067) (xy -0.22733 -0.27051)
						(xy -0.22606 -0.25908) (xy -0.22352 -0.24892) (xy -0.22225 -0.23876) (xy -0.21844 -0.22733) (xy -0.2159 -0.21717)
						(xy -0.21209 -0.20701) (xy -0.20701 -0.19685) (xy -0.2032 -0.18796) (xy -0.19812 -0.1778) (xy -0.17272 -0.14224)
						(xy -0.1651 -0.13462) (xy -0.1651 0.7366) (xy -0.16256 0.76835) (xy -0.1524 0.8001) (xy -0.13716 0.82804)
						(xy -0.11684 0.85344) (xy -0.09144 0.87376) (xy -0.0635 0.889) (xy -0.03175 0.89916) (xy 0 0.9017)
						(xy 0.03175 0.89916) (xy 0.0635 0.889) (xy 0.09144 0.87376) (xy 0.11684 0.85344) (xy 0.13716 0.82804)
						(xy 0.1524 0.8001) (xy 0.16256 0.76835) (xy 0.1651 0.7366) (xy 0.1651 -0.13462) (xy 0.17272 -0.14224)
						(xy 0.19812 -0.1778) (xy 0.2032 -0.18796) (xy 0.20701 -0.19685) (xy 0.21209 -0.20701) (xy 0.2159 -0.21717)
						(xy 0.21844 -0.22733) (xy 0.22225 -0.23876) (xy 0.22352 -0.24892) (xy 0.22606 -0.25908) (xy 0.22733 -0.27051)
						(xy 0.22733 -0.28067) (xy 0.2286 -0.2921) (xy 0.22733 -0.30353) (xy 0.22733 -0.31369) (xy 0.22606 -0.32512)
						(xy 0.22352 -0.33528) (xy 0.22225 -0.34544) (xy 0.21844 -0.35687) (xy 0.2159 -0.36703) (xy 0.21209 -0.37719)
						(xy 0.20701 -0.38735) (xy 0.2032 -0.39624) (xy 0.19812 -0.4064) (xy 0.17272 -0.44196) (xy 0.1651 -0.44958)
						(xy 0.1651 -0.7366) (xy 0.16256 -0.76835) (xy 0.1524 -0.8001) (xy 0.13716 -0.82804) (xy 0.11684 -0.85344)
						(xy 0.09144 -0.87376) (xy 0.0635 -0.889) (xy 0.03175 -0.89916)
					)
					(width 0)
					(fill yes)
				)
			)
		)
		(pad "194" smd custom
			(at 28.64993 4.100068)
			(size 0.1143 0.1143)
			(layers "B.Cu" "B.Mask" "B.Paste")
			(net "M_A_DQ63")
			(options
				(clearance outline)
				(anchor circle)
			)
			(primitives
				(gr_poly
					(pts
						(xy 0 -0.9017) (xy -0.03175 -0.89916) (xy -0.0635 -0.889) (xy -0.09144 -0.87376) (xy -0.11684 -0.85344)
						(xy -0.13716 -0.82804) (xy -0.1524 -0.8001) (xy -0.16256 -0.76835) (xy -0.1651 -0.7366) (xy -0.1651 0.13462)
						(xy -0.17272 0.14224) (xy -0.19812 0.1778) (xy -0.2032 0.18796) (xy -0.20701 0.19685) (xy -0.21209 0.20701)
						(xy -0.2159 0.21717) (xy -0.21844 0.22733) (xy -0.22225 0.23876) (xy -0.22352 0.24892) (xy -0.22606 0.25908)
						(xy -0.22733 0.27051) (xy -0.22733 0.28067) (xy -0.2286 0.2921) (xy -0.22733 0.30353) (xy -0.22733 0.31369)
						(xy -0.22606 0.32512) (xy -0.22352 0.33528) (xy -0.22225 0.34544) (xy -0.21844 0.35687) (xy -0.2159 0.36703)
						(xy -0.21209 0.37719) (xy -0.20701 0.38735) (xy -0.2032 0.39624) (xy -0.19812 0.4064) (xy -0.17272 0.44196)
						(xy -0.1651 0.44958) (xy -0.1651 0.7366) (xy -0.16256 0.76835) (xy -0.1524 0.8001) (xy -0.13716 0.82804)
						(xy -0.11684 0.85344) (xy -0.09144 0.87376) (xy -0.0635 0.889) (xy -0.03175 0.89916) (xy 0 0.9017)
						(xy 0.03175 0.89916) (xy 0.0635 0.889) (xy 0.09144 0.87376) (xy 0.11684 0.85344) (xy 0.13716 0.82804)
						(xy 0.1524 0.8001) (xy 0.16256 0.76835) (xy 0.1651 0.7366) (xy 0.1651 0.44958) (xy 0.17272 0.44196)
						(xy 0.19812 0.4064) (xy 0.2032 0.39624) (xy 0.20701 0.38735) (xy 0.21209 0.37719) (xy 0.2159 0.36703)
						(xy 0.21844 0.35687) (xy 0.22225 0.34544) (xy 0.22352 0.33528) (xy 0.22606 0.32512) (xy 0.22733 0.31369)
						(xy 0.22733 0.30353) (xy 0.2286 0.2921) (xy 0.22733 0.28067) (xy 0.22733 0.27051) (xy 0.22606 0.25908)
						(xy 0.22352 0.24892) (xy 0.22225 0.23876) (xy 0.21844 0.22733) (xy 0.2159 0.21717) (xy 0.21209 0.20701)
						(xy 0.20701 0.19685) (xy 0.2032 0.18796) (xy 0.19812 0.1778) (xy 0.17272 0.14224) (xy 0.1651 0.13462)
						(xy 0.1651 -0.7366) (xy 0.16256 -0.76835) (xy 0.1524 -0.8001) (xy 0.13716 -0.82804) (xy 0.11684 -0.85344)
						(xy 0.09144 -0.87376) (xy 0.0635 -0.889) (xy 0.03175 -0.89916)
					)
					(width 0)
					(fill yes)
				)
			)
		)
		(pad "195" smd custom
			(at 28.949904 -4.100068)
			(size 0.1143 0.1143)
			(layers "B.Cu" "B.Mask" "B.Paste")
			(net "GND")
			(options
				(clearance outline)
				(anchor circle)
			)
			(primitives
				(gr_poly
					(pts
						(xy 0 -0.9017) (xy -0.03175 -0.89916) (xy -0.0635 -0.889) (xy -0.09144 -0.87376) (xy -0.11684 -0.85344)
						(xy -0.13716 -0.82804) (xy -0.1524 -0.8001) (xy -0.16256 -0.76835) (xy -0.1651 -0.7366) (xy -0.1651 -0.19685)
						(xy -0.17272 -0.18923) (xy -0.17907 -0.18034) (xy -0.18669 -0.17145) (xy -0.19177 -0.16256) (xy -0.19812 -0.15367)
						(xy -0.20828 -0.13335) (xy -0.21971 -0.10287) (xy -0.22225 -0.09271) (xy -0.22479 -0.08128) (xy -0.22606 -0.07112)
						(xy -0.2286 -0.05969) (xy -0.2286 -0.01651) (xy -0.22606 -0.00508) (xy -0.22479 0.00508) (xy -0.22225 0.01651)
						(xy -0.21971 0.02667) (xy -0.20828 0.05715) (xy -0.19812 0.07747) (xy -0.19177 0.08636) (xy -0.18669 0.09525)
						(xy -0.17907 0.10414) (xy -0.17272 0.11303) (xy -0.1651 0.12065) (xy -0.1651 0.7366) (xy -0.16256 0.76835)
						(xy -0.1524 0.8001) (xy -0.13716 0.82804) (xy -0.11684 0.85344) (xy -0.09144 0.87376) (xy -0.0635 0.889)
						(xy -0.03175 0.89916) (xy 0 0.9017) (xy 0.03175 0.89916) (xy 0.0635 0.889) (xy 0.09144 0.87376)
						(xy 0.11684 0.85344) (xy 0.13716 0.82804) (xy 0.1524 0.8001) (xy 0.16256 0.76835) (xy 0.1651 0.7366)
						(xy 0.1651 0.11938) (xy 0.17272 0.11176) (xy 0.19812 0.0762) (xy 0.2032 0.06604) (xy 0.20701 0.05715)
						(xy 0.21209 0.04699) (xy 0.2159 0.03683) (xy 0.21844 0.02667) (xy 0.22225 0.01524) (xy 0.22352 0.00508)
						(xy 0.22606 -0.00508) (xy 0.22733 -0.01651) (xy 0.22733 -0.02667) (xy 0.2286 -0.0381) (xy 0.22733 -0.04953)
						(xy 0.22733 -0.05969) (xy 0.22606 -0.07112) (xy 0.22352 -0.08128) (xy 0.22225 -0.09144) (xy 0.21844 -0.10287)
						(xy 0.2159 -0.11303) (xy 0.21209 -0.12319) (xy 0.20701 -0.13335) (xy 0.2032 -0.14224) (xy 0.19812 -0.1524)
						(xy 0.17272 -0.18796) (xy 0.1651 -0.19558) (xy 0.1651 -0.7366) (xy 0.16256 -0.76835) (xy 0.1524 -0.8001)
						(xy 0.13716 -0.82804) (xy 0.11684 -0.85344) (xy 0.09144 -0.87376) (xy 0.0635 -0.889) (xy 0.03175 -0.89916)
					)
					(width 0)
					(fill yes)
				)
			)
		)
		(pad "196" smd custom
			(at 29.249878 4.100068)
			(size 0.1143 0.1143)
			(layers "B.Cu" "B.Mask" "B.Paste")
			(net "GND")
			(options
				(clearance outline)
				(anchor circle)
			)
			(primitives
				(gr_poly
					(pts
						(xy 0 -0.9017) (xy -0.03175 -0.89916) (xy -0.0635 -0.889) (xy -0.09144 -0.87376) (xy -0.11684 -0.85344)
						(xy -0.13716 -0.82804) (xy -0.1524 -0.8001) (xy -0.16256 -0.76835) (xy -0.1651 -0.7366) (xy -0.1651 -0.11938)
						(xy -0.17272 -0.11176) (xy -0.19812 -0.0762) (xy -0.2032 -0.06604) (xy -0.20701 -0.05715) (xy -0.21209 -0.04699)
						(xy -0.2159 -0.03683) (xy -0.21844 -0.02667) (xy -0.22225 -0.01524) (xy -0.22352 -0.00508) (xy -0.22606 0.00508)
						(xy -0.22733 0.01651) (xy -0.22733 0.02667) (xy -0.2286 0.0381) (xy -0.22733 0.04953) (xy -0.22733 0.05969)
						(xy -0.22606 0.07112) (xy -0.22352 0.08128) (xy -0.22225 0.09144) (xy -0.21844 0.10287) (xy -0.2159 0.11303)
						(xy -0.21209 0.12319) (xy -0.20701 0.13335) (xy -0.2032 0.14224) (xy -0.19812 0.1524) (xy -0.17272 0.18796)
						(xy -0.1651 0.19558) (xy -0.1651 0.7366) (xy -0.16256 0.76835) (xy -0.1524 0.8001) (xy -0.13716 0.82804)
						(xy -0.11684 0.85344) (xy -0.09144 0.87376) (xy -0.0635 0.889) (xy -0.03175 0.89916) (xy 0 0.9017)
						(xy 0.03175 0.89916) (xy 0.0635 0.889) (xy 0.09144 0.87376) (xy 0.11684 0.85344) (xy 0.13716 0.82804)
						(xy 0.1524 0.8001) (xy 0.16256 0.76835) (xy 0.1651 0.7366) (xy 0.1651 0.19685) (xy 0.17272 0.18923)
						(xy 0.17907 0.18034) (xy 0.18669 0.17145) (xy 0.19177 0.16256) (xy 0.19812 0.15367) (xy 0.20828 0.13335)
						(xy 0.21971 0.10287) (xy 0.22225 0.09271) (xy 0.22479 0.08128) (xy 0.22606 0.07112) (xy 0.2286 0.05969)
						(xy 0.2286 0.01651) (xy 0.22606 0.00508) (xy 0.22479 -0.00508) (xy 0.22225 -0.01651) (xy 0.21971 -0.02667)
						(xy 0.20828 -0.05715) (xy 0.19812 -0.07747) (xy 0.19177 -0.08636) (xy 0.18669 -0.09525) (xy 0.17907 -0.10414)
						(xy 0.17272 -0.11303) (xy 0.1651 -0.12065) (xy 0.1651 -0.7366) (xy 0.16256 -0.76835) (xy 0.1524 -0.8001)
						(xy 0.13716 -0.82804) (xy 0.11684 -0.85344) (xy 0.09144 -0.87376) (xy 0.0635 -0.889) (xy 0.03175 -0.89916)
					)
					(width 0)
					(fill yes)
				)
			)
		)
		(pad "197" smd custom
			(at 29.550106 -4.100068)
			(size 0.1143 0.1143)
			(layers "B.Cu" "B.Mask" "B.Paste")
			(net "CHA_0_SA0")
			(options
				(clearance outline)
				(anchor circle)
			)
			(primitives
				(gr_poly
					(pts
						(xy 0 -0.9017) (xy -0.03175 -0.89916) (xy -0.0635 -0.889) (xy -0.09144 -0.87376) (xy -0.11684 -0.85344)
						(xy -0.13716 -0.82804) (xy -0.1524 -0.8001) (xy -0.16256 -0.76835) (xy -0.1651 -0.7366) (xy -0.1651 -0.44958)
						(xy -0.17272 -0.44196) (xy -0.19812 -0.4064) (xy -0.2032 -0.39624) (xy -0.20701 -0.38735) (xy -0.21209 -0.37719)
						(xy -0.2159 -0.36703) (xy -0.21844 -0.35687) (xy -0.22225 -0.34544) (xy -0.22352 -0.33528) (xy -0.22606 -0.32512)
						(xy -0.22733 -0.31369) (xy -0.22733 -0.30353) (xy -0.2286 -0.2921) (xy -0.22733 -0.28067) (xy -0.22733 -0.27051)
						(xy -0.22606 -0.25908) (xy -0.22352 -0.24892) (xy -0.22225 -0.23876) (xy -0.21844 -0.22733) (xy -0.2159 -0.21717)
						(xy -0.21209 -0.20701) (xy -0.20701 -0.19685) (xy -0.2032 -0.18796) (xy -0.19812 -0.1778) (xy -0.17272 -0.14224)
						(xy -0.1651 -0.13462) (xy -0.1651 0.7366) (xy -0.16256 0.76835) (xy -0.1524 0.8001) (xy -0.13716 0.82804)
						(xy -0.11684 0.85344) (xy -0.09144 0.87376) (xy -0.0635 0.889) (xy -0.03175 0.89916) (xy 0 0.9017)
						(xy 0.03175 0.89916) (xy 0.0635 0.889) (xy 0.09144 0.87376) (xy 0.11684 0.85344) (xy 0.13716 0.82804)
						(xy 0.1524 0.8001) (xy 0.16256 0.76835) (xy 0.1651 0.7366) (xy 0.1651 -0.13462) (xy 0.17272 -0.14224)
						(xy 0.19812 -0.1778) (xy 0.2032 -0.18796) (xy 0.20701 -0.19685) (xy 0.21209 -0.20701) (xy 0.2159 -0.21717)
						(xy 0.21844 -0.22733) (xy 0.22225 -0.23876) (xy 0.22352 -0.24892) (xy 0.22606 -0.25908) (xy 0.22733 -0.27051)
						(xy 0.22733 -0.28067) (xy 0.2286 -0.2921) (xy 0.22733 -0.30353) (xy 0.22733 -0.31369) (xy 0.22606 -0.32512)
						(xy 0.22352 -0.33528) (xy 0.22225 -0.34544) (xy 0.21844 -0.35687) (xy 0.2159 -0.36703) (xy 0.21209 -0.37719)
						(xy 0.20701 -0.38735) (xy 0.2032 -0.39624) (xy 0.19812 -0.4064) (xy 0.17272 -0.44196) (xy 0.1651 -0.44958)
						(xy 0.1651 -0.7366) (xy 0.16256 -0.76835) (xy 0.1524 -0.8001) (xy 0.13716 -0.82804) (xy 0.11684 -0.85344)
						(xy 0.09144 -0.87376) (xy 0.0635 -0.889) (xy 0.03175 -0.89916)
					)
					(width 0)
					(fill yes)
				)
			)
		)
		(pad "198" smd custom
			(at 29.85008 4.100068)
			(size 0.1143 0.1143)
			(layers "B.Cu" "B.Mask" "B.Paste")
			(net "MEMORY_HOT_LV_R#")
			(options
				(clearance outline)
				(anchor circle)
			)
			(primitives
				(gr_poly
					(pts
						(xy 0 -0.9017) (xy -0.03175 -0.89916) (xy -0.0635 -0.889) (xy -0.09144 -0.87376) (xy -0.11684 -0.85344)
						(xy -0.13716 -0.82804) (xy -0.1524 -0.8001) (xy -0.16256 -0.76835) (xy -0.1651 -0.7366) (xy -0.1651 0.13462)
						(xy -0.17272 0.14224) (xy -0.19812 0.1778) (xy -0.2032 0.18796) (xy -0.20701 0.19685) (xy -0.21209 0.20701)
						(xy -0.2159 0.21717) (xy -0.21844 0.22733) (xy -0.22225 0.23876) (xy -0.22352 0.24892) (xy -0.22606 0.25908)
						(xy -0.22733 0.27051) (xy -0.22733 0.28067) (xy -0.2286 0.2921) (xy -0.22733 0.30353) (xy -0.22733 0.31369)
						(xy -0.22606 0.32512) (xy -0.22352 0.33528) (xy -0.22225 0.34544) (xy -0.21844 0.35687) (xy -0.2159 0.36703)
						(xy -0.21209 0.37719) (xy -0.20701 0.38735) (xy -0.2032 0.39624) (xy -0.19812 0.4064) (xy -0.17272 0.44196)
						(xy -0.1651 0.44958) (xy -0.1651 0.7366) (xy -0.16256 0.76835) (xy -0.1524 0.8001) (xy -0.13716 0.82804)
						(xy -0.11684 0.85344) (xy -0.09144 0.87376) (xy -0.0635 0.889) (xy -0.03175 0.89916) (xy 0 0.9017)
						(xy 0.03175 0.89916) (xy 0.0635 0.889) (xy 0.09144 0.87376) (xy 0.11684 0.85344) (xy 0.13716 0.82804)
						(xy 0.1524 0.8001) (xy 0.16256 0.76835) (xy 0.1651 0.7366) (xy 0.1651 0.44958) (xy 0.17272 0.44196)
						(xy 0.19812 0.4064) (xy 0.2032 0.39624) (xy 0.20701 0.38735) (xy 0.21209 0.37719) (xy 0.2159 0.36703)
						(xy 0.21844 0.35687) (xy 0.22225 0.34544) (xy 0.22352 0.33528) (xy 0.22606 0.32512) (xy 0.22733 0.31369)
						(xy 0.22733 0.30353) (xy 0.2286 0.2921) (xy 0.22733 0.28067) (xy 0.22733 0.27051) (xy 0.22606 0.25908)
						(xy 0.22352 0.24892) (xy 0.22225 0.23876) (xy 0.21844 0.22733) (xy 0.2159 0.21717) (xy 0.21209 0.20701)
						(xy 0.20701 0.19685) (xy 0.2032 0.18796) (xy 0.19812 0.1778) (xy 0.17272 0.14224) (xy 0.1651 0.13462)
						(xy 0.1651 -0.7366) (xy 0.16256 -0.76835) (xy 0.1524 -0.8001) (xy 0.13716 -0.82804) (xy 0.11684 -0.85344)
						(xy 0.09144 -0.87376) (xy 0.0635 -0.889) (xy 0.03175 -0.89916)
					)
					(width 0)
					(fill yes)
				)
			)
		)
		(pad "199" smd custom
			(at 30.150054 -4.100068)
			(size 0.1143 0.1143)
			(layers "B.Cu" "B.Mask" "B.Paste")
			(net "P3V3_STBY")
			(options
				(clearance outline)
				(anchor circle)
			)
			(primitives
				(gr_poly
					(pts
						(xy 0 -0.9017) (xy -0.03175 -0.89916) (xy -0.0635 -0.889) (xy -0.09144 -0.87376) (xy -0.11684 -0.85344)
						(xy -0.13716 -0.82804) (xy -0.1524 -0.8001) (xy -0.16256 -0.76835) (xy -0.1651 -0.7366) (xy -0.1651 -0.19685)
						(xy -0.17272 -0.18923) (xy -0.17907 -0.18034) (xy -0.18669 -0.17145) (xy -0.19177 -0.16256) (xy -0.19812 -0.15367)
						(xy -0.20828 -0.13335) (xy -0.21971 -0.10287) (xy -0.22225 -0.09271) (xy -0.22479 -0.08128) (xy -0.22606 -0.07112)
						(xy -0.2286 -0.05969) (xy -0.2286 -0.01651) (xy -0.22606 -0.00508) (xy -0.22479 0.00508) (xy -0.22225 0.01651)
						(xy -0.21971 0.02667) (xy -0.20828 0.05715) (xy -0.19812 0.07747) (xy -0.19177 0.08636) (xy -0.18669 0.09525)
						(xy -0.17907 0.10414) (xy -0.17272 0.11303) (xy -0.1651 0.12065) (xy -0.1651 0.7366) (xy -0.16256 0.76835)
						(xy -0.1524 0.8001) (xy -0.13716 0.82804) (xy -0.11684 0.85344) (xy -0.09144 0.87376) (xy -0.0635 0.889)
						(xy -0.03175 0.89916) (xy 0 0.9017) (xy 0.03175 0.89916) (xy 0.0635 0.889) (xy 0.09144 0.87376)
						(xy 0.11684 0.85344) (xy 0.13716 0.82804) (xy 0.1524 0.8001) (xy 0.16256 0.76835) (xy 0.1651 0.7366)
						(xy 0.1651 0.11938) (xy 0.17272 0.11176) (xy 0.19812 0.0762) (xy 0.2032 0.06604) (xy 0.20701 0.05715)
						(xy 0.21209 0.04699) (xy 0.2159 0.03683) (xy 0.21844 0.02667) (xy 0.22225 0.01524) (xy 0.22352 0.00508)
						(xy 0.22606 -0.00508) (xy 0.22733 -0.01651) (xy 0.22733 -0.02667) (xy 0.2286 -0.0381) (xy 0.22733 -0.04953)
						(xy 0.22733 -0.05969) (xy 0.22606 -0.07112) (xy 0.22352 -0.08128) (xy 0.22225 -0.09144) (xy 0.21844 -0.10287)
						(xy 0.2159 -0.11303) (xy 0.21209 -0.12319) (xy 0.20701 -0.13335) (xy 0.2032 -0.14224) (xy 0.19812 -0.1524)
						(xy 0.17272 -0.18796) (xy 0.1651 -0.19558) (xy 0.1651 -0.7366) (xy 0.16256 -0.76835) (xy 0.1524 -0.8001)
						(xy 0.13716 -0.82804) (xy 0.11684 -0.85344) (xy 0.09144 -0.87376) (xy 0.0635 -0.889) (xy 0.03175 -0.89916)
					)
					(width 0)
					(fill yes)
				)
			)
		)
		(pad "200" smd custom
			(at 30.450028 4.100068)
			(size 0.1143 0.1143)
			(layers "B.Cu" "B.Mask" "B.Paste")
			(net "SMB_M_A0_R_DATA")
			(options
				(clearance outline)
				(anchor circle)
			)
			(primitives
				(gr_poly
					(pts
						(xy 0 -0.9017) (xy -0.03175 -0.89916) (xy -0.0635 -0.889) (xy -0.09144 -0.87376) (xy -0.11684 -0.85344)
						(xy -0.13716 -0.82804) (xy -0.1524 -0.8001) (xy -0.16256 -0.76835) (xy -0.1651 -0.7366) (xy -0.1651 -0.11938)
						(xy -0.17272 -0.11176) (xy -0.19812 -0.0762) (xy -0.2032 -0.06604) (xy -0.20701 -0.05715) (xy -0.21209 -0.04699)
						(xy -0.2159 -0.03683) (xy -0.21844 -0.02667) (xy -0.22225 -0.01524) (xy -0.22352 -0.00508) (xy -0.22606 0.00508)
						(xy -0.22733 0.01651) (xy -0.22733 0.02667) (xy -0.2286 0.0381) (xy -0.22733 0.04953) (xy -0.22733 0.05969)
						(xy -0.22606 0.07112) (xy -0.22352 0.08128) (xy -0.22225 0.09144) (xy -0.21844 0.10287) (xy -0.2159 0.11303)
						(xy -0.21209 0.12319) (xy -0.20701 0.13335) (xy -0.2032 0.14224) (xy -0.19812 0.1524) (xy -0.17272 0.18796)
						(xy -0.1651 0.19558) (xy -0.1651 0.7366) (xy -0.16256 0.76835) (xy -0.1524 0.8001) (xy -0.13716 0.82804)
						(xy -0.11684 0.85344) (xy -0.09144 0.87376) (xy -0.0635 0.889) (xy -0.03175 0.89916) (xy 0 0.9017)
						(xy 0.03175 0.89916) (xy 0.0635 0.889) (xy 0.09144 0.87376) (xy 0.11684 0.85344) (xy 0.13716 0.82804)
						(xy 0.1524 0.8001) (xy 0.16256 0.76835) (xy 0.1651 0.7366) (xy 0.1651 0.19685) (xy 0.17272 0.18923)
						(xy 0.17907 0.18034) (xy 0.18669 0.17145) (xy 0.19177 0.16256) (xy 0.19812 0.15367) (xy 0.20828 0.13335)
						(xy 0.21971 0.10287) (xy 0.22225 0.09271) (xy 0.22479 0.08128) (xy 0.22606 0.07112) (xy 0.2286 0.05969)
						(xy 0.2286 0.01651) (xy 0.22606 0.00508) (xy 0.22479 -0.00508) (xy 0.22225 -0.01651) (xy 0.21971 -0.02667)
						(xy 0.20828 -0.05715) (xy 0.19812 -0.07747) (xy 0.19177 -0.08636) (xy 0.18669 -0.09525) (xy 0.17907 -0.10414)
						(xy 0.17272 -0.11303) (xy 0.1651 -0.12065) (xy 0.1651 -0.7366) (xy 0.16256 -0.76835) (xy 0.1524 -0.8001)
						(xy 0.13716 -0.82804) (xy 0.11684 -0.85344) (xy 0.09144 -0.87376) (xy 0.0635 -0.889) (xy 0.03175 -0.89916)
					)
					(width 0)
					(fill yes)
				)
			)
		)
		(pad "201" smd custom
			(at 30.750002 -4.100068)
			(size 0.1143 0.1143)
			(layers "B.Cu" "B.Mask" "B.Paste")
			(net "CHA_0_SA1")
			(options
				(clearance outline)
				(anchor circle)
			)
			(primitives
				(gr_poly
					(pts
						(xy 0 -0.9017) (xy -0.03175 -0.89916) (xy -0.0635 -0.889) (xy -0.09144 -0.87376) (xy -0.11684 -0.85344)
						(xy -0.13716 -0.82804) (xy -0.1524 -0.8001) (xy -0.16256 -0.76835) (xy -0.1651 -0.7366) (xy -0.1651 -0.44958)
						(xy -0.17272 -0.44196) (xy -0.19812 -0.4064) (xy -0.2032 -0.39624) (xy -0.20701 -0.38735) (xy -0.21209 -0.37719)
						(xy -0.2159 -0.36703) (xy -0.21844 -0.35687) (xy -0.22225 -0.34544) (xy -0.22352 -0.33528) (xy -0.22606 -0.32512)
						(xy -0.22733 -0.31369) (xy -0.22733 -0.30353) (xy -0.2286 -0.2921) (xy -0.22733 -0.28067) (xy -0.22733 -0.27051)
						(xy -0.22606 -0.25908) (xy -0.22352 -0.24892) (xy -0.22225 -0.23876) (xy -0.21844 -0.22733) (xy -0.2159 -0.21717)
						(xy -0.21209 -0.20701) (xy -0.20701 -0.19685) (xy -0.2032 -0.18796) (xy -0.19812 -0.1778) (xy -0.17272 -0.14224)
						(xy -0.1651 -0.13462) (xy -0.1651 0.7366) (xy -0.16256 0.76835) (xy -0.1524 0.8001) (xy -0.13716 0.82804)
						(xy -0.11684 0.85344) (xy -0.09144 0.87376) (xy -0.0635 0.889) (xy -0.03175 0.89916) (xy 0 0.9017)
						(xy 0.03175 0.89916) (xy 0.0635 0.889) (xy 0.09144 0.87376) (xy 0.11684 0.85344) (xy 0.13716 0.82804)
						(xy 0.1524 0.8001) (xy 0.16256 0.76835) (xy 0.1651 0.7366) (xy 0.1651 -0.13462) (xy 0.17272 -0.14224)
						(xy 0.19812 -0.1778) (xy 0.2032 -0.18796) (xy 0.20701 -0.19685) (xy 0.21209 -0.20701) (xy 0.2159 -0.21717)
						(xy 0.21844 -0.22733) (xy 0.22225 -0.23876) (xy 0.22352 -0.24892) (xy 0.22606 -0.25908) (xy 0.22733 -0.27051)
						(xy 0.22733 -0.28067) (xy 0.2286 -0.2921) (xy 0.22733 -0.30353) (xy 0.22733 -0.31369) (xy 0.22606 -0.32512)
						(xy 0.22352 -0.33528) (xy 0.22225 -0.34544) (xy 0.21844 -0.35687) (xy 0.2159 -0.36703) (xy 0.21209 -0.37719)
						(xy 0.20701 -0.38735) (xy 0.2032 -0.39624) (xy 0.19812 -0.4064) (xy 0.17272 -0.44196) (xy 0.1651 -0.44958)
						(xy 0.1651 -0.7366) (xy 0.16256 -0.76835) (xy 0.1524 -0.8001) (xy 0.13716 -0.82804) (xy 0.11684 -0.85344)
						(xy 0.09144 -0.87376) (xy 0.0635 -0.889) (xy 0.03175 -0.89916)
					)
					(width 0)
					(fill yes)
				)
			)
		)
		(pad "202" smd custom
			(at 31.049976 4.100068)
			(size 0.1143 0.1143)
			(layers "B.Cu" "B.Mask" "B.Paste")
			(net "SMB_M_A0_R_CLK")
			(options
				(clearance outline)
				(anchor circle)
			)
			(primitives
				(gr_poly
					(pts
						(xy 0 -0.9017) (xy -0.03175 -0.89916) (xy -0.0635 -0.889) (xy -0.09144 -0.87376) (xy -0.11684 -0.85344)
						(xy -0.13716 -0.82804) (xy -0.1524 -0.8001) (xy -0.16256 -0.76835) (xy -0.1651 -0.7366) (xy -0.1651 0.13462)
						(xy -0.17272 0.14224) (xy -0.19812 0.1778) (xy -0.2032 0.18796) (xy -0.20701 0.19685) (xy -0.21209 0.20701)
						(xy -0.2159 0.21717) (xy -0.21844 0.22733) (xy -0.22225 0.23876) (xy -0.22352 0.24892) (xy -0.22606 0.25908)
						(xy -0.22733 0.27051) (xy -0.22733 0.28067) (xy -0.2286 0.2921) (xy -0.22733 0.30353) (xy -0.22733 0.31369)
						(xy -0.22606 0.32512) (xy -0.22352 0.33528) (xy -0.22225 0.34544) (xy -0.21844 0.35687) (xy -0.2159 0.36703)
						(xy -0.21209 0.37719) (xy -0.20701 0.38735) (xy -0.2032 0.39624) (xy -0.19812 0.4064) (xy -0.17272 0.44196)
						(xy -0.1651 0.44958) (xy -0.1651 0.7366) (xy -0.16256 0.76835) (xy -0.1524 0.8001) (xy -0.13716 0.82804)
						(xy -0.11684 0.85344) (xy -0.09144 0.87376) (xy -0.0635 0.889) (xy -0.03175 0.89916) (xy 0 0.9017)
						(xy 0.03175 0.89916) (xy 0.0635 0.889) (xy 0.09144 0.87376) (xy 0.11684 0.85344) (xy 0.13716 0.82804)
						(xy 0.1524 0.8001) (xy 0.16256 0.76835) (xy 0.1651 0.7366) (xy 0.1651 0.44958) (xy 0.17272 0.44196)
						(xy 0.19812 0.4064) (xy 0.2032 0.39624) (xy 0.20701 0.38735) (xy 0.21209 0.37719) (xy 0.2159 0.36703)
						(xy 0.21844 0.35687) (xy 0.22225 0.34544) (xy 0.22352 0.33528) (xy 0.22606 0.32512) (xy 0.22733 0.31369)
						(xy 0.22733 0.30353) (xy 0.2286 0.2921) (xy 0.22733 0.28067) (xy 0.22733 0.27051) (xy 0.22606 0.25908)
						(xy 0.22352 0.24892) (xy 0.22225 0.23876) (xy 0.21844 0.22733) (xy 0.2159 0.21717) (xy 0.21209 0.20701)
						(xy 0.20701 0.19685) (xy 0.2032 0.18796) (xy 0.19812 0.1778) (xy 0.17272 0.14224) (xy 0.1651 0.13462)
						(xy 0.1651 -0.7366) (xy 0.16256 -0.76835) (xy 0.1524 -0.8001) (xy 0.13716 -0.82804) (xy 0.11684 -0.85344)
						(xy 0.09144 -0.87376) (xy 0.0635 -0.889) (xy 0.03175 -0.89916)
					)
					(width 0)
					(fill yes)
				)
			)
		)
		(pad "203" smd custom
			(at 31.34995 -4.100068)
			(size 0.1143 0.1143)
			(layers "B.Cu" "B.Mask" "B.Paste")
			(net "PV_VTT_DDR_A")
			(options
				(clearance outline)
				(anchor circle)
			)
			(primitives
				(gr_poly
					(pts
						(xy 0 -0.9017) (xy -0.03175 -0.89916) (xy -0.0635 -0.889) (xy -0.09144 -0.87376) (xy -0.11684 -0.85344)
						(xy -0.13716 -0.82804) (xy -0.1524 -0.8001) (xy -0.16256 -0.76835) (xy -0.1651 -0.7366) (xy -0.1651 -0.19685)
						(xy -0.17272 -0.18923) (xy -0.17907 -0.18034) (xy -0.18669 -0.17145) (xy -0.19177 -0.16256) (xy -0.19812 -0.15367)
						(xy -0.20828 -0.13335) (xy -0.21971 -0.10287) (xy -0.22225 -0.09271) (xy -0.22479 -0.08128) (xy -0.22606 -0.07112)
						(xy -0.2286 -0.05969) (xy -0.2286 -0.01651) (xy -0.22606 -0.00508) (xy -0.22479 0.00508) (xy -0.22225 0.01651)
						(xy -0.21971 0.02667) (xy -0.20828 0.05715) (xy -0.19812 0.07747) (xy -0.19177 0.08636) (xy -0.18669 0.09525)
						(xy -0.17907 0.10414) (xy -0.17272 0.11303) (xy -0.1651 0.12065) (xy -0.1651 0.7366) (xy -0.16256 0.76835)
						(xy -0.1524 0.8001) (xy -0.13716 0.82804) (xy -0.11684 0.85344) (xy -0.09144 0.87376) (xy -0.0635 0.889)
						(xy -0.03175 0.89916) (xy 0 0.9017) (xy 0.03175 0.89916) (xy 0.0635 0.889) (xy 0.09144 0.87376)
						(xy 0.11684 0.85344) (xy 0.13716 0.82804) (xy 0.1524 0.8001) (xy 0.16256 0.76835) (xy 0.1651 0.7366)
						(xy 0.1651 0.11938) (xy 0.17272 0.11176) (xy 0.19812 0.0762) (xy 0.2032 0.06604) (xy 0.20701 0.05715)
						(xy 0.21209 0.04699) (xy 0.2159 0.03683) (xy 0.21844 0.02667) (xy 0.22225 0.01524) (xy 0.22352 0.00508)
						(xy 0.22606 -0.00508) (xy 0.22733 -0.01651) (xy 0.22733 -0.02667) (xy 0.2286 -0.0381) (xy 0.22733 -0.04953)
						(xy 0.22733 -0.05969) (xy 0.22606 -0.07112) (xy 0.22352 -0.08128) (xy 0.22225 -0.09144) (xy 0.21844 -0.10287)
						(xy 0.2159 -0.11303) (xy 0.21209 -0.12319) (xy 0.20701 -0.13335) (xy 0.2032 -0.14224) (xy 0.19812 -0.1524)
						(xy 0.17272 -0.18796) (xy 0.1651 -0.19558) (xy 0.1651 -0.7366) (xy 0.16256 -0.76835) (xy 0.1524 -0.8001)
						(xy 0.13716 -0.82804) (xy 0.11684 -0.85344) (xy 0.09144 -0.87376) (xy 0.0635 -0.889) (xy 0.03175 -0.89916)
					)
					(width 0)
					(fill yes)
				)
			)
		)
		(pad "204" smd custom
			(at 31.649924 4.100068)
			(size 0.1143 0.1143)
			(layers "B.Cu" "B.Mask" "B.Paste")
			(net "PV_VTT_DDR_A")
			(options
				(clearance outline)
				(anchor circle)
			)
			(primitives
				(gr_poly
					(pts
						(xy 0 -0.9017) (xy -0.03175 -0.89916) (xy -0.0635 -0.889) (xy -0.09144 -0.87376) (xy -0.11684 -0.85344)
						(xy -0.13716 -0.82804) (xy -0.1524 -0.8001) (xy -0.16256 -0.76835) (xy -0.1651 -0.7366) (xy -0.1651 -0.11938)
						(xy -0.17272 -0.11176) (xy -0.19812 -0.0762) (xy -0.2032 -0.06604) (xy -0.20701 -0.05715) (xy -0.21209 -0.04699)
						(xy -0.2159 -0.03683) (xy -0.21844 -0.02667) (xy -0.22225 -0.01524) (xy -0.22352 -0.00508) (xy -0.22606 0.00508)
						(xy -0.22733 0.01651) (xy -0.22733 0.02667) (xy -0.2286 0.0381) (xy -0.22733 0.04953) (xy -0.22733 0.05969)
						(xy -0.22606 0.07112) (xy -0.22352 0.08128) (xy -0.22225 0.09144) (xy -0.21844 0.10287) (xy -0.2159 0.11303)
						(xy -0.21209 0.12319) (xy -0.20701 0.13335) (xy -0.2032 0.14224) (xy -0.19812 0.1524) (xy -0.17272 0.18796)
						(xy -0.1651 0.19558) (xy -0.1651 0.7366) (xy -0.16256 0.76835) (xy -0.1524 0.8001) (xy -0.13716 0.82804)
						(xy -0.11684 0.85344) (xy -0.09144 0.87376) (xy -0.0635 0.889) (xy -0.03175 0.89916) (xy 0 0.9017)
						(xy 0.03175 0.89916) (xy 0.0635 0.889) (xy 0.09144 0.87376) (xy 0.11684 0.85344) (xy 0.13716 0.82804)
						(xy 0.1524 0.8001) (xy 0.16256 0.76835) (xy 0.1651 0.7366) (xy 0.1651 0.19685) (xy 0.17272 0.18923)
						(xy 0.17907 0.18034) (xy 0.18669 0.17145) (xy 0.19177 0.16256) (xy 0.19812 0.15367) (xy 0.20828 0.13335)
						(xy 0.21971 0.10287) (xy 0.22225 0.09271) (xy 0.22479 0.08128) (xy 0.22606 0.07112) (xy 0.2286 0.05969)
						(xy 0.2286 0.01651) (xy 0.22606 0.00508) (xy 0.22479 -0.00508) (xy 0.22225 -0.01651) (xy 0.21971 -0.02667)
						(xy 0.20828 -0.05715) (xy 0.19812 -0.07747) (xy 0.19177 -0.08636) (xy 0.18669 -0.09525) (xy 0.17907 -0.10414)
						(xy 0.17272 -0.11303) (xy 0.1651 -0.12065) (xy 0.1651 -0.7366) (xy 0.16256 -0.76835) (xy 0.1524 -0.8001)
						(xy 0.13716 -0.82804) (xy 0.11684 -0.85344) (xy 0.09144 -0.87376) (xy 0.0635 -0.889) (xy 0.03175 -0.89916)
					)
					(width 0)
					(fill yes)
				)
			)
		)
		(pad "205" smd rect
			(at 37.450014 -11.999976)
			(size 4.4958 4.5974)
			(layers "B.Cu" "B.Mask" "B.Paste")
			(net "GND")
		)
		(pad "206" smd rect
			(at 32.800036 -11.999976)
			(size 3.5052 4.5974)
			(layers "B.Cu" "B.Mask" "B.Paste")
			(net "GND")
		)
		(pad "207" smd rect
			(at -32.800036 -11.999976)
			(size 3.5052 4.5974)
			(layers "B.Cu" "B.Mask" "B.Paste")
			(net "GND")
		)
		(pad "208" smd rect
			(at -37.450014 -11.999976)
			(size 4.4958 4.5974)
			(layers "B.Cu" "B.Mask" "B.Paste")
			(net "GND")
		)
		(zone
			(layers "F.Cu" "B.Cu" "In1.Cu" "In2.Cu" "In3.Cu" "In4.Cu" "In5.Cu" "In6.Cu"
				"In7.Cu" "In8.Cu" "In9.Cu" "In10.Cu"
			)
			(hatch none 0.5)
			(connect_pads
				(clearance 0)
			)
			(min_thickness 0.25)
			(keepout
				(tracks not_allowed)
				(vias allowed)
				(pads allowed)
				(copperpour not_allowed)
				(footprints allowed)
			)
			(placement
				(enabled no)
				(sheetname "")
			)
			(fill
				(thermal_gap 0.5)
				(thermal_bridge_width 0.5)
				(island_removal_mode 0)
			)
			(polygon
				(pts
					(arc
						(start 125.96368 -66.699892)
						(mid 124.23648 -66.699892)
						(end 125.96368 -66.699892)
					)
				)
			)
		)
		(zone
			(layers "F.Cu" "B.Cu" "In1.Cu" "In2.Cu" "In3.Cu" "In4.Cu" "In5.Cu" "In6.Cu"
				"In7.Cu" "In8.Cu" "In9.Cu" "In10.Cu"
			)
			(hatch none 0.5)
			(connect_pads
				(clearance 0)
			)
			(min_thickness 0.25)
			(keepout
				(tracks not_allowed)
				(vias allowed)
				(pads allowed)
				(copperpour not_allowed)
				(footprints allowed)
			)
			(placement
				(enabled no)
				(sheetname "")
			)
			(fill
				(thermal_gap 0.5)
				(thermal_bridge_width 0.5)
				(island_removal_mode 0)
			)
			(polygon
				(pts
					(arc
						(start 193.004948 -66.699892)
						(mid 190.795148 -66.699892)
						(end 193.004948 -66.699892)
					)
				)
			)
		)
		(zone
			(layer "B.Cu")
			(hatch none 0.5)
			(connect_pads
				(clearance 0)
			)
			(min_thickness 0.25)
			(keepout
				(tracks allowed)
				(vias not_allowed)
				(pads allowed)
				(copperpour not_allowed)
				(footprints allowed)
			)
			(placement
				(enabled no)
				(sheetname "")
			)
			(fill
				(thermal_gap 0.5)
				(thermal_bridge_width 0.5)
				(island_removal_mode 0)
			)
			(polygon
				(pts
					(xy 166.078662 -69.59346) (xy 126.62154 -69.59346) (xy 126.62154 -69.89826) (xy 166.078662 -69.89826)
				)
			)
		)
		(zone
			(layer "B.Cu")
			(hatch none 0.5)
			(connect_pads
				(clearance 0)
			)
			(min_thickness 0.25)
			(keepout
				(tracks allowed)
				(vias not_allowed)
				(pads allowed)
				(copperpour not_allowed)
				(footprints allowed)
			)
			(placement
				(enabled no)
				(sheetname "")
			)
			(fill
				(thermal_gap 0.5)
				(thermal_bridge_width 0.5)
				(island_removal_mode 0)
			)
			(polygon
				(pts
					(xy 166.378636 -63.501524) (xy 126.921514 -63.501524) (xy 126.921514 -63.806324) (xy 166.378636 -63.806324)
				)
			)
		)
		(zone
			(layer "B.Cu")
			(hatch none 0.5)
			(connect_pads
				(clearance 0)
			)
			(min_thickness 0.25)
			(keepout
				(tracks allowed)
				(vias not_allowed)
				(pads allowed)
				(copperpour not_allowed)
				(footprints allowed)
			)
			(placement
				(enabled no)
				(sheetname "")
			)
			(fill
				(thermal_gap 0.5)
				(thermal_bridge_width 0.5)
				(island_removal_mode 0)
			)
			(polygon
				(pts
					(xy 168.621456 -69.89826) (xy 168.621456 -69.59346) (xy 190.078614 -69.59346) (xy 190.078614 -69.89826)
				)
			)
		)
		(zone
			(layer "B.Cu")
			(hatch none 0.5)
			(connect_pads
				(clearance 0)
			)
			(min_thickness 0.25)
			(keepout
				(tracks allowed)
				(vias not_allowed)
				(pads allowed)
				(copperpour not_allowed)
				(footprints allowed)
			)
			(placement
				(enabled no)
				(sheetname "")
			)
			(fill
				(thermal_gap 0.5)
				(thermal_bridge_width 0.5)
				(island_removal_mode 0)
			)
			(polygon
				(pts
					(xy 190.378588 -63.501524) (xy 190.378588 -63.806324) (xy 168.92143 -63.806324) (xy 168.92143 -63.501524)
				)
			)
		)
	)
	(footprint ""
		(layer "B.Cu")
		(at 68.072 -13.589)
		(property "Reference" "C281"
			(at 0 0 0)
			(layer "B.SilkS")
			(hide yes)
			(effects
				(font
					(size 1.27 1.27)
				)
				(justify mirror)
			)
		)
		(property "Value" "SCD1U16V2KX-3GP"
			(at -1.1811 -2.7051 0)
			(unlocked yes)
			(layer "B.Fab")
			(hide yes)
			(effects
				(font
					(size 1.016 1.016)
					(thickness 0.1524)
				)
				(justify mirror)
			)
		)
		(property "Device Type" "C402H22"
			(at -1.1811 -4.2291 0)
			(unlocked yes)
			(layer "B.Fab")
			(hide yes)
			(effects
				(font
					(size 1.016 1.016)
					(thickness 0.1524)
				)
				(justify mirror)
			)
		)
		(duplicate_pad_numbers_are_jumpers no)
		(fp_rect
			(start 0.381 0.7366)
			(end -0.381 -0.7366)
			(stroke
				(width 0)
				(type default)
			)
			(fill no)
			(layer "B.CrtYd")
		)
		(fp_rect
			(start 0.381 0.7366)
			(end -0.381 -0.7366)
			(stroke
				(width 0)
				(type default)
			)
			(fill no)
			(layer "B.Fab")
		)
		(pad "1" smd custom
			(at 0 -0.4572 180)
			(size 0.1143 0.1143)
			(layers "B.Cu" "B.Mask" "B.Paste")
			(net "P2E_CPU_SAS_C_TX_DN3")
			(options
				(clearance outline)
				(anchor circle)
			)
			(primitives
				(gr_poly
					(pts
						(arc
							(start -0.254 0.1778)
							(mid -0.239121 0.213721)
							(end -0.2032 0.2286)
						)
						(arc
							(start 0.2032 0.2286)
							(mid 0.239121 0.213721)
							(end 0.254 0.1778)
						)
						(arc
							(start 0.254 -0.1778)
							(mid 0.239121 -0.213721)
							(end 0.2032 -0.2286)
						)
						(arc
							(start -0.2032 -0.2286)
							(mid -0.239121 -0.213721)
							(end -0.254 -0.1778)
						)
					)
					(width 0)
					(fill yes)
				)
			)
		)
		(pad "2" smd custom
			(at 0 0.4572 180)
			(size 0.1143 0.1143)
			(layers "B.Cu" "B.Mask" "B.Paste")
			(net "P2E_CPU_SAS_TX_DN3")
			(options
				(clearance outline)
				(anchor circle)
			)
			(primitives
				(gr_poly
					(pts
						(arc
							(start -0.254 0.1778)
							(mid -0.239121 0.213721)
							(end -0.2032 0.2286)
						)
						(arc
							(start 0.2032 0.2286)
							(mid 0.239121 0.213721)
							(end 0.254 0.1778)
						)
						(arc
							(start 0.254 -0.1778)
							(mid 0.239121 -0.213721)
							(end 0.2032 -0.2286)
						)
						(arc
							(start -0.2032 -0.2286)
							(mid -0.239121 -0.213721)
							(end -0.254 -0.1778)
						)
					)
					(width 0)
					(fill yes)
				)
			)
		)
	)
	(footprint ""
		(layer "B.Cu")
		(at 70.7644 -37.4904 180)
		(property "Reference" "PR129"
			(at 0 0 0)
			(layer "B.SilkS")
			(hide yes)
			(effects
				(font
					(size 1.27 1.27)
				)
				(justify mirror)
			)
		)
		(property "Value" "0R2J-2-GP"
			(at -0.064008 -3.993896 180)
			(unlocked yes)
			(layer "B.Fab")
			(hide yes)
			(effects
				(font
					(size 1.016 1.016)
					(thickness 0.1524)
				)
				(justify mirror)
			)
		)
		(property "Device Type" "R402H16"
			(at -0.064008 -5.517896 180)
			(unlocked yes)
			(layer "B.Fab")
			(hide yes)
			(effects
				(font
					(size 1.016 1.016)
					(thickness 0.1524)
				)
				(justify mirror)
			)
		)
		(duplicate_pad_numbers_are_jumpers no)
		(fp_rect
			(start 0.381 0.8382)
			(end -0.381 -0.8382)
			(stroke
				(width 0)
				(type default)
			)
			(fill no)
			(layer "B.CrtYd")
		)
		(fp_rect
			(start 0.381 0.8382)
			(end -0.381 -0.8382)
			(stroke
				(width 0)
				(type default)
			)
			(fill no)
			(layer "B.Fab")
		)
		(pad "1" smd custom
			(at 0 -0.4318)
			(size 0.127 0.127)
			(layers "B.Cu" "B.Mask" "B.Paste")
			(net "PMU_SLP_S3#")
			(options
				(clearance outline)
				(anchor circle)
			)
			(primitives
				(gr_poly
					(pts
						(arc
							(start -0.2032 0.2794)
							(mid -0.239121 0.264521)
							(end -0.254 0.2286)
						)
						(arc
							(start -0.254 -0.2286)
							(mid -0.239121 -0.264521)
							(end -0.2032 -0.2794)
						)
						(arc
							(start 0.2032 -0.2794)
							(mid 0.239121 -0.264521)
							(end 0.254 -0.2286)
						)
						(arc
							(start 0.254 0.2286)
							(mid 0.239121 0.264521)
							(end 0.2032 0.2794)
						)
					)
					(width 0)
					(fill yes)
				)
			)
		)
		(pad "2" smd custom
			(at 0 0.4318)
			(size 0.127 0.127)
			(layers "B.Cu" "B.Mask" "B.Paste")
			(net "PMU_SLP_INB_S3#")
			(options
				(clearance outline)
				(anchor circle)
			)
			(primitives
				(gr_poly
					(pts
						(arc
							(start -0.2032 0.2794)
							(mid -0.239121 0.264521)
							(end -0.254 0.2286)
						)
						(arc
							(start -0.254 -0.2286)
							(mid -0.239121 -0.264521)
							(end -0.2032 -0.2794)
						)
						(arc
							(start 0.2032 -0.2794)
							(mid 0.239121 -0.264521)
							(end 0.254 -0.2286)
						)
						(arc
							(start 0.254 0.2286)
							(mid 0.239121 0.264521)
							(end 0.2032 0.2794)
						)
					)
					(width 0)
					(fill yes)
				)
			)
		)
	)
	(footprint ""
		(layer "B.Cu")
		(at 109.22 -21.59 90)
		(property "Reference" "C260"
			(at 0 0 90)
			(layer "B.SilkS")
			(hide yes)
			(effects
				(font
					(size 1.27 1.27)
				)
				(justify mirror)
			)
		)
		(property "Value" "SC22U6D3V5MX-2GP"
			(at 0.0762 -6.1214 90)
			(unlocked yes)
			(layer "B.Fab")
			(hide yes)
			(effects
				(font
					(size 1.016 1.016)
					(thickness 0.1524)
				)
				(justify mirror)
			)
		)
		(property "Device Type" "C805H58"
			(at 0.0762 -8.1534 90)
			(unlocked yes)
			(layer "B.Fab")
			(hide yes)
			(effects
				(font
					(size 1.016 1.016)
					(thickness 0.1524)
				)
				(justify mirror)
			)
		)
		(duplicate_pad_numbers_are_jumpers no)
		(fp_line
			(start -0.6096 0)
			(end 0.6096 0)
			(stroke
				(width 0.3048)
				(type default)
			)
			(layer "B.SilkS")
		)
		(fp_poly
			(pts
				(xy 0.9017 1.4351) (xy -0.9017 1.4351) (xy -0.9017 -1.4351) (xy 0.9017 -1.4351)
			)
			(stroke
				(width 0)
				(type default)
			)
			(fill no)
			(layer "B.CrtYd")
		)
		(fp_poly
			(pts
				(xy -0.9017 1.4351) (xy -0.9017 -1.4351) (xy 0.9017 -1.4351) (xy 0.9017 1.4351)
			)
			(stroke
				(width 0)
				(type default)
			)
			(fill no)
			(layer "B.Fab")
		)
		(pad "1" smd rect
			(at 0 -0.8382 270)
			(size 1.5494 0.9398)
			(layers "B.Cu" "B.Mask" "B.Paste")
			(net "PV_VDDR")
		)
		(pad "2" smd rect
			(at 0 0.8382 270)
			(size 1.5494 0.9398)
			(layers "B.Cu" "B.Mask" "B.Paste")
			(net "GND")
		)
	)
	(footprint ""
		(layer "B.Cu")
		(at 88.519 -24.003 -90)
		(property "Reference" "C261"
			(at 0 0 90)
			(layer "B.SilkS")
			(hide yes)
			(effects
				(font
					(size 1.27 1.27)
				)
				(justify mirror)
			)
		)
		(property "Value" "SC1U10V2KX-1GP"
			(at -1.1811 -2.7051 270)
			(unlocked yes)
			(layer "B.Fab")
			(hide yes)
			(effects
				(font
					(size 1.016 1.016)
					(thickness 0.1524)
				)
				(justify mirror)
			)
		)
		(property "Device Type" "C402H22"
			(at -1.1811 -4.2291 270)
			(unlocked yes)
			(layer "B.Fab")
			(hide yes)
			(effects
				(font
					(size 1.016 1.016)
					(thickness 0.1524)
				)
				(justify mirror)
			)
		)
		(duplicate_pad_numbers_are_jumpers no)
		(fp_rect
			(start 0.381 0.7366)
			(end -0.381 -0.7366)
			(stroke
				(width 0)
				(type default)
			)
			(fill no)
			(layer "B.CrtYd")
		)
		(fp_rect
			(start 0.381 0.7366)
			(end -0.381 -0.7366)
			(stroke
				(width 0)
				(type default)
			)
			(fill no)
			(layer "B.Fab")
		)
		(pad "1" smd custom
			(at 0 -0.4572 90)
			(size 0.1143 0.1143)
			(layers "B.Cu" "B.Mask" "B.Paste")
			(net "P1V0")
			(options
				(clearance outline)
				(anchor circle)
			)
			(primitives
				(gr_poly
					(pts
						(arc
							(start -0.254 0.1778)
							(mid -0.239121 0.213721)
							(end -0.2032 0.2286)
						)
						(arc
							(start 0.2032 0.2286)
							(mid 0.239121 0.213721)
							(end 0.254 0.1778)
						)
						(arc
							(start 0.254 -0.1778)
							(mid 0.239121 -0.213721)
							(end 0.2032 -0.2286)
						)
						(arc
							(start -0.2032 -0.2286)
							(mid -0.239121 -0.213721)
							(end -0.254 -0.1778)
						)
					)
					(width 0)
					(fill yes)
				)
			)
		)
		(pad "2" smd custom
			(at 0 0.4572 90)
			(size 0.1143 0.1143)
			(layers "B.Cu" "B.Mask" "B.Paste")
			(net "GND")
			(options
				(clearance outline)
				(anchor circle)
			)
			(primitives
				(gr_poly
					(pts
						(arc
							(start -0.254 0.1778)
							(mid -0.239121 0.213721)
							(end -0.2032 0.2286)
						)
						(arc
							(start 0.2032 0.2286)
							(mid 0.239121 0.213721)
							(end 0.254 0.1778)
						)
						(arc
							(start 0.254 -0.1778)
							(mid 0.239121 -0.213721)
							(end 0.2032 -0.2286)
						)
						(arc
							(start -0.2032 -0.2286)
							(mid -0.239121 -0.213721)
							(end -0.254 -0.1778)
						)
					)
					(width 0)
					(fill yes)
				)
			)
		)
	)
	(footprint ""
		(layer "B.Cu")
		(at 24.765 -49.022 90)
		(property "Reference" "PR179"
			(at 0 0 90)
			(layer "B.SilkS")
			(hide yes)
			(effects
				(font
					(size 1.27 1.27)
				)
				(justify mirror)
			)
		)
		(property "Value" "0R3J-6-GP"
			(at 0.0254 -2.0193 90)
			(unlocked yes)
			(layer "B.Fab")
			(hide yes)
			(effects
				(font
					(size 1.016 1.016)
					(thickness 0.1524)
				)
				(justify mirror)
			)
		)
		(property "Device Type" "R603H22"
			(at 0.0254 -3.5433 90)
			(unlocked yes)
			(layer "B.Fab")
			(hide yes)
			(effects
				(font
					(size 1.016 1.016)
					(thickness 0.1524)
				)
				(justify mirror)
			)
		)
		(duplicate_pad_numbers_are_jumpers no)
		(fp_line
			(start 0.2032 0)
			(end 0.4191 0)
			(stroke
				(width 0.2032)
				(type default)
			)
			(layer "B.SilkS")
		)
		(fp_line
			(start -0.4318 0)
			(end -0.2032 0)
			(stroke
				(width 0.2032)
				(type default)
			)
			(layer "B.SilkS")
		)
		(fp_rect
			(start 0.635 1.1811)
			(end -0.635 -1.1811)
			(stroke
				(width 0)
				(type default)
			)
			(fill no)
			(layer "B.CrtYd")
		)
		(fp_rect
			(start 0.635 1.1811)
			(end -0.635 -1.1811)
			(stroke
				(width 0)
				(type default)
			)
			(fill no)
			(layer "B.Fab")
		)
		(pad "1" smd custom
			(at 0 -0.6604 270)
			(size 0.19685 0.19685)
			(layers "B.Cu" "B.Mask" "B.Paste")
			(net "P1V8_STBY")
			(options
				(clearance outline)
				(anchor circle)
			)
			(primitives
				(gr_poly
					(pts
						(arc
							(start 0.508 0.2921)
							(mid 0.478242 0.363942)
							(end 0.4064 0.3937)
						)
						(arc
							(start -0.4064 0.3937)
							(mid -0.478242 0.363942)
							(end -0.508 0.2921)
						)
						(arc
							(start -0.508 -0.2921)
							(mid -0.478242 -0.363942)
							(end -0.4064 -0.3937)
						)
						(arc
							(start 0.4064 -0.3937)
							(mid 0.478242 -0.363942)
							(end 0.508 -0.2921)
						)
					)
					(width 0)
					(fill yes)
				)
			)
		)
		(pad "2" smd custom
			(at 0 0.6604 270)
			(size 0.19685 0.19685)
			(layers "B.Cu" "B.Mask" "B.Paste")
			(net "P1V5_STBY_IN")
			(options
				(clearance outline)
				(anchor circle)
			)
			(primitives
				(gr_poly
					(pts
						(arc
							(start 0.508 0.2921)
							(mid 0.478242 0.363942)
							(end 0.4064 0.3937)
						)
						(arc
							(start -0.4064 0.3937)
							(mid -0.478242 0.363942)
							(end -0.508 0.2921)
						)
						(arc
							(start -0.508 -0.2921)
							(mid -0.478242 -0.363942)
							(end -0.4064 -0.3937)
						)
						(arc
							(start 0.4064 -0.3937)
							(mid 0.478242 -0.363942)
							(end 0.508 -0.2921)
						)
					)
					(width 0)
					(fill yes)
				)
			)
		)
	)
	(footprint ""
		(layer "B.Cu")
		(at 94.234 -44.6151 90)
		(property "Reference" "L6"
			(at 0 0 90)
			(layer "B.SilkS")
			(hide yes)
			(effects
				(font
					(size 1.27 1.27)
				)
				(justify mirror)
			)
		)
		(property "Value" "BLM18PG121SN1D-GP"
			(at 0.0254 -2.8956 90)
			(unlocked yes)
			(layer "B.Fab")
			(hide yes)
			(effects
				(font
					(size 1.016 1.016)
					(thickness 0.1524)
				)
				(justify mirror)
			)
		)
		(property "Device Type" "L1608-UH38"
			(at 0.0254 -4.4196 90)
			(unlocked yes)
			(layer "B.Fab")
			(hide yes)
			(effects
				(font
					(size 1.016 1.016)
					(thickness 0.1524)
				)
				(justify mirror)
			)
		)
		(duplicate_pad_numbers_are_jumpers no)
		(fp_line
			(start 0.4064 0)
			(end -0.4064 0)
			(stroke
				(width 0.2032)
				(type default)
			)
			(layer "B.SilkS")
		)
		(fp_rect
			(start 0.635 1.1811)
			(end -0.635 -1.1811)
			(stroke
				(width 0)
				(type default)
			)
			(fill no)
			(layer "B.CrtYd")
		)
		(fp_rect
			(start 0.635 1.1811)
			(end -0.635 -1.1811)
			(stroke
				(width 0)
				(type default)
			)
			(fill no)
			(layer "B.Fab")
		)
		(pad "1" smd custom
			(at 0 -0.6604 270)
			(size 0.19685 0.19685)
			(layers "B.Cu" "B.Mask" "B.Paste")
			(net "P1V0")
			(options
				(clearance outline)
				(anchor circle)
			)
			(primitives
				(gr_poly
					(pts
						(arc
							(start 0.508 0.2921)
							(mid 0.478242 0.363942)
							(end 0.4064 0.3937)
						)
						(arc
							(start -0.4064 0.3937)
							(mid -0.478242 0.363942)
							(end -0.508 0.2921)
						)
						(arc
							(start -0.508 -0.2921)
							(mid -0.478242 -0.363942)
							(end -0.4064 -0.3937)
						)
						(arc
							(start 0.4064 -0.3937)
							(mid 0.478242 -0.363942)
							(end 0.508 -0.2921)
						)
					)
					(width 0)
					(fill yes)
				)
			)
		)
		(pad "2" smd custom
			(at 0 0.6604 270)
			(size 0.19685 0.19685)
			(layers "B.Cu" "B.Mask" "B.Paste")
			(net "VCCA_PLLDDR0_AVN")
			(options
				(clearance outline)
				(anchor circle)
			)
			(primitives
				(gr_poly
					(pts
						(arc
							(start 0.508 0.2921)
							(mid 0.478242 0.363942)
							(end 0.4064 0.3937)
						)
						(arc
							(start -0.4064 0.3937)
							(mid -0.478242 0.363942)
							(end -0.508 0.2921)
						)
						(arc
							(start -0.508 -0.2921)
							(mid -0.478242 -0.363942)
							(end -0.4064 -0.3937)
						)
						(arc
							(start 0.4064 -0.3937)
							(mid 0.478242 -0.363942)
							(end 0.508 -0.2921)
						)
					)
					(width 0)
					(fill yes)
				)
			)
		)
	)
	(footprint ""
		(layer "B.Cu")
		(at 15.875 -63.881 90)
		(property "Reference" "C31"
			(at 0 0 90)
			(layer "B.SilkS")
			(hide yes)
			(effects
				(font
					(size 1.27 1.27)
				)
				(justify mirror)
			)
		)
		(property "Value" "SC1U6D3V2KX-GP"
			(at -1.8923 -1.2065 90)
			(unlocked yes)
			(layer "B.Fab")
			(hide yes)
			(effects
				(font
					(size 1.016 1.016)
					(thickness 0.1524)
				)
				(justify mirror)
			)
		)
		(property "Device Type" "C402H22"
			(at -1.8923 -2.7305 90)
			(unlocked yes)
			(layer "B.Fab")
			(hide yes)
			(effects
				(font
					(size 1.016 1.016)
					(thickness 0.1524)
				)
				(justify mirror)
			)
		)
		(duplicate_pad_numbers_are_jumpers no)
		(fp_rect
			(start 0.381 0.7366)
			(end -0.381 -0.7366)
			(stroke
				(width 0)
				(type default)
			)
			(fill no)
			(layer "B.CrtYd")
		)
		(fp_rect
			(start 0.381 0.7366)
			(end -0.381 -0.7366)
			(stroke
				(width 0)
				(type default)
			)
			(fill no)
			(layer "B.Fab")
		)
		(pad "1" smd custom
			(at 0 -0.4572 270)
			(size 0.1143 0.1143)
			(layers "B.Cu" "B.Mask" "B.Paste")
			(net "P3V3")
			(options
				(clearance outline)
				(anchor circle)
			)
			(primitives
				(gr_poly
					(pts
						(arc
							(start -0.254 0.1778)
							(mid -0.239121 0.213721)
							(end -0.2032 0.2286)
						)
						(arc
							(start 0.2032 0.2286)
							(mid 0.239121 0.213721)
							(end 0.254 0.1778)
						)
						(arc
							(start 0.254 -0.1778)
							(mid 0.239121 -0.213721)
							(end 0.2032 -0.2286)
						)
						(arc
							(start -0.2032 -0.2286)
							(mid -0.239121 -0.213721)
							(end -0.254 -0.1778)
						)
					)
					(width 0)
					(fill yes)
				)
			)
		)
		(pad "2" smd custom
			(at 0 0.4572 270)
			(size 0.1143 0.1143)
			(layers "B.Cu" "B.Mask" "B.Paste")
			(net "GND")
			(options
				(clearance outline)
				(anchor circle)
			)
			(primitives
				(gr_poly
					(pts
						(arc
							(start -0.254 0.1778)
							(mid -0.239121 0.213721)
							(end -0.2032 0.2286)
						)
						(arc
							(start 0.2032 0.2286)
							(mid 0.239121 0.213721)
							(end 0.254 0.1778)
						)
						(arc
							(start 0.254 -0.1778)
							(mid 0.239121 -0.213721)
							(end 0.2032 -0.2286)
						)
						(arc
							(start -0.2032 -0.2286)
							(mid -0.239121 -0.213721)
							(end -0.254 -0.1778)
						)
					)
					(width 0)
					(fill yes)
				)
			)
		)
	)
	(footprint ""
		(layer "B.Cu")
		(at 197.739 -2.9718 90)
		(property "Reference" "C288"
			(at 0 0 90)
			(layer "B.SilkS")
			(hide yes)
			(effects
				(font
					(size 1.27 1.27)
				)
				(justify mirror)
			)
		)
		(property "Value" "SC10U6D3V3MX-GP"
			(at 0 -2.8194 90)
			(unlocked yes)
			(layer "B.Fab")
			(hide yes)
			(effects
				(font
					(size 1.016 1.016)
					(thickness 0.1524)
				)
				(justify mirror)
			)
		)
		(property "Device Type" "C603H38"
			(at 0 -4.3434 90)
			(unlocked yes)
			(layer "B.Fab")
			(hide yes)
			(effects
				(font
					(size 1.016 1.016)
					(thickness 0.1524)
				)
				(justify mirror)
			)
		)
		(duplicate_pad_numbers_are_jumpers no)
		(fp_line
			(start 0.4064 0)
			(end -0.4064 0)
			(stroke
				(width 0.2286)
				(type default)
			)
			(layer "B.SilkS")
		)
		(fp_rect
			(start 0.635 1.1811)
			(end -0.635 -1.1811)
			(stroke
				(width 0)
				(type default)
			)
			(fill no)
			(layer "B.CrtYd")
		)
		(fp_rect
			(start 0.635 1.1811)
			(end -0.635 -1.1811)
			(stroke
				(width 0)
				(type default)
			)
			(fill no)
			(layer "B.Fab")
		)
		(pad "1" smd custom
			(at 0 -0.6604 270)
			(size 0.19685 0.19685)
			(layers "B.Cu" "B.Mask" "B.Paste")
			(net "PV_VTT_DDR_B")
			(options
				(clearance outline)
				(anchor circle)
			)
			(primitives
				(gr_poly
					(pts
						(arc
							(start 0.508 0.2921)
							(mid 0.478242 0.363942)
							(end 0.4064 0.3937)
						)
						(arc
							(start -0.4064 0.3937)
							(mid -0.478242 0.363942)
							(end -0.508 0.2921)
						)
						(arc
							(start -0.508 -0.2921)
							(mid -0.478242 -0.363942)
							(end -0.4064 -0.3937)
						)
						(arc
							(start 0.4064 -0.3937)
							(mid 0.478242 -0.363942)
							(end 0.508 -0.2921)
						)
					)
					(width 0)
					(fill yes)
				)
			)
		)
		(pad "2" smd custom
			(at 0 0.6604 270)
			(size 0.19685 0.19685)
			(layers "B.Cu" "B.Mask" "B.Paste")
			(net "GND")
			(options
				(clearance outline)
				(anchor circle)
			)
			(primitives
				(gr_poly
					(pts
						(arc
							(start 0.508 0.2921)
							(mid 0.478242 0.363942)
							(end 0.4064 0.3937)
						)
						(arc
							(start -0.4064 0.3937)
							(mid -0.478242 0.363942)
							(end -0.508 0.2921)
						)
						(arc
							(start -0.508 -0.2921)
							(mid -0.478242 -0.363942)
							(end -0.4064 -0.3937)
						)
						(arc
							(start 0.4064 -0.3937)
							(mid 0.478242 -0.363942)
							(end 0.508 -0.2921)
						)
					)
					(width 0)
					(fill yes)
				)
			)
		)
	)
	(footprint ""
		(layer "B.Cu")
		(at 46.8884 -28.321 180)
		(property "Reference" "R447"
			(at 0 0 0)
			(layer "B.SilkS")
			(hide yes)
			(effects
				(font
					(size 1.27 1.27)
				)
				(justify mirror)
			)
		)
		(property "Value" "4K7R2F-GP"
			(at -1.7907 -1.1176 180)
			(unlocked yes)
			(layer "B.Fab")
			(hide yes)
			(effects
				(font
					(size 1.016 1.016)
					(thickness 0.1524)
				)
				(justify mirror)
			)
		)
		(property "Device Type" "R402H16"
			(at -1.7907 -2.6416 180)
			(unlocked yes)
			(layer "B.Fab")
			(hide yes)
			(effects
				(font
					(size 1.016 1.016)
					(thickness 0.1524)
				)
				(justify mirror)
			)
		)
		(duplicate_pad_numbers_are_jumpers no)
		(fp_rect
			(start 0.381 0.8382)
			(end -0.381 -0.8382)
			(stroke
				(width 0)
				(type default)
			)
			(fill no)
			(layer "B.CrtYd")
		)
		(fp_rect
			(start 0.381 0.8382)
			(end -0.381 -0.8382)
			(stroke
				(width 0)
				(type default)
			)
			(fill no)
			(layer "B.Fab")
		)
		(pad "1" smd custom
			(at 0 -0.4318)
			(size 0.127 0.127)
			(layers "B.Cu" "B.Mask" "B.Paste")
			(net "CLKBUFF_OE6#")
			(options
				(clearance outline)
				(anchor circle)
			)
			(primitives
				(gr_poly
					(pts
						(arc
							(start -0.2032 0.2794)
							(mid -0.239121 0.264521)
							(end -0.254 0.2286)
						)
						(arc
							(start -0.254 -0.2286)
							(mid -0.239121 -0.264521)
							(end -0.2032 -0.2794)
						)
						(arc
							(start 0.2032 -0.2794)
							(mid 0.239121 -0.264521)
							(end 0.254 -0.2286)
						)
						(arc
							(start 0.254 0.2286)
							(mid 0.239121 0.264521)
							(end 0.2032 0.2794)
						)
					)
					(width 0)
					(fill yes)
				)
			)
		)
		(pad "2" smd custom
			(at 0 0.4318)
			(size 0.127 0.127)
			(layers "B.Cu" "B.Mask" "B.Paste")
			(net "GND")
			(options
				(clearance outline)
				(anchor circle)
			)
			(primitives
				(gr_poly
					(pts
						(arc
							(start -0.2032 0.2794)
							(mid -0.239121 0.264521)
							(end -0.254 0.2286)
						)
						(arc
							(start -0.254 -0.2286)
							(mid -0.239121 -0.264521)
							(end -0.2032 -0.2794)
						)
						(arc
							(start 0.2032 -0.2794)
							(mid 0.239121 -0.264521)
							(end 0.254 -0.2286)
						)
						(arc
							(start 0.254 0.2286)
							(mid 0.239121 0.264521)
							(end 0.2032 0.2794)
						)
					)
					(width 0)
					(fill yes)
				)
			)
		)
	)
	(footprint ""
		(layer "B.Cu")
		(at 86.106 -20.701 -90)
		(property "Reference" "PR224"
			(at 0 0 90)
			(layer "B.SilkS")
			(hide yes)
			(effects
				(font
					(size 1.27 1.27)
				)
				(justify mirror)
			)
		)
		(property "Value" "3K3R2F-2-GP"
			(at -0.064008 -3.993896 270)
			(unlocked yes)
			(layer "B.Fab")
			(hide yes)
			(effects
				(font
					(size 1.016 1.016)
					(thickness 0.1524)
				)
				(justify mirror)
			)
		)
		(property "Device Type" "R402H16"
			(at -0.064008 -5.517896 270)
			(unlocked yes)
			(layer "B.Fab")
			(hide yes)
			(effects
				(font
					(size 1.016 1.016)
					(thickness 0.1524)
				)
				(justify mirror)
			)
		)
		(duplicate_pad_numbers_are_jumpers no)
		(fp_rect
			(start 0.381 0.8382)
			(end -0.381 -0.8382)
			(stroke
				(width 0)
				(type default)
			)
			(fill no)
			(layer "B.CrtYd")
		)
		(fp_rect
			(start 0.381 0.8382)
			(end -0.381 -0.8382)
			(stroke
				(width 0)
				(type default)
			)
			(fill no)
			(layer "B.Fab")
		)
		(pad "1" smd custom
			(at 0 -0.4318 90)
			(size 0.127 0.127)
			(layers "B.Cu" "B.Mask" "B.Paste")
			(net "TPS74801_1V35_OUT")
			(options
				(clearance outline)
				(anchor circle)
			)
			(primitives
				(gr_poly
					(pts
						(arc
							(start -0.2032 0.2794)
							(mid -0.239121 0.264521)
							(end -0.254 0.2286)
						)
						(arc
							(start -0.254 -0.2286)
							(mid -0.239121 -0.264521)
							(end -0.2032 -0.2794)
						)
						(arc
							(start 0.2032 -0.2794)
							(mid 0.239121 -0.264521)
							(end 0.254 -0.2286)
						)
						(arc
							(start 0.254 0.2286)
							(mid 0.239121 0.264521)
							(end 0.2032 0.2794)
						)
					)
					(width 0)
					(fill yes)
				)
			)
		)
		(pad "2" smd custom
			(at 0 0.4318 90)
			(size 0.127 0.127)
			(layers "B.Cu" "B.Mask" "B.Paste")
			(net "TPS74801_1V35_FB")
			(options
				(clearance outline)
				(anchor circle)
			)
			(primitives
				(gr_poly
					(pts
						(arc
							(start -0.2032 0.2794)
							(mid -0.239121 0.264521)
							(end -0.254 0.2286)
						)
						(arc
							(start -0.254 -0.2286)
							(mid -0.239121 -0.264521)
							(end -0.2032 -0.2794)
						)
						(arc
							(start 0.2032 -0.2794)
							(mid 0.239121 -0.264521)
							(end 0.254 -0.2286)
						)
						(arc
							(start 0.254 0.2286)
							(mid 0.239121 0.264521)
							(end 0.2032 0.2794)
						)
					)
					(width 0)
					(fill yes)
				)
			)
		)
	)
	(footprint ""
		(layer "B.Cu")
		(at 75.565 -36.703 180)
		(property "Reference" "R376"
			(at 0 0 0)
			(layer "B.SilkS")
			(hide yes)
			(effects
				(font
					(size 1.27 1.27)
				)
				(justify mirror)
			)
		)
		(property "Value" "33R2F-3-GP"
			(at -0.064008 -3.993896 180)
			(unlocked yes)
			(layer "B.Fab")
			(hide yes)
			(effects
				(font
					(size 1.016 1.016)
					(thickness 0.1524)
				)
				(justify mirror)
			)
		)
		(property "Device Type" "R402H16"
			(at -0.064008 -5.517896 180)
			(unlocked yes)
			(layer "B.Fab")
			(hide yes)
			(effects
				(font
					(size 1.016 1.016)
					(thickness 0.1524)
				)
				(justify mirror)
			)
		)
		(duplicate_pad_numbers_are_jumpers no)
		(fp_rect
			(start 0.381 0.8382)
			(end -0.381 -0.8382)
			(stroke
				(width 0)
				(type default)
			)
			(fill no)
			(layer "B.CrtYd")
		)
		(fp_rect
			(start 0.381 0.8382)
			(end -0.381 -0.8382)
			(stroke
				(width 0)
				(type default)
			)
			(fill no)
			(layer "B.Fab")
		)
		(pad "1" smd custom
			(at 0 -0.4318)
			(size 0.127 0.127)
			(layers "B.Cu" "B.Mask" "B.Paste")
			(net "LPC_CPU_CLKOUT0")
			(options
				(clearance outline)
				(anchor circle)
			)
			(primitives
				(gr_poly
					(pts
						(arc
							(start -0.2032 0.2794)
							(mid -0.239121 0.264521)
							(end -0.254 0.2286)
						)
						(arc
							(start -0.254 -0.2286)
							(mid -0.239121 -0.264521)
							(end -0.2032 -0.2794)
						)
						(arc
							(start 0.2032 -0.2794)
							(mid 0.239121 -0.264521)
							(end 0.254 -0.2286)
						)
						(arc
							(start 0.254 0.2286)
							(mid 0.239121 0.264521)
							(end 0.2032 0.2794)
						)
					)
					(width 0)
					(fill yes)
				)
			)
		)
		(pad "2" smd custom
			(at 0 0.4318)
			(size 0.127 0.127)
			(layers "B.Cu" "B.Mask" "B.Paste")
			(net "LPC_CPU_R_CLKOUT0")
			(options
				(clearance outline)
				(anchor circle)
			)
			(primitives
				(gr_poly
					(pts
						(arc
							(start -0.2032 0.2794)
							(mid -0.239121 0.264521)
							(end -0.254 0.2286)
						)
						(arc
							(start -0.254 -0.2286)
							(mid -0.239121 -0.264521)
							(end -0.2032 -0.2794)
						)
						(arc
							(start 0.2032 -0.2794)
							(mid 0.239121 -0.264521)
							(end 0.254 -0.2286)
						)
						(arc
							(start 0.254 0.2286)
							(mid 0.239121 0.264521)
							(end 0.2032 0.2794)
						)
					)
					(width 0)
					(fill yes)
				)
			)
		)
	)
	(footprint ""
		(layer "B.Cu")
		(at 112.014 -35.941)
		(property "Reference" "C195"
			(at 0 0 0)
			(layer "B.SilkS")
			(hide yes)
			(effects
				(font
					(size 1.27 1.27)
				)
				(justify mirror)
			)
		)
		(property "Value" "SC1U10V2KX-1GP"
			(at -1.1811 -2.7051 0)
			(unlocked yes)
			(layer "B.Fab")
			(hide yes)
			(effects
				(font
					(size 1.016 1.016)
					(thickness 0.1524)
				)
				(justify mirror)
			)
		)
		(property "Device Type" "C402H22"
			(at -1.1811 -4.2291 0)
			(unlocked yes)
			(layer "B.Fab")
			(hide yes)
			(effects
				(font
					(size 1.016 1.016)
					(thickness 0.1524)
				)
				(justify mirror)
			)
		)
		(duplicate_pad_numbers_are_jumpers no)
		(fp_rect
			(start 0.381 0.7366)
			(end -0.381 -0.7366)
			(stroke
				(width 0)
				(type default)
			)
			(fill no)
			(layer "B.CrtYd")
		)
		(fp_rect
			(start 0.381 0.7366)
			(end -0.381 -0.7366)
			(stroke
				(width 0)
				(type default)
			)
			(fill no)
			(layer "B.Fab")
		)
		(pad "1" smd custom
			(at 0 -0.4572 180)
			(size 0.1143 0.1143)
			(layers "B.Cu" "B.Mask" "B.Paste")
			(net "PVCCP")
			(options
				(clearance outline)
				(anchor circle)
			)
			(primitives
				(gr_poly
					(pts
						(arc
							(start -0.254 0.1778)
							(mid -0.239121 0.213721)
							(end -0.2032 0.2286)
						)
						(arc
							(start 0.2032 0.2286)
							(mid 0.239121 0.213721)
							(end 0.254 0.1778)
						)
						(arc
							(start 0.254 -0.1778)
							(mid 0.239121 -0.213721)
							(end 0.2032 -0.2286)
						)
						(arc
							(start -0.2032 -0.2286)
							(mid -0.239121 -0.213721)
							(end -0.254 -0.1778)
						)
					)
					(width 0)
					(fill yes)
				)
			)
		)
		(pad "2" smd custom
			(at 0 0.4572 180)
			(size 0.1143 0.1143)
			(layers "B.Cu" "B.Mask" "B.Paste")
			(net "GND")
			(options
				(clearance outline)
				(anchor circle)
			)
			(primitives
				(gr_poly
					(pts
						(arc
							(start -0.254 0.1778)
							(mid -0.239121 0.213721)
							(end -0.2032 0.2286)
						)
						(arc
							(start 0.2032 0.2286)
							(mid 0.239121 0.213721)
							(end 0.254 0.1778)
						)
						(arc
							(start 0.254 -0.1778)
							(mid 0.239121 -0.213721)
							(end 0.2032 -0.2286)
						)
						(arc
							(start -0.2032 -0.2286)
							(mid -0.239121 -0.213721)
							(end -0.254 -0.1778)
						)
					)
					(width 0)
					(fill yes)
				)
			)
		)
	)
	(footprint ""
		(layer "B.Cu")
		(at 155.7528 -59.5884)
		(property "Reference" "C101"
			(at 0 0 0)
			(layer "B.SilkS")
			(hide yes)
			(effects
				(font
					(size 1.27 1.27)
				)
				(justify mirror)
			)
		)
		(property "Value" "SC1U10V2KX-1GP"
			(at -1.8923 -1.2065 0)
			(unlocked yes)
			(layer "B.Fab")
			(hide yes)
			(effects
				(font
					(size 1.016 1.016)
					(thickness 0.1524)
				)
				(justify mirror)
			)
		)
		(property "Device Type" "C402H22"
			(at -1.8923 -2.7305 0)
			(unlocked yes)
			(layer "B.Fab")
			(hide yes)
			(effects
				(font
					(size 1.016 1.016)
					(thickness 0.1524)
				)
				(justify mirror)
			)
		)
		(duplicate_pad_numbers_are_jumpers no)
		(fp_rect
			(start 0.381 0.7366)
			(end -0.381 -0.7366)
			(stroke
				(width 0)
				(type default)
			)
			(fill no)
			(layer "B.CrtYd")
		)
		(fp_rect
			(start 0.381 0.7366)
			(end -0.381 -0.7366)
			(stroke
				(width 0)
				(type default)
			)
			(fill no)
			(layer "B.Fab")
		)
		(pad "1" smd custom
			(at 0 -0.4572 180)
			(size 0.1143 0.1143)
			(layers "B.Cu" "B.Mask" "B.Paste")
			(net "PV_VDDR")
			(options
				(clearance outline)
				(anchor circle)
			)
			(primitives
				(gr_poly
					(pts
						(arc
							(start -0.254 0.1778)
							(mid -0.239121 0.213721)
							(end -0.2032 0.2286)
						)
						(arc
							(start 0.2032 0.2286)
							(mid 0.239121 0.213721)
							(end 0.254 0.1778)
						)
						(arc
							(start 0.254 -0.1778)
							(mid 0.239121 -0.213721)
							(end 0.2032 -0.2286)
						)
						(arc
							(start -0.2032 -0.2286)
							(mid -0.239121 -0.213721)
							(end -0.254 -0.1778)
						)
					)
					(width 0)
					(fill yes)
				)
			)
		)
		(pad "2" smd custom
			(at 0 0.4572 180)
			(size 0.1143 0.1143)
			(layers "B.Cu" "B.Mask" "B.Paste")
			(net "GND")
			(options
				(clearance outline)
				(anchor circle)
			)
			(primitives
				(gr_poly
					(pts
						(arc
							(start -0.254 0.1778)
							(mid -0.239121 0.213721)
							(end -0.2032 0.2286)
						)
						(arc
							(start 0.2032 0.2286)
							(mid 0.239121 0.213721)
							(end 0.254 0.1778)
						)
						(arc
							(start 0.254 -0.1778)
							(mid 0.239121 -0.213721)
							(end 0.2032 -0.2286)
						)
						(arc
							(start -0.2032 -0.2286)
							(mid -0.239121 -0.213721)
							(end -0.254 -0.1778)
						)
					)
					(width 0)
					(fill yes)
				)
			)
		)
	)
	(footprint ""
		(layer "B.Cu")
		(at 199.300084 -71.300086 -90)
		(property "Reference" "LED1"
			(at 0 0 90)
			(layer "B.SilkS")
			(hide yes)
			(effects
				(font
					(size 1.27 1.27)
				)
				(justify mirror)
			)
		)
		(property "Value" "LED-B-36-GP"
			(at 0.0635 -2.4765 270)
			(unlocked yes)
			(layer "B.Fab")
			(hide yes)
			(effects
				(font
					(size 1.016 1.016)
					(thickness 0.1524)
				)
				(justify mirror)
			)
		)
		(property "Device Type" "LED1608-1H32"
			(at 0.0635 -4.0005 270)
			(unlocked yes)
			(layer "B.Fab")
			(hide yes)
			(effects
				(font
					(size 1.016 1.016)
					(thickness 0.1524)
				)
				(justify mirror)
			)
		)
		(duplicate_pad_numbers_are_jumpers no)
		(fp_line
			(start 0.5969 -1.3081)
			(end -0.5842 -1.3081)
			(stroke
				(width 0.254)
				(type default)
			)
			(layer "B.SilkS")
		)
		(fp_rect
			(start 0.635 1.1811)
			(end -0.635 -1.1811)
			(stroke
				(width 0)
				(type default)
			)
			(fill no)
			(layer "B.CrtYd")
		)
		(fp_rect
			(start 0.635 1.1811)
			(end -0.635 -1.1811)
			(stroke
				(width 0)
				(type default)
			)
			(fill no)
			(layer "B.Fab")
		)
		(pad "1" smd custom
			(at 0 0.762 90)
			(size 0.19685 0.19685)
			(layers "B.Cu" "B.Mask" "B.Paste")
			(net "PWR_STATUS_LED")
			(options
				(clearance outline)
				(anchor circle)
			)
			(primitives
				(gr_poly
					(pts
						(arc
							(start 0.508 0.2921)
							(mid 0.478242 0.363942)
							(end 0.4064 0.3937)
						)
						(arc
							(start -0.4064 0.3937)
							(mid -0.478242 0.363942)
							(end -0.508 0.2921)
						)
						(arc
							(start -0.508 -0.2921)
							(mid -0.478242 -0.363942)
							(end -0.4064 -0.3937)
						)
						(arc
							(start 0.4064 -0.3937)
							(mid 0.478242 -0.363942)
							(end 0.508 -0.2921)
						)
					)
					(width 0)
					(fill yes)
				)
			)
		)
		(pad "2" smd custom
			(at 0 -0.762 90)
			(size 0.19685 0.19685)
			(layers "B.Cu" "B.Mask" "B.Paste")
			(net "PWR_STATUS_LED_D")
			(options
				(clearance outline)
				(anchor circle)
			)
			(primitives
				(gr_poly
					(pts
						(arc
							(start 0.508 0.2921)
							(mid 0.478242 0.363942)
							(end 0.4064 0.3937)
						)
						(arc
							(start -0.4064 0.3937)
							(mid -0.478242 0.363942)
							(end -0.508 0.2921)
						)
						(arc
							(start -0.508 -0.2921)
							(mid -0.478242 -0.363942)
							(end -0.4064 -0.3937)
						)
						(arc
							(start 0.4064 -0.3937)
							(mid 0.478242 -0.363942)
							(end 0.508 -0.2921)
						)
					)
					(width 0)
					(fill yes)
				)
			)
		)
	)
	(footprint ""
		(layer "B.Cu")
		(at 15.621 -48.133)
		(property "Reference" "C249"
			(at 0 0 0)
			(layer "B.SilkS")
			(hide yes)
			(effects
				(font
					(size 1.27 1.27)
				)
				(justify mirror)
			)
		)
		(property "Value" "SCD1U16V2KX-3GP"
			(at -1.8923 -1.2065 0)
			(unlocked yes)
			(layer "B.Fab")
			(hide yes)
			(effects
				(font
					(size 1.016 1.016)
					(thickness 0.1524)
				)
				(justify mirror)
			)
		)
		(property "Device Type" "C402H22"
			(at -1.8923 -2.7305 0)
			(unlocked yes)
			(layer "B.Fab")
			(hide yes)
			(effects
				(font
					(size 1.016 1.016)
					(thickness 0.1524)
				)
				(justify mirror)
			)
		)
		(duplicate_pad_numbers_are_jumpers no)
		(fp_rect
			(start 0.381 0.7366)
			(end -0.381 -0.7366)
			(stroke
				(width 0)
				(type default)
			)
			(fill no)
			(layer "B.CrtYd")
		)
		(fp_rect
			(start 0.381 0.7366)
			(end -0.381 -0.7366)
			(stroke
				(width 0)
				(type default)
			)
			(fill no)
			(layer "B.Fab")
		)
		(pad "1" smd custom
			(at 0 -0.4572 180)
			(size 0.1143 0.1143)
			(layers "B.Cu" "B.Mask" "B.Paste")
			(net "P3V3")
			(options
				(clearance outline)
				(anchor circle)
			)
			(primitives
				(gr_poly
					(pts
						(arc
							(start -0.254 0.1778)
							(mid -0.239121 0.213721)
							(end -0.2032 0.2286)
						)
						(arc
							(start 0.2032 0.2286)
							(mid 0.239121 0.213721)
							(end 0.254 0.1778)
						)
						(arc
							(start 0.254 -0.1778)
							(mid 0.239121 -0.213721)
							(end 0.2032 -0.2286)
						)
						(arc
							(start -0.2032 -0.2286)
							(mid -0.239121 -0.213721)
							(end -0.254 -0.1778)
						)
					)
					(width 0)
					(fill yes)
				)
			)
		)
		(pad "2" smd custom
			(at 0 0.4572 180)
			(size 0.1143 0.1143)
			(layers "B.Cu" "B.Mask" "B.Paste")
			(net "GND")
			(options
				(clearance outline)
				(anchor circle)
			)
			(primitives
				(gr_poly
					(pts
						(arc
							(start -0.254 0.1778)
							(mid -0.239121 0.213721)
							(end -0.2032 0.2286)
						)
						(arc
							(start 0.2032 0.2286)
							(mid 0.239121 0.213721)
							(end 0.254 0.1778)
						)
						(arc
							(start 0.254 -0.1778)
							(mid 0.239121 -0.213721)
							(end 0.2032 -0.2286)
						)
						(arc
							(start -0.2032 -0.2286)
							(mid -0.239121 -0.213721)
							(end -0.254 -0.1778)
						)
					)
					(width 0)
					(fill yes)
				)
			)
		)
	)
	(footprint ""
		(layer "B.Cu")
		(at 95.19412 -46.89094 90)
		(property "Reference" "C147"
			(at 0 0 90)
			(layer "B.SilkS")
			(hide yes)
			(effects
				(font
					(size 1.27 1.27)
				)
				(justify mirror)
			)
		)
		(property "Value" "SC1U10V2KX-1GP"
			(at -1.1811 -2.7051 90)
			(unlocked yes)
			(layer "B.Fab")
			(hide yes)
			(effects
				(font
					(size 1.016 1.016)
					(thickness 0.1524)
				)
				(justify mirror)
			)
		)
		(property "Device Type" "C402H22"
			(at -1.1811 -4.2291 90)
			(unlocked yes)
			(layer "B.Fab")
			(hide yes)
			(effects
				(font
					(size 1.016 1.016)
					(thickness 0.1524)
				)
				(justify mirror)
			)
		)
		(duplicate_pad_numbers_are_jumpers no)
		(fp_rect
			(start 0.381 0.7366)
			(end -0.381 -0.7366)
			(stroke
				(width 0)
				(type default)
			)
			(fill no)
			(layer "B.CrtYd")
		)
		(fp_rect
			(start 0.381 0.7366)
			(end -0.381 -0.7366)
			(stroke
				(width 0)
				(type default)
			)
			(fill no)
			(layer "B.Fab")
		)
		(pad "1" smd custom
			(at 0 -0.4572 270)
			(size 0.1143 0.1143)
			(layers "B.Cu" "B.Mask" "B.Paste")
			(net "P1V0")
			(options
				(clearance outline)
				(anchor circle)
			)
			(primitives
				(gr_poly
					(pts
						(arc
							(start -0.254 0.1778)
							(mid -0.239121 0.213721)
							(end -0.2032 0.2286)
						)
						(arc
							(start 0.2032 0.2286)
							(mid 0.239121 0.213721)
							(end 0.254 0.1778)
						)
						(arc
							(start 0.254 -0.1778)
							(mid 0.239121 -0.213721)
							(end 0.2032 -0.2286)
						)
						(arc
							(start -0.2032 -0.2286)
							(mid -0.239121 -0.213721)
							(end -0.254 -0.1778)
						)
					)
					(width 0)
					(fill yes)
				)
			)
		)
		(pad "2" smd custom
			(at 0 0.4572 270)
			(size 0.1143 0.1143)
			(layers "B.Cu" "B.Mask" "B.Paste")
			(net "GND")
			(options
				(clearance outline)
				(anchor circle)
			)
			(primitives
				(gr_poly
					(pts
						(arc
							(start -0.254 0.1778)
							(mid -0.239121 0.213721)
							(end -0.2032 0.2286)
						)
						(arc
							(start 0.2032 0.2286)
							(mid 0.239121 0.213721)
							(end 0.254 0.1778)
						)
						(arc
							(start 0.254 -0.1778)
							(mid 0.239121 -0.213721)
							(end 0.2032 -0.2286)
						)
						(arc
							(start -0.2032 -0.2286)
							(mid -0.239121 -0.213721)
							(end -0.254 -0.1778)
						)
					)
					(width 0)
					(fill yes)
				)
			)
		)
	)
	(footprint ""
		(layer "B.Cu")
		(at 68.707 -32.0802 90)
		(property "Reference" "C82"
			(at 0 0 90)
			(layer "B.SilkS")
			(hide yes)
			(effects
				(font
					(size 1.27 1.27)
				)
				(justify mirror)
			)
		)
		(property "Value" "SCD1U10V2KX-5GP"
			(at -1.8923 -1.2065 90)
			(unlocked yes)
			(layer "B.Fab")
			(hide yes)
			(effects
				(font
					(size 1.016 1.016)
					(thickness 0.1524)
				)
				(justify mirror)
			)
		)
		(property "Device Type" "C402H22"
			(at -1.8923 -2.7305 90)
			(unlocked yes)
			(layer "B.Fab")
			(hide yes)
			(effects
				(font
					(size 1.016 1.016)
					(thickness 0.1524)
				)
				(justify mirror)
			)
		)
		(duplicate_pad_numbers_are_jumpers no)
		(fp_rect
			(start 0.381 0.7366)
			(end -0.381 -0.7366)
			(stroke
				(width 0)
				(type default)
			)
			(fill no)
			(layer "B.CrtYd")
		)
		(fp_rect
			(start 0.381 0.7366)
			(end -0.381 -0.7366)
			(stroke
				(width 0)
				(type default)
			)
			(fill no)
			(layer "B.Fab")
		)
		(pad "1" smd custom
			(at 0 -0.4572 270)
			(size 0.1143 0.1143)
			(layers "B.Cu" "B.Mask" "B.Paste")
			(net "P3V3_STBY")
			(options
				(clearance outline)
				(anchor circle)
			)
			(primitives
				(gr_poly
					(pts
						(arc
							(start -0.254 0.1778)
							(mid -0.239121 0.213721)
							(end -0.2032 0.2286)
						)
						(arc
							(start 0.2032 0.2286)
							(mid 0.239121 0.213721)
							(end 0.254 0.1778)
						)
						(arc
							(start 0.254 -0.1778)
							(mid 0.239121 -0.213721)
							(end 0.2032 -0.2286)
						)
						(arc
							(start -0.2032 -0.2286)
							(mid -0.239121 -0.213721)
							(end -0.254 -0.1778)
						)
					)
					(width 0)
					(fill yes)
				)
			)
		)
		(pad "2" smd custom
			(at 0 0.4572 270)
			(size 0.1143 0.1143)
			(layers "B.Cu" "B.Mask" "B.Paste")
			(net "GND")
			(options
				(clearance outline)
				(anchor circle)
			)
			(primitives
				(gr_poly
					(pts
						(arc
							(start -0.254 0.1778)
							(mid -0.239121 0.213721)
							(end -0.2032 0.2286)
						)
						(arc
							(start 0.2032 0.2286)
							(mid 0.239121 0.213721)
							(end 0.254 0.1778)
						)
						(arc
							(start 0.254 -0.1778)
							(mid 0.239121 -0.213721)
							(end 0.2032 -0.2286)
						)
						(arc
							(start -0.2032 -0.2286)
							(mid -0.239121 -0.213721)
							(end -0.254 -0.1778)
						)
					)
					(width 0)
					(fill yes)
				)
			)
		)
	)
	(footprint ""
		(layer "B.Cu")
		(at 100.33 -65.659)
		(property "Reference" "PR15"
			(at 0 0 0)
			(layer "B.SilkS")
			(hide yes)
			(effects
				(font
					(size 1.27 1.27)
				)
				(justify mirror)
			)
		)
		(property "Value" "470KR2F-GP"
			(at -0.064008 -3.993896 0)
			(unlocked yes)
			(layer "B.Fab")
			(hide yes)
			(effects
				(font
					(size 1.016 1.016)
					(thickness 0.1524)
				)
				(justify mirror)
			)
		)
		(property "Device Type" "R402H16"
			(at -0.064008 -5.517896 0)
			(unlocked yes)
			(layer "B.Fab")
			(hide yes)
			(effects
				(font
					(size 1.016 1.016)
					(thickness 0.1524)
				)
				(justify mirror)
			)
		)
		(duplicate_pad_numbers_are_jumpers no)
		(fp_rect
			(start 0.381 0.8382)
			(end -0.381 -0.8382)
			(stroke
				(width 0)
				(type default)
			)
			(fill no)
			(layer "B.CrtYd")
		)
		(fp_rect
			(start 0.381 0.8382)
			(end -0.381 -0.8382)
			(stroke
				(width 0)
				(type default)
			)
			(fill no)
			(layer "B.Fab")
		)
		(pad "1" smd custom
			(at 0 -0.4318 180)
			(size 0.127 0.127)
			(layers "B.Cu" "B.Mask" "B.Paste")
			(net "VR_P1V1_VFB")
			(options
				(clearance outline)
				(anchor circle)
			)
			(primitives
				(gr_poly
					(pts
						(arc
							(start -0.2032 0.2794)
							(mid -0.239121 0.264521)
							(end -0.254 0.2286)
						)
						(arc
							(start -0.254 -0.2286)
							(mid -0.239121 -0.264521)
							(end -0.2032 -0.2794)
						)
						(arc
							(start 0.2032 -0.2794)
							(mid 0.239121 -0.264521)
							(end 0.254 -0.2286)
						)
						(arc
							(start 0.254 0.2286)
							(mid 0.239121 0.264521)
							(end 0.2032 0.2794)
						)
					)
					(width 0)
					(fill yes)
				)
			)
		)
		(pad "2" smd custom
			(at 0 0.4318 180)
			(size 0.127 0.127)
			(layers "B.Cu" "B.Mask" "B.Paste")
			(net "AGND_P1V1")
			(options
				(clearance outline)
				(anchor circle)
			)
			(primitives
				(gr_poly
					(pts
						(arc
							(start -0.2032 0.2794)
							(mid -0.239121 0.264521)
							(end -0.254 0.2286)
						)
						(arc
							(start -0.254 -0.2286)
							(mid -0.239121 -0.264521)
							(end -0.2032 -0.2794)
						)
						(arc
							(start 0.2032 -0.2794)
							(mid 0.239121 -0.264521)
							(end 0.254 -0.2286)
						)
						(arc
							(start 0.254 0.2286)
							(mid 0.239121 0.264521)
							(end 0.2032 0.2794)
						)
					)
					(width 0)
					(fill yes)
				)
			)
		)
	)
	(footprint ""
		(layer "B.Cu")
		(at 81.661 -24.511)
		(property "Reference" "R307"
			(at 0 0 0)
			(layer "B.SilkS")
			(hide yes)
			(effects
				(font
					(size 1.27 1.27)
				)
				(justify mirror)
			)
		)
		(property "Value" "0R2J-2-GP"
			(at -0.064008 -3.993896 0)
			(unlocked yes)
			(layer "B.Fab")
			(hide yes)
			(effects
				(font
					(size 1.016 1.016)
					(thickness 0.1524)
				)
				(justify mirror)
			)
		)
		(property "Device Type" "R402H16"
			(at -0.064008 -5.517896 0)
			(unlocked yes)
			(layer "B.Fab")
			(hide yes)
			(effects
				(font
					(size 1.016 1.016)
					(thickness 0.1524)
				)
				(justify mirror)
			)
		)
		(duplicate_pad_numbers_are_jumpers no)
		(fp_rect
			(start 0.381 0.8382)
			(end -0.381 -0.8382)
			(stroke
				(width 0)
				(type default)
			)
			(fill no)
			(layer "B.CrtYd")
		)
		(fp_rect
			(start 0.381 0.8382)
			(end -0.381 -0.8382)
			(stroke
				(width 0)
				(type default)
			)
			(fill no)
			(layer "B.Fab")
		)
		(pad "1" smd custom
			(at 0 -0.4318 180)
			(size 0.127 0.127)
			(layers "B.Cu" "B.Mask" "B.Paste")
			(net "CPU_UART_TXD_R")
			(options
				(clearance outline)
				(anchor circle)
			)
			(primitives
				(gr_poly
					(pts
						(arc
							(start -0.2032 0.2794)
							(mid -0.239121 0.264521)
							(end -0.254 0.2286)
						)
						(arc
							(start -0.254 -0.2286)
							(mid -0.239121 -0.264521)
							(end -0.2032 -0.2794)
						)
						(arc
							(start 0.2032 -0.2794)
							(mid 0.239121 -0.264521)
							(end 0.254 -0.2286)
						)
						(arc
							(start 0.254 0.2286)
							(mid 0.239121 0.264521)
							(end 0.2032 0.2794)
						)
					)
					(width 0)
					(fill yes)
				)
			)
		)
		(pad "2" smd custom
			(at 0 0.4318 180)
			(size 0.127 0.127)
			(layers "B.Cu" "B.Mask" "B.Paste")
			(net "CPU_TXD")
			(options
				(clearance outline)
				(anchor circle)
			)
			(primitives
				(gr_poly
					(pts
						(arc
							(start -0.2032 0.2794)
							(mid -0.239121 0.264521)
							(end -0.254 0.2286)
						)
						(arc
							(start -0.254 -0.2286)
							(mid -0.239121 -0.264521)
							(end -0.2032 -0.2794)
						)
						(arc
							(start 0.2032 -0.2794)
							(mid 0.239121 -0.264521)
							(end 0.254 -0.2286)
						)
						(arc
							(start 0.254 0.2286)
							(mid 0.239121 0.264521)
							(end 0.2032 0.2794)
						)
					)
					(width 0)
					(fill yes)
				)
			)
		)
	)
	(footprint ""
		(layer "B.Cu")
		(at 186.563 -26.035 -90)
		(property "Reference" "PR164"
			(at 0 0 90)
			(layer "B.SilkS")
			(hide yes)
			(effects
				(font
					(size 1.27 1.27)
				)
				(justify mirror)
			)
		)
		(property "Value" "10R2F-L-GP"
			(at -1.7907 -1.1176 270)
			(unlocked yes)
			(layer "B.Fab")
			(hide yes)
			(effects
				(font
					(size 1.016 1.016)
					(thickness 0.1524)
				)
				(justify mirror)
			)
		)
		(property "Device Type" "R402H14"
			(at -1.7907 -2.6416 270)
			(unlocked yes)
			(layer "B.Fab")
			(hide yes)
			(effects
				(font
					(size 1.016 1.016)
					(thickness 0.1524)
				)
				(justify mirror)
			)
		)
		(duplicate_pad_numbers_are_jumpers no)
		(fp_rect
			(start 0.381 0.8382)
			(end -0.381 -0.8382)
			(stroke
				(width 0)
				(type default)
			)
			(fill no)
			(layer "B.CrtYd")
		)
		(fp_rect
			(start 0.381 0.8382)
			(end -0.381 -0.8382)
			(stroke
				(width 0)
				(type default)
			)
			(fill no)
			(layer "B.Fab")
		)
		(pad "1" smd custom
			(at 0 -0.4318 90)
			(size 0.127 0.127)
			(layers "B.Cu" "B.Mask" "B.Paste")
			(net "VR_PVDDRA_ISUMN1")
			(options
				(clearance outline)
				(anchor circle)
			)
			(primitives
				(gr_poly
					(pts
						(arc
							(start -0.2032 0.2794)
							(mid -0.239121 0.264521)
							(end -0.254 0.2286)
						)
						(arc
							(start -0.254 -0.2286)
							(mid -0.239121 -0.264521)
							(end -0.2032 -0.2794)
						)
						(arc
							(start 0.2032 -0.2794)
							(mid 0.239121 -0.264521)
							(end 0.254 -0.2286)
						)
						(arc
							(start 0.254 0.2286)
							(mid 0.239121 0.264521)
							(end 0.2032 0.2794)
						)
					)
					(width 0)
					(fill yes)
				)
			)
		)
		(pad "2" smd custom
			(at 0 0.4318 90)
			(size 0.127 0.127)
			(layers "B.Cu" "B.Mask" "B.Paste")
			(net "VR_PVDDRA_R_ISUMN1")
			(options
				(clearance outline)
				(anchor circle)
			)
			(primitives
				(gr_poly
					(pts
						(arc
							(start -0.2032 0.2794)
							(mid -0.239121 0.264521)
							(end -0.254 0.2286)
						)
						(arc
							(start -0.254 -0.2286)
							(mid -0.239121 -0.264521)
							(end -0.2032 -0.2794)
						)
						(arc
							(start 0.2032 -0.2794)
							(mid 0.239121 -0.264521)
							(end 0.254 -0.2286)
						)
						(arc
							(start 0.254 0.2286)
							(mid 0.239121 0.264521)
							(end 0.2032 0.2794)
						)
					)
					(width 0)
					(fill yes)
				)
			)
		)
	)
	(footprint ""
		(layer "B.Cu")
		(at 29.718 -43.053)
		(property "Reference" "PC141"
			(at 0 0 0)
			(layer "B.SilkS")
			(hide yes)
			(effects
				(font
					(size 1.27 1.27)
				)
				(justify mirror)
			)
		)
		(property "Value" "SC10U6D3V5KX-4GP"
			(at 0 -4.9022 0)
			(unlocked yes)
			(layer "B.Fab")
			(hide yes)
			(effects
				(font
					(size 1.016 1.016)
					(thickness 0.1524)
				)
				(justify mirror)
			)
		)
		(property "Device Type" "C805H58"
			(at 0 -6.8072 0)
			(unlocked yes)
			(layer "B.Fab")
			(hide yes)
			(effects
				(font
					(size 1.016 1.016)
					(thickness 0.1524)
				)
				(justify mirror)
			)
		)
		(duplicate_pad_numbers_are_jumpers no)
		(fp_line
			(start -0.6096 0)
			(end 0.6096 0)
			(stroke
				(width 0.3048)
				(type default)
			)
			(layer "B.SilkS")
		)
		(fp_poly
			(pts
				(xy 0.9017 1.4351) (xy -0.9017 1.4351) (xy -0.9017 -1.4351) (xy 0.9017 -1.4351)
			)
			(stroke
				(width 0)
				(type default)
			)
			(fill no)
			(layer "B.CrtYd")
		)
		(fp_poly
			(pts
				(xy -0.9017 1.4351) (xy -0.9017 -1.4351) (xy 0.9017 -1.4351) (xy 0.9017 1.4351)
			)
			(stroke
				(width 0)
				(type default)
			)
			(fill no)
			(layer "B.Fab")
		)
		(pad "1" smd rect
			(at 0 -0.8382 180)
			(size 1.5494 0.9398)
			(layers "B.Cu" "B.Mask" "B.Paste")
			(net "P1V5_STBY_OUT")
		)
		(pad "2" smd rect
			(at 0 0.8382 180)
			(size 1.5494 0.9398)
			(layers "B.Cu" "B.Mask" "B.Paste")
			(net "GND")
		)
	)
	(footprint ""
		(layer "B.Cu")
		(at 79.248 -23.6474)
		(property "Reference" "R379"
			(at 0 0 0)
			(layer "B.SilkS")
			(hide yes)
			(effects
				(font
					(size 1.27 1.27)
				)
				(justify mirror)
			)
		)
		(property "Value" "4K75R2F-1-GP"
			(at -0.064008 -3.993896 0)
			(unlocked yes)
			(layer "B.Fab")
			(hide yes)
			(effects
				(font
					(size 1.016 1.016)
					(thickness 0.1524)
				)
				(justify mirror)
			)
		)
		(property "Device Type" "R402H16"
			(at -0.064008 -5.517896 0)
			(unlocked yes)
			(layer "B.Fab")
			(hide yes)
			(effects
				(font
					(size 1.016 1.016)
					(thickness 0.1524)
				)
				(justify mirror)
			)
		)
		(duplicate_pad_numbers_are_jumpers no)
		(fp_rect
			(start 0.381 0.8382)
			(end -0.381 -0.8382)
			(stroke
				(width 0)
				(type default)
			)
			(fill no)
			(layer "B.CrtYd")
		)
		(fp_rect
			(start 0.381 0.8382)
			(end -0.381 -0.8382)
			(stroke
				(width 0)
				(type default)
			)
			(fill no)
			(layer "B.Fab")
		)
		(pad "1" smd custom
			(at 0 -0.4318 180)
			(size 0.127 0.127)
			(layers "B.Cu" "B.Mask" "B.Paste")
			(net "P3V3_STBY")
			(options
				(clearance outline)
				(anchor circle)
			)
			(primitives
				(gr_poly
					(pts
						(arc
							(start -0.2032 0.2794)
							(mid -0.239121 0.264521)
							(end -0.254 0.2286)
						)
						(arc
							(start -0.254 -0.2286)
							(mid -0.239121 -0.264521)
							(end -0.2032 -0.2794)
						)
						(arc
							(start 0.2032 -0.2794)
							(mid 0.239121 -0.264521)
							(end 0.254 -0.2286)
						)
						(arc
							(start 0.254 0.2286)
							(mid 0.239121 0.264521)
							(end 0.2032 0.2794)
						)
					)
					(width 0)
					(fill yes)
				)
			)
		)
		(pad "2" smd custom
			(at 0 0.4318 180)
			(size 0.127 0.127)
			(layers "B.Cu" "B.Mask" "B.Paste")
			(net "TPS74801_1V35_EN")
			(options
				(clearance outline)
				(anchor circle)
			)
			(primitives
				(gr_poly
					(pts
						(arc
							(start -0.2032 0.2794)
							(mid -0.239121 0.264521)
							(end -0.254 0.2286)
						)
						(arc
							(start -0.254 -0.2286)
							(mid -0.239121 -0.264521)
							(end -0.2032 -0.2794)
						)
						(arc
							(start 0.2032 -0.2794)
							(mid 0.239121 -0.264521)
							(end 0.254 -0.2286)
						)
						(arc
							(start 0.254 0.2286)
							(mid 0.239121 0.264521)
							(end 0.2032 0.2794)
						)
					)
					(width 0)
					(fill yes)
				)
			)
		)
	)
	(footprint ""
		(layer "B.Cu")
		(at 97.028 -35.433 90)
		(property "Reference" "C202"
			(at 0 0 90)
			(layer "B.SilkS")
			(hide yes)
			(effects
				(font
					(size 1.27 1.27)
				)
				(justify mirror)
			)
		)
		(property "Value" "SC1U10V2KX-1GP"
			(at -1.1811 -2.7051 90)
			(unlocked yes)
			(layer "B.Fab")
			(hide yes)
			(effects
				(font
					(size 1.016 1.016)
					(thickness 0.1524)
				)
				(justify mirror)
			)
		)
		(property "Device Type" "C402H22"
			(at -1.1811 -4.2291 90)
			(unlocked yes)
			(layer "B.Fab")
			(hide yes)
			(effects
				(font
					(size 1.016 1.016)
					(thickness 0.1524)
				)
				(justify mirror)
			)
		)
		(duplicate_pad_numbers_are_jumpers no)
		(fp_rect
			(start 0.381 0.7366)
			(end -0.381 -0.7366)
			(stroke
				(width 0)
				(type default)
			)
			(fill no)
			(layer "B.CrtYd")
		)
		(fp_rect
			(start 0.381 0.7366)
			(end -0.381 -0.7366)
			(stroke
				(width 0)
				(type default)
			)
			(fill no)
			(layer "B.Fab")
		)
		(pad "1" smd custom
			(at 0 -0.4572 270)
			(size 0.1143 0.1143)
			(layers "B.Cu" "B.Mask" "B.Paste")
			(net "P1V35")
			(options
				(clearance outline)
				(anchor circle)
			)
			(primitives
				(gr_poly
					(pts
						(arc
							(start -0.254 0.1778)
							(mid -0.239121 0.213721)
							(end -0.2032 0.2286)
						)
						(arc
							(start 0.2032 0.2286)
							(mid 0.239121 0.213721)
							(end 0.254 0.1778)
						)
						(arc
							(start 0.254 -0.1778)
							(mid 0.239121 -0.213721)
							(end 0.2032 -0.2286)
						)
						(arc
							(start -0.2032 -0.2286)
							(mid -0.239121 -0.213721)
							(end -0.254 -0.1778)
						)
					)
					(width 0)
					(fill yes)
				)
			)
		)
		(pad "2" smd custom
			(at 0 0.4572 270)
			(size 0.1143 0.1143)
			(layers "B.Cu" "B.Mask" "B.Paste")
			(net "GND")
			(options
				(clearance outline)
				(anchor circle)
			)
			(primitives
				(gr_poly
					(pts
						(arc
							(start -0.254 0.1778)
							(mid -0.239121 0.213721)
							(end -0.2032 0.2286)
						)
						(arc
							(start 0.2032 0.2286)
							(mid 0.239121 0.213721)
							(end 0.254 0.1778)
						)
						(arc
							(start 0.254 -0.1778)
							(mid 0.239121 -0.213721)
							(end 0.2032 -0.2286)
						)
						(arc
							(start -0.2032 -0.2286)
							(mid -0.239121 -0.213721)
							(end -0.254 -0.1778)
						)
					)
					(width 0)
					(fill yes)
				)
			)
		)
	)
	(footprint ""
		(layer "B.Cu")
		(at 89.154 -27.051 -90)
		(property "Reference" "C221"
			(at 0 0 90)
			(layer "B.SilkS")
			(hide yes)
			(effects
				(font
					(size 1.27 1.27)
				)
				(justify mirror)
			)
		)
		(property "Value" "SC1U10V2KX-1GP"
			(at -1.1811 -2.7051 270)
			(unlocked yes)
			(layer "B.Fab")
			(hide yes)
			(effects
				(font
					(size 1.016 1.016)
					(thickness 0.1524)
				)
				(justify mirror)
			)
		)
		(property "Device Type" "C402H22"
			(at -1.1811 -4.2291 270)
			(unlocked yes)
			(layer "B.Fab")
			(hide yes)
			(effects
				(font
					(size 1.016 1.016)
					(thickness 0.1524)
				)
				(justify mirror)
			)
		)
		(duplicate_pad_numbers_are_jumpers no)
		(fp_rect
			(start 0.381 0.7366)
			(end -0.381 -0.7366)
			(stroke
				(width 0)
				(type default)
			)
			(fill no)
			(layer "B.CrtYd")
		)
		(fp_rect
			(start 0.381 0.7366)
			(end -0.381 -0.7366)
			(stroke
				(width 0)
				(type default)
			)
			(fill no)
			(layer "B.Fab")
		)
		(pad "1" smd custom
			(at 0 -0.4572 90)
			(size 0.1143 0.1143)
			(layers "B.Cu" "B.Mask" "B.Paste")
			(net "P1V0")
			(options
				(clearance outline)
				(anchor circle)
			)
			(primitives
				(gr_poly
					(pts
						(arc
							(start -0.254 0.1778)
							(mid -0.239121 0.213721)
							(end -0.2032 0.2286)
						)
						(arc
							(start 0.2032 0.2286)
							(mid 0.239121 0.213721)
							(end 0.254 0.1778)
						)
						(arc
							(start 0.254 -0.1778)
							(mid 0.239121 -0.213721)
							(end 0.2032 -0.2286)
						)
						(arc
							(start -0.2032 -0.2286)
							(mid -0.239121 -0.213721)
							(end -0.254 -0.1778)
						)
					)
					(width 0)
					(fill yes)
				)
			)
		)
		(pad "2" smd custom
			(at 0 0.4572 90)
			(size 0.1143 0.1143)
			(layers "B.Cu" "B.Mask" "B.Paste")
			(net "GND")
			(options
				(clearance outline)
				(anchor circle)
			)
			(primitives
				(gr_poly
					(pts
						(arc
							(start -0.254 0.1778)
							(mid -0.239121 0.213721)
							(end -0.2032 0.2286)
						)
						(arc
							(start 0.2032 0.2286)
							(mid 0.239121 0.213721)
							(end 0.254 0.1778)
						)
						(arc
							(start 0.254 -0.1778)
							(mid 0.239121 -0.213721)
							(end 0.2032 -0.2286)
						)
						(arc
							(start -0.2032 -0.2286)
							(mid -0.239121 -0.213721)
							(end -0.254 -0.1778)
						)
					)
					(width 0)
					(fill yes)
				)
			)
		)
	)
	(footprint ""
		(layer "B.Cu")
		(at 87.503 -34.9504 180)
		(property "Reference" "R337"
			(at 0 0 0)
			(layer "B.SilkS")
			(hide yes)
			(effects
				(font
					(size 1.27 1.27)
				)
				(justify mirror)
			)
		)
		(property "Value" "0R2J-2-GP"
			(at -1.7907 -1.1176 180)
			(unlocked yes)
			(layer "B.Fab")
			(hide yes)
			(effects
				(font
					(size 1.016 1.016)
					(thickness 0.1524)
				)
				(justify mirror)
			)
		)
		(property "Device Type" "R402H16"
			(at -1.7907 -2.6416 180)
			(unlocked yes)
			(layer "B.Fab")
			(hide yes)
			(effects
				(font
					(size 1.016 1.016)
					(thickness 0.1524)
				)
				(justify mirror)
			)
		)
		(duplicate_pad_numbers_are_jumpers no)
		(fp_rect
			(start 0.381 0.8382)
			(end -0.381 -0.8382)
			(stroke
				(width 0)
				(type default)
			)
			(fill no)
			(layer "B.CrtYd")
		)
		(fp_rect
			(start 0.381 0.8382)
			(end -0.381 -0.8382)
			(stroke
				(width 0)
				(type default)
			)
			(fill no)
			(layer "B.Fab")
		)
		(pad "1" smd custom
			(at 0 -0.4318)
			(size 0.127 0.127)
			(layers "B.Cu" "B.Mask" "B.Paste")
			(net "PMU_SLP_DDRVTT#")
			(options
				(clearance outline)
				(anchor circle)
			)
			(primitives
				(gr_poly
					(pts
						(arc
							(start -0.2032 0.2794)
							(mid -0.239121 0.264521)
							(end -0.254 0.2286)
						)
						(arc
							(start -0.254 -0.2286)
							(mid -0.239121 -0.264521)
							(end -0.2032 -0.2794)
						)
						(arc
							(start 0.2032 -0.2794)
							(mid 0.239121 -0.264521)
							(end 0.254 -0.2286)
						)
						(arc
							(start 0.254 0.2286)
							(mid 0.239121 0.264521)
							(end 0.2032 0.2794)
						)
					)
					(width 0)
					(fill yes)
				)
			)
		)
		(pad "2" smd custom
			(at 0 0.4318)
			(size 0.127 0.127)
			(layers "B.Cu" "B.Mask" "B.Paste")
			(net "PMU_SLP_LAN#")
			(options
				(clearance outline)
				(anchor circle)
			)
			(primitives
				(gr_poly
					(pts
						(arc
							(start -0.2032 0.2794)
							(mid -0.239121 0.264521)
							(end -0.254 0.2286)
						)
						(arc
							(start -0.254 -0.2286)
							(mid -0.239121 -0.264521)
							(end -0.2032 -0.2794)
						)
						(arc
							(start 0.2032 -0.2794)
							(mid 0.239121 -0.264521)
							(end 0.254 -0.2286)
						)
						(arc
							(start 0.254 0.2286)
							(mid 0.239121 0.264521)
							(end 0.2032 0.2794)
						)
					)
					(width 0)
					(fill yes)
				)
			)
		)
	)
	(footprint ""
		(layer "B.Cu")
		(at 49.53 -43.434 180)
		(property "Reference" "R95"
			(at 0 0 0)
			(layer "B.SilkS")
			(hide yes)
			(effects
				(font
					(size 1.27 1.27)
				)
				(justify mirror)
			)
		)
		(property "Value" "4K7R2F-GP"
			(at -0.064008 -3.993896 180)
			(unlocked yes)
			(layer "B.Fab")
			(hide yes)
			(effects
				(font
					(size 1.016 1.016)
					(thickness 0.1524)
				)
				(justify mirror)
			)
		)
		(property "Device Type" "R402H16"
			(at -0.064008 -5.517896 180)
			(unlocked yes)
			(layer "B.Fab")
			(hide yes)
			(effects
				(font
					(size 1.016 1.016)
					(thickness 0.1524)
				)
				(justify mirror)
			)
		)
		(duplicate_pad_numbers_are_jumpers no)
		(fp_rect
			(start 0.381 0.8382)
			(end -0.381 -0.8382)
			(stroke
				(width 0)
				(type default)
			)
			(fill no)
			(layer "B.CrtYd")
		)
		(fp_rect
			(start 0.381 0.8382)
			(end -0.381 -0.8382)
			(stroke
				(width 0)
				(type default)
			)
			(fill no)
			(layer "B.Fab")
		)
		(pad "1" smd custom
			(at 0 -0.4318)
			(size 0.127 0.127)
			(layers "B.Cu" "B.Mask" "B.Paste")
			(net "P3V3_STBY")
			(options
				(clearance outline)
				(anchor circle)
			)
			(primitives
				(gr_poly
					(pts
						(arc
							(start -0.2032 0.2794)
							(mid -0.239121 0.264521)
							(end -0.254 0.2286)
						)
						(arc
							(start -0.254 -0.2286)
							(mid -0.239121 -0.264521)
							(end -0.2032 -0.2794)
						)
						(arc
							(start 0.2032 -0.2794)
							(mid 0.239121 -0.264521)
							(end 0.254 -0.2286)
						)
						(arc
							(start 0.254 0.2286)
							(mid 0.239121 0.264521)
							(end 0.2032 0.2794)
						)
					)
					(width 0)
					(fill yes)
				)
			)
		)
		(pad "2" smd custom
			(at 0 0.4318)
			(size 0.127 0.127)
			(layers "B.Cu" "B.Mask" "B.Paste")
			(net "CLKGEN_DIF_STOP#")
			(options
				(clearance outline)
				(anchor circle)
			)
			(primitives
				(gr_poly
					(pts
						(arc
							(start -0.2032 0.2794)
							(mid -0.239121 0.264521)
							(end -0.254 0.2286)
						)
						(arc
							(start -0.254 -0.2286)
							(mid -0.239121 -0.264521)
							(end -0.2032 -0.2794)
						)
						(arc
							(start 0.2032 -0.2794)
							(mid 0.239121 -0.264521)
							(end 0.254 -0.2286)
						)
						(arc
							(start 0.254 0.2286)
							(mid 0.239121 0.264521)
							(end 0.2032 0.2794)
						)
					)
					(width 0)
					(fill yes)
				)
			)
		)
	)
	(footprint ""
		(layer "B.Cu")
		(at 73.66 -13.589)
		(property "Reference" "C278"
			(at 0 0 0)
			(layer "B.SilkS")
			(hide yes)
			(effects
				(font
					(size 1.27 1.27)
				)
				(justify mirror)
			)
		)
		(property "Value" "SCD1U16V2KX-3GP"
			(at -1.1811 -2.7051 0)
			(unlocked yes)
			(layer "B.Fab")
			(hide yes)
			(effects
				(font
					(size 1.016 1.016)
					(thickness 0.1524)
				)
				(justify mirror)
			)
		)
		(property "Device Type" "C402H22"
			(at -1.1811 -4.2291 0)
			(unlocked yes)
			(layer "B.Fab")
			(hide yes)
			(effects
				(font
					(size 1.016 1.016)
					(thickness 0.1524)
				)
				(justify mirror)
			)
		)
		(duplicate_pad_numbers_are_jumpers no)
		(fp_rect
			(start 0.381 0.7366)
			(end -0.381 -0.7366)
			(stroke
				(width 0)
				(type default)
			)
			(fill no)
			(layer "B.CrtYd")
		)
		(fp_rect
			(start 0.381 0.7366)
			(end -0.381 -0.7366)
			(stroke
				(width 0)
				(type default)
			)
			(fill no)
			(layer "B.Fab")
		)
		(pad "1" smd custom
			(at 0 -0.4572 180)
			(size 0.1143 0.1143)
			(layers "B.Cu" "B.Mask" "B.Paste")
			(net "P2E_CPU_SAS_C_TX_DP2")
			(options
				(clearance outline)
				(anchor circle)
			)
			(primitives
				(gr_poly
					(pts
						(arc
							(start -0.254 0.1778)
							(mid -0.239121 0.213721)
							(end -0.2032 0.2286)
						)
						(arc
							(start 0.2032 0.2286)
							(mid 0.239121 0.213721)
							(end 0.254 0.1778)
						)
						(arc
							(start 0.254 -0.1778)
							(mid 0.239121 -0.213721)
							(end 0.2032 -0.2286)
						)
						(arc
							(start -0.2032 -0.2286)
							(mid -0.239121 -0.213721)
							(end -0.254 -0.1778)
						)
					)
					(width 0)
					(fill yes)
				)
			)
		)
		(pad "2" smd custom
			(at 0 0.4572 180)
			(size 0.1143 0.1143)
			(layers "B.Cu" "B.Mask" "B.Paste")
			(net "P2E_CPU_SAS_TX_DP2")
			(options
				(clearance outline)
				(anchor circle)
			)
			(primitives
				(gr_poly
					(pts
						(arc
							(start -0.254 0.1778)
							(mid -0.239121 0.213721)
							(end -0.2032 0.2286)
						)
						(arc
							(start 0.2032 0.2286)
							(mid 0.239121 0.213721)
							(end 0.254 0.1778)
						)
						(arc
							(start 0.254 -0.1778)
							(mid 0.239121 -0.213721)
							(end 0.2032 -0.2286)
						)
						(arc
							(start -0.2032 -0.2286)
							(mid -0.239121 -0.213721)
							(end -0.254 -0.1778)
						)
					)
					(width 0)
					(fill yes)
				)
			)
		)
	)
	(footprint ""
		(layer "B.Cu")
		(at 81.915 -63.246 180)
		(property "Reference" "R283"
			(at 0 0 0)
			(layer "B.SilkS")
			(hide yes)
			(effects
				(font
					(size 1.27 1.27)
				)
				(justify mirror)
			)
		)
		(property "Value" "0R2J-2-GP"
			(at -0.064008 -3.993896 180)
			(unlocked yes)
			(layer "B.Fab")
			(hide yes)
			(effects
				(font
					(size 1.016 1.016)
					(thickness 0.1524)
				)
				(justify mirror)
			)
		)
		(property "Device Type" "R402H16"
			(at -0.064008 -5.517896 180)
			(unlocked yes)
			(layer "B.Fab")
			(hide yes)
			(effects
				(font
					(size 1.016 1.016)
					(thickness 0.1524)
				)
				(justify mirror)
			)
		)
		(duplicate_pad_numbers_are_jumpers no)
		(fp_rect
			(start 0.381 0.8382)
			(end -0.381 -0.8382)
			(stroke
				(width 0)
				(type default)
			)
			(fill no)
			(layer "B.CrtYd")
		)
		(fp_rect
			(start 0.381 0.8382)
			(end -0.381 -0.8382)
			(stroke
				(width 0)
				(type default)
			)
			(fill no)
			(layer "B.Fab")
		)
		(pad "1" smd custom
			(at 0 -0.4318)
			(size 0.127 0.127)
			(layers "B.Cu" "B.Mask" "B.Paste")
			(net "SVID_CLK_R")
			(options
				(clearance outline)
				(anchor circle)
			)
			(primitives
				(gr_poly
					(pts
						(arc
							(start -0.2032 0.2794)
							(mid -0.239121 0.264521)
							(end -0.254 0.2286)
						)
						(arc
							(start -0.254 -0.2286)
							(mid -0.239121 -0.264521)
							(end -0.2032 -0.2794)
						)
						(arc
							(start 0.2032 -0.2794)
							(mid 0.239121 -0.264521)
							(end 0.254 -0.2286)
						)
						(arc
							(start 0.254 0.2286)
							(mid 0.239121 0.264521)
							(end 0.2032 0.2794)
						)
					)
					(width 0)
					(fill yes)
				)
			)
		)
		(pad "2" smd custom
			(at 0 0.4318)
			(size 0.127 0.127)
			(layers "B.Cu" "B.Mask" "B.Paste")
			(net "SVID_CPU_CLK")
			(options
				(clearance outline)
				(anchor circle)
			)
			(primitives
				(gr_poly
					(pts
						(arc
							(start -0.2032 0.2794)
							(mid -0.239121 0.264521)
							(end -0.254 0.2286)
						)
						(arc
							(start -0.254 -0.2286)
							(mid -0.239121 -0.264521)
							(end -0.2032 -0.2794)
						)
						(arc
							(start 0.2032 -0.2794)
							(mid 0.239121 -0.264521)
							(end 0.254 -0.2286)
						)
						(arc
							(start 0.254 0.2286)
							(mid 0.239121 0.264521)
							(end 0.2032 0.2794)
						)
					)
					(width 0)
					(fill yes)
				)
			)
		)
	)
	(footprint ""
		(layer "B.Cu")
		(at 18.923 -22.352 -90)
		(property "Reference" "PR101"
			(at 0 0 90)
			(layer "B.SilkS")
			(hide yes)
			(effects
				(font
					(size 1.27 1.27)
				)
				(justify mirror)
			)
		)
		(property "Value" "10KR2F-L1-GP"
			(at -1.7907 -1.1176 270)
			(unlocked yes)
			(layer "B.Fab")
			(hide yes)
			(effects
				(font
					(size 1.016 1.016)
					(thickness 0.1524)
				)
				(justify mirror)
			)
		)
		(property "Device Type" "R402H15"
			(at -1.7907 -2.6416 270)
			(unlocked yes)
			(layer "B.Fab")
			(hide yes)
			(effects
				(font
					(size 1.016 1.016)
					(thickness 0.1524)
				)
				(justify mirror)
			)
		)
		(duplicate_pad_numbers_are_jumpers no)
		(fp_rect
			(start 0.381 0.8382)
			(end -0.381 -0.8382)
			(stroke
				(width 0)
				(type default)
			)
			(fill no)
			(layer "B.CrtYd")
		)
		(fp_rect
			(start 0.381 0.8382)
			(end -0.381 -0.8382)
			(stroke
				(width 0)
				(type default)
			)
			(fill no)
			(layer "B.Fab")
		)
		(pad "1" smd custom
			(at 0 -0.4318 90)
			(size 0.127 0.127)
			(layers "B.Cu" "B.Mask" "B.Paste")
			(net "P3V3_STBY")
			(options
				(clearance outline)
				(anchor circle)
			)
			(primitives
				(gr_poly
					(pts
						(arc
							(start -0.2032 0.2794)
							(mid -0.239121 0.264521)
							(end -0.254 0.2286)
						)
						(arc
							(start -0.254 -0.2286)
							(mid -0.239121 -0.264521)
							(end -0.2032 -0.2794)
						)
						(arc
							(start 0.2032 -0.2794)
							(mid 0.239121 -0.264521)
							(end 0.254 -0.2286)
						)
						(arc
							(start 0.254 0.2286)
							(mid 0.239121 0.264521)
							(end 0.2032 0.2794)
						)
					)
					(width 0)
					(fill yes)
				)
			)
		)
		(pad "2" smd custom
			(at 0 0.4318 90)
			(size 0.127 0.127)
			(layers "B.Cu" "B.Mask" "B.Paste")
			(net "P1V0_EN")
			(options
				(clearance outline)
				(anchor circle)
			)
			(primitives
				(gr_poly
					(pts
						(arc
							(start -0.2032 0.2794)
							(mid -0.239121 0.264521)
							(end -0.254 0.2286)
						)
						(arc
							(start -0.254 -0.2286)
							(mid -0.239121 -0.264521)
							(end -0.2032 -0.2794)
						)
						(arc
							(start 0.2032 -0.2794)
							(mid 0.239121 -0.264521)
							(end 0.254 -0.2286)
						)
						(arc
							(start 0.254 0.2286)
							(mid 0.239121 0.264521)
							(end 0.2032 0.2794)
						)
					)
					(width 0)
					(fill yes)
				)
			)
		)
	)
	(footprint ""
		(layer "B.Cu")
		(at 91.7702 -41.5798 180)
		(property "Reference" "C178"
			(at 0 0 0)
			(layer "B.SilkS")
			(hide yes)
			(effects
				(font
					(size 1.27 1.27)
				)
				(justify mirror)
			)
		)
		(property "Value" "SC1U10V2KX-1GP"
			(at -1.1811 -2.7051 180)
			(unlocked yes)
			(layer "B.Fab")
			(hide yes)
			(effects
				(font
					(size 1.016 1.016)
					(thickness 0.1524)
				)
				(justify mirror)
			)
		)
		(property "Device Type" "C402H22"
			(at -1.1811 -4.2291 180)
			(unlocked yes)
			(layer "B.Fab")
			(hide yes)
			(effects
				(font
					(size 1.016 1.016)
					(thickness 0.1524)
				)
				(justify mirror)
			)
		)
		(duplicate_pad_numbers_are_jumpers no)
		(fp_rect
			(start 0.381 0.7366)
			(end -0.381 -0.7366)
			(stroke
				(width 0)
				(type default)
			)
			(fill no)
			(layer "B.CrtYd")
		)
		(fp_rect
			(start 0.381 0.7366)
			(end -0.381 -0.7366)
			(stroke
				(width 0)
				(type default)
			)
			(fill no)
			(layer "B.Fab")
		)
		(pad "1" smd custom
			(at 0 -0.4572)
			(size 0.1143 0.1143)
			(layers "B.Cu" "B.Mask" "B.Paste")
			(net "P1V8")
			(options
				(clearance outline)
				(anchor circle)
			)
			(primitives
				(gr_poly
					(pts
						(arc
							(start -0.254 0.1778)
							(mid -0.239121 0.213721)
							(end -0.2032 0.2286)
						)
						(arc
							(start 0.2032 0.2286)
							(mid 0.239121 0.213721)
							(end 0.254 0.1778)
						)
						(arc
							(start 0.254 -0.1778)
							(mid 0.239121 -0.213721)
							(end 0.2032 -0.2286)
						)
						(arc
							(start -0.2032 -0.2286)
							(mid -0.239121 -0.213721)
							(end -0.254 -0.1778)
						)
					)
					(width 0)
					(fill yes)
				)
			)
		)
		(pad "2" smd custom
			(at 0 0.4572)
			(size 0.1143 0.1143)
			(layers "B.Cu" "B.Mask" "B.Paste")
			(net "GND")
			(options
				(clearance outline)
				(anchor circle)
			)
			(primitives
				(gr_poly
					(pts
						(arc
							(start -0.254 0.1778)
							(mid -0.239121 0.213721)
							(end -0.2032 0.2286)
						)
						(arc
							(start 0.2032 0.2286)
							(mid 0.239121 0.213721)
							(end 0.254 0.1778)
						)
						(arc
							(start 0.254 -0.1778)
							(mid 0.239121 -0.213721)
							(end 0.2032 -0.2286)
						)
						(arc
							(start -0.2032 -0.2286)
							(mid -0.239121 -0.213721)
							(end -0.254 -0.1778)
						)
					)
					(width 0)
					(fill yes)
				)
			)
		)
	)
	(footprint ""
		(layer "B.Cu")
		(at 132.715 -27.305 -90)
		(property "Reference" "R34"
			(at 0 0 90)
			(layer "B.SilkS")
			(hide yes)
			(effects
				(font
					(size 1.27 1.27)
				)
				(justify mirror)
			)
		)
		(property "Value" "49D9R2F-GP"
			(at -0.064008 -3.993896 270)
			(unlocked yes)
			(layer "B.Fab")
			(hide yes)
			(effects
				(font
					(size 1.016 1.016)
					(thickness 0.1524)
				)
				(justify mirror)
			)
		)
		(property "Device Type" "R402H16"
			(at -0.064008 -5.517896 270)
			(unlocked yes)
			(layer "B.Fab")
			(hide yes)
			(effects
				(font
					(size 1.016 1.016)
					(thickness 0.1524)
				)
				(justify mirror)
			)
		)
		(duplicate_pad_numbers_are_jumpers no)
		(fp_rect
			(start 0.381 0.8382)
			(end -0.381 -0.8382)
			(stroke
				(width 0)
				(type default)
			)
			(fill no)
			(layer "B.CrtYd")
		)
		(fp_rect
			(start 0.381 0.8382)
			(end -0.381 -0.8382)
			(stroke
				(width 0)
				(type default)
			)
			(fill no)
			(layer "B.Fab")
		)
		(pad "1" smd custom
			(at 0 -0.4318 90)
			(size 0.127 0.127)
			(layers "B.Cu" "B.Mask" "B.Paste")
			(net "P1V0")
			(options
				(clearance outline)
				(anchor circle)
			)
			(primitives
				(gr_poly
					(pts
						(arc
							(start -0.2032 0.2794)
							(mid -0.239121 0.264521)
							(end -0.254 0.2286)
						)
						(arc
							(start -0.254 -0.2286)
							(mid -0.239121 -0.264521)
							(end -0.2032 -0.2794)
						)
						(arc
							(start 0.2032 -0.2794)
							(mid 0.239121 -0.264521)
							(end 0.254 -0.2286)
						)
						(arc
							(start 0.254 0.2286)
							(mid 0.239121 0.264521)
							(end 0.2032 0.2794)
						)
					)
					(width 0)
					(fill yes)
				)
			)
		)
		(pad "2" smd custom
			(at 0 0.4318 90)
			(size 0.127 0.127)
			(layers "B.Cu" "B.Mask" "B.Paste")
			(net "CPU_THERMTRIP#")
			(options
				(clearance outline)
				(anchor circle)
			)
			(primitives
				(gr_poly
					(pts
						(arc
							(start -0.2032 0.2794)
							(mid -0.239121 0.264521)
							(end -0.254 0.2286)
						)
						(arc
							(start -0.254 -0.2286)
							(mid -0.239121 -0.264521)
							(end -0.2032 -0.2794)
						)
						(arc
							(start 0.2032 -0.2794)
							(mid 0.239121 -0.264521)
							(end 0.254 -0.2286)
						)
						(arc
							(start 0.254 0.2286)
							(mid 0.239121 0.264521)
							(end 0.2032 0.2794)
						)
					)
					(width 0)
					(fill yes)
				)
			)
		)
	)
	(footprint ""
		(layer "B.Cu")
		(at 105.664 -27.321002)
		(property "Reference" "C240"
			(at 0 0 0)
			(layer "B.SilkS")
			(hide yes)
			(effects
				(font
					(size 1.27 1.27)
				)
				(justify mirror)
			)
		)
		(property "Value" "SC1U10V2KX-1GP"
			(at -1.1811 -2.7051 0)
			(unlocked yes)
			(layer "B.Fab")
			(hide yes)
			(effects
				(font
					(size 1.016 1.016)
					(thickness 0.1524)
				)
				(justify mirror)
			)
		)
		(property "Device Type" "C402H22"
			(at -1.1811 -4.2291 0)
			(unlocked yes)
			(layer "B.Fab")
			(hide yes)
			(effects
				(font
					(size 1.016 1.016)
					(thickness 0.1524)
				)
				(justify mirror)
			)
		)
		(duplicate_pad_numbers_are_jumpers no)
		(fp_rect
			(start 0.381 0.7366)
			(end -0.381 -0.7366)
			(stroke
				(width 0)
				(type default)
			)
			(fill no)
			(layer "B.CrtYd")
		)
		(fp_rect
			(start 0.381 0.7366)
			(end -0.381 -0.7366)
			(stroke
				(width 0)
				(type default)
			)
			(fill no)
			(layer "B.Fab")
		)
		(pad "1" smd custom
			(at 0 -0.4572 180)
			(size 0.1143 0.1143)
			(layers "B.Cu" "B.Mask" "B.Paste")
			(net "PV_VDDR")
			(options
				(clearance outline)
				(anchor circle)
			)
			(primitives
				(gr_poly
					(pts
						(arc
							(start -0.254 0.1778)
							(mid -0.239121 0.213721)
							(end -0.2032 0.2286)
						)
						(arc
							(start 0.2032 0.2286)
							(mid 0.239121 0.213721)
							(end 0.254 0.1778)
						)
						(arc
							(start 0.254 -0.1778)
							(mid 0.239121 -0.213721)
							(end 0.2032 -0.2286)
						)
						(arc
							(start -0.2032 -0.2286)
							(mid -0.239121 -0.213721)
							(end -0.254 -0.1778)
						)
					)
					(width 0)
					(fill yes)
				)
			)
		)
		(pad "2" smd custom
			(at 0 0.4572 180)
			(size 0.1143 0.1143)
			(layers "B.Cu" "B.Mask" "B.Paste")
			(net "GND")
			(options
				(clearance outline)
				(anchor circle)
			)
			(primitives
				(gr_poly
					(pts
						(arc
							(start -0.254 0.1778)
							(mid -0.239121 0.213721)
							(end -0.2032 0.2286)
						)
						(arc
							(start 0.2032 0.2286)
							(mid 0.239121 0.213721)
							(end 0.254 0.1778)
						)
						(arc
							(start 0.254 -0.1778)
							(mid 0.239121 -0.213721)
							(end 0.2032 -0.2286)
						)
						(arc
							(start -0.2032 -0.2286)
							(mid -0.239121 -0.213721)
							(end -0.254 -0.1778)
						)
					)
					(width 0)
					(fill yes)
				)
			)
		)
	)
	(footprint ""
		(layer "B.Cu")
		(at 74.168 -46.101 90)
		(property "Reference" "R292"
			(at 0 0 90)
			(layer "B.SilkS")
			(hide yes)
			(effects
				(font
					(size 1.27 1.27)
				)
				(justify mirror)
			)
		)
		(property "Value" "22R2F-1-GP"
			(at -0.064008 -3.993896 90)
			(unlocked yes)
			(layer "B.Fab")
			(hide yes)
			(effects
				(font
					(size 1.016 1.016)
					(thickness 0.1524)
				)
				(justify mirror)
			)
		)
		(property "Device Type" "R402H16"
			(at -0.064008 -5.517896 90)
			(unlocked yes)
			(layer "B.Fab")
			(hide yes)
			(effects
				(font
					(size 1.016 1.016)
					(thickness 0.1524)
				)
				(justify mirror)
			)
		)
		(duplicate_pad_numbers_are_jumpers no)
		(fp_rect
			(start 0.381 0.8382)
			(end -0.381 -0.8382)
			(stroke
				(width 0)
				(type default)
			)
			(fill no)
			(layer "B.CrtYd")
		)
		(fp_rect
			(start 0.381 0.8382)
			(end -0.381 -0.8382)
			(stroke
				(width 0)
				(type default)
			)
			(fill no)
			(layer "B.Fab")
		)
		(pad "1" smd custom
			(at 0 -0.4318 270)
			(size 0.127 0.127)
			(layers "B.Cu" "B.Mask" "B.Paste")
			(net "PMU_RESETBUTTON#")
			(options
				(clearance outline)
				(anchor circle)
			)
			(primitives
				(gr_poly
					(pts
						(arc
							(start -0.2032 0.2794)
							(mid -0.239121 0.264521)
							(end -0.254 0.2286)
						)
						(arc
							(start -0.254 -0.2286)
							(mid -0.239121 -0.264521)
							(end -0.2032 -0.2794)
						)
						(arc
							(start 0.2032 -0.2794)
							(mid 0.239121 -0.264521)
							(end 0.254 -0.2286)
						)
						(arc
							(start 0.254 0.2286)
							(mid 0.239121 0.264521)
							(end 0.2032 0.2794)
						)
					)
					(width 0)
					(fill yes)
				)
			)
		)
		(pad "2" smd custom
			(at 0 0.4318 270)
			(size 0.127 0.127)
			(layers "B.Cu" "B.Mask" "B.Paste")
			(net "PMU_RESETBUTTON_R#")
			(options
				(clearance outline)
				(anchor circle)
			)
			(primitives
				(gr_poly
					(pts
						(arc
							(start -0.2032 0.2794)
							(mid -0.239121 0.264521)
							(end -0.254 0.2286)
						)
						(arc
							(start -0.254 -0.2286)
							(mid -0.239121 -0.264521)
							(end -0.2032 -0.2794)
						)
						(arc
							(start 0.2032 -0.2794)
							(mid 0.239121 -0.264521)
							(end 0.254 -0.2286)
						)
						(arc
							(start 0.254 0.2286)
							(mid 0.239121 0.264521)
							(end 0.2032 0.2794)
						)
					)
					(width 0)
					(fill yes)
				)
			)
		)
	)
	(footprint ""
		(layer "B.Cu")
		(at 84.709 -62.865)
		(property "Reference" "Q12"
			(at 0 0 0)
			(layer "B.SilkS")
			(hide yes)
			(effects
				(font
					(size 1.27 1.27)
				)
				(justify mirror)
			)
		)
		(property "Value" "MMBT3904TT1G-GP"
			(at 0 -9.7282 0)
			(unlocked yes)
			(layer "B.Fab")
			(hide yes)
			(effects
				(font
					(size 1.016 1.016)
					(thickness 0.1524)
				)
				(justify mirror)
			)
		)
		(property "Device Type" "SC75CBE1D6H36"
			(at 0 -11.6332 0)
			(unlocked yes)
			(layer "B.Fab")
			(hide yes)
			(effects
				(font
					(size 1.016 1.016)
					(thickness 0.1524)
				)
				(justify mirror)
			)
		)
		(duplicate_pad_numbers_are_jumpers no)
		(fp_poly
			(pts
				(xy -0.381 -1.1938) (xy 0.381 -1.1938) (xy 0.381 -0.6604) (xy 1.0541 -0.6604) (xy 1.0541 0.6604)
				(xy 0.889 0.6604) (xy 0.889 1.1938) (xy -0.889 1.1938) (xy -0.889 0.6604) (xy -1.0541 0.6604) (xy -1.0541 -0.6604)
				(xy -0.381 -0.6604)
			)
			(stroke
				(width 0)
				(type default)
			)
			(fill no)
			(layer "B.CrtYd")
		)
		(fp_poly
			(pts
				(xy -0.381 -1.1938) (xy 0.381 -1.1938) (xy 0.381 -0.6604) (xy 1.0541 -0.6604) (xy 1.0541 0.6604)
				(xy 0.889 0.6604) (xy 0.889 1.1938) (xy -0.889 1.1938) (xy -0.889 0.6604) (xy -1.0541 0.6604) (xy -1.0541 -0.6604)
				(xy -0.381 -0.6604)
			)
			(stroke
				(width 0)
				(type default)
			)
			(fill no)
			(layer "B.Fab")
		)
		(pad "B" smd custom
			(at 0.508 0.6604 180)
			(size 0.127 0.127)
			(layers "B.Cu" "B.Mask" "B.Paste")
			(net "H_PROCESSOR_HOT_N_R")
			(options
				(clearance outline)
				(anchor circle)
			)
			(primitives
				(gr_poly
					(pts
						(arc
							(start -0.0508 -0.4064)
							(mid -0.194484 -0.346884)
							(end -0.254 -0.2032)
						)
						(arc
							(start -0.254 0.2032)
							(mid -0.194484 0.346884)
							(end -0.0508 0.4064)
						)
						(arc
							(start 0.0508 0.4064)
							(mid 0.194484 0.346884)
							(end 0.254 0.2032)
						)
						(arc
							(start 0.254 -0.2032)
							(mid 0.194484 -0.346884)
							(end 0.0508 -0.4064)
						)
					)
					(width 0)
					(fill yes)
				)
			)
		)
		(pad "C" smd custom
			(at 0 -0.6604 180)
			(size 0.127 0.127)
			(layers "B.Cu" "B.Mask" "B.Paste")
			(net "PROCESSOR_HOT_LVC#")
			(options
				(clearance outline)
				(anchor circle)
			)
			(primitives
				(gr_poly
					(pts
						(arc
							(start -0.0508 -0.4064)
							(mid -0.194484 -0.346884)
							(end -0.254 -0.2032)
						)
						(arc
							(start -0.254 0.2032)
							(mid -0.194484 0.346884)
							(end -0.0508 0.4064)
						)
						(arc
							(start 0.0508 0.4064)
							(mid 0.194484 0.346884)
							(end 0.254 0.2032)
						)
						(arc
							(start 0.254 -0.2032)
							(mid 0.194484 -0.346884)
							(end 0.0508 -0.4064)
						)
					)
					(width 0)
					(fill yes)
				)
			)
		)
		(pad "E" smd custom
			(at -0.508 0.6604 180)
			(size 0.127 0.127)
			(layers "B.Cu" "B.Mask" "B.Paste")
			(net "PROCESSOR_HOT#")
			(options
				(clearance outline)
				(anchor circle)
			)
			(primitives
				(gr_poly
					(pts
						(arc
							(start -0.0508 -0.4064)
							(mid -0.194484 -0.346884)
							(end -0.254 -0.2032)
						)
						(arc
							(start -0.254 0.2032)
							(mid -0.194484 0.346884)
							(end -0.0508 0.4064)
						)
						(arc
							(start 0.0508 0.4064)
							(mid 0.194484 0.346884)
							(end 0.254 0.2032)
						)
						(arc
							(start 0.254 -0.2032)
							(mid 0.194484 -0.346884)
							(end 0.0508 -0.4064)
						)
					)
					(width 0)
					(fill yes)
				)
			)
		)
	)
	(footprint ""
		(layer "B.Cu")
		(at 105.156 -19.177)
		(property "Reference" "C255"
			(at 0 0 0)
			(layer "B.SilkS")
			(hide yes)
			(effects
				(font
					(size 1.27 1.27)
				)
				(justify mirror)
			)
		)
		(property "Value" "SC10U6D3V3MX-GP"
			(at 0 -2.8194 0)
			(unlocked yes)
			(layer "B.Fab")
			(hide yes)
			(effects
				(font
					(size 1.016 1.016)
					(thickness 0.1524)
				)
				(justify mirror)
			)
		)
		(property "Device Type" "C603H38"
			(at 0 -4.3434 0)
			(unlocked yes)
			(layer "B.Fab")
			(hide yes)
			(effects
				(font
					(size 1.016 1.016)
					(thickness 0.1524)
				)
				(justify mirror)
			)
		)
		(duplicate_pad_numbers_are_jumpers no)
		(fp_line
			(start 0.4064 0)
			(end -0.4064 0)
			(stroke
				(width 0.2286)
				(type default)
			)
			(layer "B.SilkS")
		)
		(fp_rect
			(start 0.635 1.1811)
			(end -0.635 -1.1811)
			(stroke
				(width 0)
				(type default)
			)
			(fill no)
			(layer "B.CrtYd")
		)
		(fp_rect
			(start 0.635 1.1811)
			(end -0.635 -1.1811)
			(stroke
				(width 0)
				(type default)
			)
			(fill no)
			(layer "B.Fab")
		)
		(pad "1" smd custom
			(at 0 -0.6604 180)
			(size 0.19685 0.19685)
			(layers "B.Cu" "B.Mask" "B.Paste")
			(net "VCCCLKDDR1")
			(options
				(clearance outline)
				(anchor circle)
			)
			(primitives
				(gr_poly
					(pts
						(arc
							(start 0.508 0.2921)
							(mid 0.478242 0.363942)
							(end 0.4064 0.3937)
						)
						(arc
							(start -0.4064 0.3937)
							(mid -0.478242 0.363942)
							(end -0.508 0.2921)
						)
						(arc
							(start -0.508 -0.2921)
							(mid -0.478242 -0.363942)
							(end -0.4064 -0.3937)
						)
						(arc
							(start 0.4064 -0.3937)
							(mid 0.478242 -0.363942)
							(end 0.508 -0.2921)
						)
					)
					(width 0)
					(fill yes)
				)
			)
		)
		(pad "2" smd custom
			(at 0 0.6604 180)
			(size 0.19685 0.19685)
			(layers "B.Cu" "B.Mask" "B.Paste")
			(net "GND")
			(options
				(clearance outline)
				(anchor circle)
			)
			(primitives
				(gr_poly
					(pts
						(arc
							(start 0.508 0.2921)
							(mid 0.478242 0.363942)
							(end 0.4064 0.3937)
						)
						(arc
							(start -0.4064 0.3937)
							(mid -0.478242 0.363942)
							(end -0.508 0.2921)
						)
						(arc
							(start -0.508 -0.2921)
							(mid -0.478242 -0.363942)
							(end -0.4064 -0.3937)
						)
						(arc
							(start 0.4064 -0.3937)
							(mid 0.478242 -0.363942)
							(end 0.508 -0.2921)
						)
					)
					(width 0)
					(fill yes)
				)
			)
		)
	)
	(footprint ""
		(layer "B.Cu")
		(at 74.041 -33.274 90)
		(property "Reference" "R108"
			(at 0 0 90)
			(layer "B.SilkS")
			(hide yes)
			(effects
				(font
					(size 1.27 1.27)
				)
				(justify mirror)
			)
		)
		(property "Value" "4K7R2F-GP"
			(at -0.064008 -3.993896 90)
			(unlocked yes)
			(layer "B.Fab")
			(hide yes)
			(effects
				(font
					(size 1.016 1.016)
					(thickness 0.1524)
				)
				(justify mirror)
			)
		)
		(property "Device Type" "R402H16"
			(at -0.064008 -5.517896 90)
			(unlocked yes)
			(layer "B.Fab")
			(hide yes)
			(effects
				(font
					(size 1.016 1.016)
					(thickness 0.1524)
				)
				(justify mirror)
			)
		)
		(duplicate_pad_numbers_are_jumpers no)
		(fp_rect
			(start 0.381 0.8382)
			(end -0.381 -0.8382)
			(stroke
				(width 0)
				(type default)
			)
			(fill no)
			(layer "B.CrtYd")
		)
		(fp_rect
			(start 0.381 0.8382)
			(end -0.381 -0.8382)
			(stroke
				(width 0)
				(type default)
			)
			(fill no)
			(layer "B.Fab")
		)
		(pad "1" smd custom
			(at 0 -0.4318 270)
			(size 0.127 0.127)
			(layers "B.Cu" "B.Mask" "B.Paste")
			(net "P3V3_CPU")
			(options
				(clearance outline)
				(anchor circle)
			)
			(primitives
				(gr_poly
					(pts
						(arc
							(start -0.2032 0.2794)
							(mid -0.239121 0.264521)
							(end -0.254 0.2286)
						)
						(arc
							(start -0.254 -0.2286)
							(mid -0.239121 -0.264521)
							(end -0.2032 -0.2794)
						)
						(arc
							(start 0.2032 -0.2794)
							(mid 0.239121 -0.264521)
							(end 0.254 -0.2286)
						)
						(arc
							(start 0.254 0.2286)
							(mid 0.239121 0.264521)
							(end 0.2032 0.2794)
						)
					)
					(width 0)
					(fill yes)
				)
			)
		)
		(pad "2" smd custom
			(at 0 0.4318 270)
			(size 0.127 0.127)
			(layers "B.Cu" "B.Mask" "B.Paste")
			(net "CPU_FPGA_DISABLE")
			(options
				(clearance outline)
				(anchor circle)
			)
			(primitives
				(gr_poly
					(pts
						(arc
							(start -0.2032 0.2794)
							(mid -0.239121 0.264521)
							(end -0.254 0.2286)
						)
						(arc
							(start -0.254 -0.2286)
							(mid -0.239121 -0.264521)
							(end -0.2032 -0.2794)
						)
						(arc
							(start 0.2032 -0.2794)
							(mid 0.239121 -0.264521)
							(end 0.254 -0.2286)
						)
						(arc
							(start 0.254 0.2286)
							(mid 0.239121 0.264521)
							(end 0.2032 0.2794)
						)
					)
					(width 0)
					(fill yes)
				)
			)
		)
	)
	(footprint ""
		(layer "B.Cu")
		(at 118.999 -65.151 180)
		(property "Reference" "R498"
			(at 0 0 0)
			(layer "B.SilkS")
			(hide yes)
			(effects
				(font
					(size 1.27 1.27)
				)
				(justify mirror)
			)
		)
		(property "Value" "4K7R2F-GP"
			(at -1.7907 -1.1176 180)
			(unlocked yes)
			(layer "B.Fab")
			(hide yes)
			(effects
				(font
					(size 1.016 1.016)
					(thickness 0.1524)
				)
				(justify mirror)
			)
		)
		(property "Device Type" "R402H16"
			(at -1.7907 -2.6416 180)
			(unlocked yes)
			(layer "B.Fab")
			(hide yes)
			(effects
				(font
					(size 1.016 1.016)
					(thickness 0.1524)
				)
				(justify mirror)
			)
		)
		(duplicate_pad_numbers_are_jumpers no)
		(fp_rect
			(start 0.381 0.8382)
			(end -0.381 -0.8382)
			(stroke
				(width 0)
				(type default)
			)
			(fill no)
			(layer "B.CrtYd")
		)
		(fp_rect
			(start 0.381 0.8382)
			(end -0.381 -0.8382)
			(stroke
				(width 0)
				(type default)
			)
			(fill no)
			(layer "B.Fab")
		)
		(pad "1" smd custom
			(at 0 -0.4318)
			(size 0.127 0.127)
			(layers "B.Cu" "B.Mask" "B.Paste")
			(net "P3V3_STBY")
			(options
				(clearance outline)
				(anchor circle)
			)
			(primitives
				(gr_poly
					(pts
						(arc
							(start -0.2032 0.2794)
							(mid -0.239121 0.264521)
							(end -0.254 0.2286)
						)
						(arc
							(start -0.254 -0.2286)
							(mid -0.239121 -0.264521)
							(end -0.2032 -0.2794)
						)
						(arc
							(start 0.2032 -0.2794)
							(mid 0.239121 -0.264521)
							(end 0.254 -0.2286)
						)
						(arc
							(start 0.254 0.2286)
							(mid 0.239121 0.264521)
							(end 0.2032 0.2794)
						)
					)
					(width 0)
					(fill yes)
				)
			)
		)
		(pad "2" smd custom
			(at 0 0.4318)
			(size 0.127 0.127)
			(layers "B.Cu" "B.Mask" "B.Paste")
			(net "SMB_HOST_LV_CLK")
			(options
				(clearance outline)
				(anchor circle)
			)
			(primitives
				(gr_poly
					(pts
						(arc
							(start -0.2032 0.2794)
							(mid -0.239121 0.264521)
							(end -0.254 0.2286)
						)
						(arc
							(start -0.254 -0.2286)
							(mid -0.239121 -0.264521)
							(end -0.2032 -0.2794)
						)
						(arc
							(start 0.2032 -0.2794)
							(mid 0.239121 -0.264521)
							(end 0.254 -0.2286)
						)
						(arc
							(start 0.254 0.2286)
							(mid 0.239121 0.264521)
							(end 0.2032 0.2794)
						)
					)
					(width 0)
					(fill yes)
				)
			)
		)
	)
	(footprint ""
		(layer "B.Cu")
		(at 74.041 -36.703 90)
		(property "Reference" "R82"
			(at 0 0 90)
			(layer "B.SilkS")
			(hide yes)
			(effects
				(font
					(size 1.27 1.27)
				)
				(justify mirror)
			)
		)
		(property "Value" "10KR2F-2-GP"
			(at -0.064008 -3.993896 90)
			(unlocked yes)
			(layer "B.Fab")
			(hide yes)
			(effects
				(font
					(size 1.016 1.016)
					(thickness 0.1524)
				)
				(justify mirror)
			)
		)
		(property "Device Type" "R402H16"
			(at -0.064008 -5.517896 90)
			(unlocked yes)
			(layer "B.Fab")
			(hide yes)
			(effects
				(font
					(size 1.016 1.016)
					(thickness 0.1524)
				)
				(justify mirror)
			)
		)
		(duplicate_pad_numbers_are_jumpers no)
		(fp_rect
			(start 0.381 0.8382)
			(end -0.381 -0.8382)
			(stroke
				(width 0)
				(type default)
			)
			(fill no)
			(layer "B.CrtYd")
		)
		(fp_rect
			(start 0.381 0.8382)
			(end -0.381 -0.8382)
			(stroke
				(width 0)
				(type default)
			)
			(fill no)
			(layer "B.Fab")
		)
		(pad "1" smd custom
			(at 0 -0.4318 270)
			(size 0.127 0.127)
			(layers "B.Cu" "B.Mask" "B.Paste")
			(net "P3V3")
			(options
				(clearance outline)
				(anchor circle)
			)
			(primitives
				(gr_poly
					(pts
						(arc
							(start -0.2032 0.2794)
							(mid -0.239121 0.264521)
							(end -0.254 0.2286)
						)
						(arc
							(start -0.254 -0.2286)
							(mid -0.239121 -0.264521)
							(end -0.2032 -0.2794)
						)
						(arc
							(start 0.2032 -0.2794)
							(mid 0.239121 -0.264521)
							(end 0.254 -0.2286)
						)
						(arc
							(start 0.254 0.2286)
							(mid 0.239121 0.264521)
							(end 0.2032 0.2794)
						)
					)
					(width 0)
					(fill yes)
				)
			)
		)
		(pad "2" smd custom
			(at 0 0.4318 270)
			(size 0.127 0.127)
			(layers "B.Cu" "B.Mask" "B.Paste")
			(net "FLEX_CLK_SE1")
			(options
				(clearance outline)
				(anchor circle)
			)
			(primitives
				(gr_poly
					(pts
						(arc
							(start -0.2032 0.2794)
							(mid -0.239121 0.264521)
							(end -0.254 0.2286)
						)
						(arc
							(start -0.254 -0.2286)
							(mid -0.239121 -0.264521)
							(end -0.2032 -0.2794)
						)
						(arc
							(start 0.2032 -0.2794)
							(mid 0.239121 -0.264521)
							(end 0.254 -0.2286)
						)
						(arc
							(start 0.254 0.2286)
							(mid 0.239121 0.264521)
							(end 0.2032 0.2794)
						)
					)
					(width 0)
					(fill yes)
				)
			)
		)
	)
	(footprint ""
		(layer "B.Cu")
		(at 85.598 -33.274 90)
		(property "Reference" "R345"
			(at 0 0 90)
			(layer "B.SilkS")
			(hide yes)
			(effects
				(font
					(size 1.27 1.27)
				)
				(justify mirror)
			)
		)
		(property "Value" "100R3F-1-GP"
			(at 0.0254 -2.5146 90)
			(unlocked yes)
			(layer "B.Fab")
			(hide yes)
			(effects
				(font
					(size 1.016 1.016)
					(thickness 0.1524)
				)
				(justify mirror)
			)
		)
		(property "Device Type" "R603H22"
			(at 0.0254 -4.0386 90)
			(unlocked yes)
			(layer "B.Fab")
			(hide yes)
			(effects
				(font
					(size 1.016 1.016)
					(thickness 0.1524)
				)
				(justify mirror)
			)
		)
		(duplicate_pad_numbers_are_jumpers no)
		(fp_line
			(start 0.2032 0)
			(end 0.4191 0)
			(stroke
				(width 0.2032)
				(type default)
			)
			(layer "B.SilkS")
		)
		(fp_line
			(start -0.4318 0)
			(end -0.2032 0)
			(stroke
				(width 0.2032)
				(type default)
			)
			(layer "B.SilkS")
		)
		(fp_rect
			(start 0.635 1.1811)
			(end -0.635 -1.1811)
			(stroke
				(width 0)
				(type default)
			)
			(fill no)
			(layer "B.CrtYd")
		)
		(fp_rect
			(start 0.635 1.1811)
			(end -0.635 -1.1811)
			(stroke
				(width 0)
				(type default)
			)
			(fill no)
			(layer "B.Fab")
		)
		(pad "1" smd custom
			(at 0 -0.6604 270)
			(size 0.19685 0.19685)
			(layers "B.Cu" "B.Mask" "B.Paste")
			(net "SATA3_OBS_P")
			(options
				(clearance outline)
				(anchor circle)
			)
			(primitives
				(gr_poly
					(pts
						(arc
							(start 0.508 0.2921)
							(mid 0.478242 0.363942)
							(end 0.4064 0.3937)
						)
						(arc
							(start -0.4064 0.3937)
							(mid -0.478242 0.363942)
							(end -0.508 0.2921)
						)
						(arc
							(start -0.508 -0.2921)
							(mid -0.478242 -0.363942)
							(end -0.4064 -0.3937)
						)
						(arc
							(start 0.4064 -0.3937)
							(mid 0.478242 -0.363942)
							(end 0.508 -0.2921)
						)
					)
					(width 0)
					(fill yes)
				)
			)
		)
		(pad "2" smd custom
			(at 0 0.6604 270)
			(size 0.19685 0.19685)
			(layers "B.Cu" "B.Mask" "B.Paste")
			(net "SATA3_OBS_N")
			(options
				(clearance outline)
				(anchor circle)
			)
			(primitives
				(gr_poly
					(pts
						(arc
							(start 0.508 0.2921)
							(mid 0.478242 0.363942)
							(end 0.4064 0.3937)
						)
						(arc
							(start -0.4064 0.3937)
							(mid -0.478242 0.363942)
							(end -0.508 0.2921)
						)
						(arc
							(start -0.508 -0.2921)
							(mid -0.478242 -0.363942)
							(end -0.4064 -0.3937)
						)
						(arc
							(start 0.4064 -0.3937)
							(mid 0.478242 -0.363942)
							(end 0.508 -0.2921)
						)
					)
					(width 0)
					(fill yes)
				)
			)
		)
	)
	(footprint ""
		(layer "B.Cu")
		(at 88.265 -34.9504)
		(property "Reference" "R502"
			(at 0 0 0)
			(layer "B.SilkS")
			(hide yes)
			(effects
				(font
					(size 1.27 1.27)
				)
				(justify mirror)
			)
		)
		(property "Value" "4K7R2F-GP"
			(at -1.7907 -1.1176 0)
			(unlocked yes)
			(layer "B.Fab")
			(hide yes)
			(effects
				(font
					(size 1.016 1.016)
					(thickness 0.1524)
				)
				(justify mirror)
			)
		)
		(property "Device Type" "R402H16"
			(at -1.7907 -2.6416 0)
			(unlocked yes)
			(layer "B.Fab")
			(hide yes)
			(effects
				(font
					(size 1.016 1.016)
					(thickness 0.1524)
				)
				(justify mirror)
			)
		)
		(duplicate_pad_numbers_are_jumpers no)
		(fp_rect
			(start 0.381 0.8382)
			(end -0.381 -0.8382)
			(stroke
				(width 0)
				(type default)
			)
			(fill no)
			(layer "B.CrtYd")
		)
		(fp_rect
			(start 0.381 0.8382)
			(end -0.381 -0.8382)
			(stroke
				(width 0)
				(type default)
			)
			(fill no)
			(layer "B.Fab")
		)
		(pad "1" smd custom
			(at 0 -0.4318 180)
			(size 0.127 0.127)
			(layers "B.Cu" "B.Mask" "B.Paste")
			(net "P3V3_CPU")
			(options
				(clearance outline)
				(anchor circle)
			)
			(primitives
				(gr_poly
					(pts
						(arc
							(start -0.2032 0.2794)
							(mid -0.239121 0.264521)
							(end -0.254 0.2286)
						)
						(arc
							(start -0.254 -0.2286)
							(mid -0.239121 -0.264521)
							(end -0.2032 -0.2794)
						)
						(arc
							(start 0.2032 -0.2794)
							(mid 0.239121 -0.264521)
							(end 0.254 -0.2286)
						)
						(arc
							(start 0.254 0.2286)
							(mid 0.239121 0.264521)
							(end 0.2032 0.2794)
						)
					)
					(width 0)
					(fill yes)
				)
			)
		)
		(pad "2" smd custom
			(at 0 0.4318 180)
			(size 0.127 0.127)
			(layers "B.Cu" "B.Mask" "B.Paste")
			(net "BD_REV_1")
			(options
				(clearance outline)
				(anchor circle)
			)
			(primitives
				(gr_poly
					(pts
						(arc
							(start -0.2032 0.2794)
							(mid -0.239121 0.264521)
							(end -0.254 0.2286)
						)
						(arc
							(start -0.254 -0.2286)
							(mid -0.239121 -0.264521)
							(end -0.2032 -0.2794)
						)
						(arc
							(start 0.2032 -0.2794)
							(mid 0.239121 -0.264521)
							(end 0.254 -0.2286)
						)
						(arc
							(start 0.254 0.2286)
							(mid 0.239121 0.264521)
							(end 0.2032 0.2794)
						)
					)
					(width 0)
					(fill yes)
				)
			)
		)
	)
	(footprint ""
		(layer "B.Cu")
		(at 159.131 -12.447778 180)
		(property "Reference" "C299"
			(at 0 0 0)
			(layer "B.SilkS")
			(hide yes)
			(effects
				(font
					(size 1.27 1.27)
				)
				(justify mirror)
			)
		)
		(property "Value" "SC1U10V2KX-1GP"
			(at -1.8923 -1.2065 180)
			(unlocked yes)
			(layer "B.Fab")
			(hide yes)
			(effects
				(font
					(size 1.016 1.016)
					(thickness 0.1524)
				)
				(justify mirror)
			)
		)
		(property "Device Type" "C402H22"
			(at -1.8923 -2.7305 180)
			(unlocked yes)
			(layer "B.Fab")
			(hide yes)
			(effects
				(font
					(size 1.016 1.016)
					(thickness 0.1524)
				)
				(justify mirror)
			)
		)
		(duplicate_pad_numbers_are_jumpers no)
		(fp_rect
			(start 0.381 0.7366)
			(end -0.381 -0.7366)
			(stroke
				(width 0)
				(type default)
			)
			(fill no)
			(layer "B.CrtYd")
		)
		(fp_rect
			(start 0.381 0.7366)
			(end -0.381 -0.7366)
			(stroke
				(width 0)
				(type default)
			)
			(fill no)
			(layer "B.Fab")
		)
		(pad "1" smd custom
			(at 0 -0.4572)
			(size 0.1143 0.1143)
			(layers "B.Cu" "B.Mask" "B.Paste")
			(net "PV_VDDR")
			(options
				(clearance outline)
				(anchor circle)
			)
			(primitives
				(gr_poly
					(pts
						(arc
							(start -0.254 0.1778)
							(mid -0.239121 0.213721)
							(end -0.2032 0.2286)
						)
						(arc
							(start 0.2032 0.2286)
							(mid 0.239121 0.213721)
							(end 0.254 0.1778)
						)
						(arc
							(start 0.254 -0.1778)
							(mid 0.239121 -0.213721)
							(end 0.2032 -0.2286)
						)
						(arc
							(start -0.2032 -0.2286)
							(mid -0.239121 -0.213721)
							(end -0.254 -0.1778)
						)
					)
					(width 0)
					(fill yes)
				)
			)
		)
		(pad "2" smd custom
			(at 0 0.4572)
			(size 0.1143 0.1143)
			(layers "B.Cu" "B.Mask" "B.Paste")
			(net "GND")
			(options
				(clearance outline)
				(anchor circle)
			)
			(primitives
				(gr_poly
					(pts
						(arc
							(start -0.254 0.1778)
							(mid -0.239121 0.213721)
							(end -0.2032 0.2286)
						)
						(arc
							(start 0.2032 0.2286)
							(mid 0.239121 0.213721)
							(end 0.254 0.1778)
						)
						(arc
							(start 0.254 -0.1778)
							(mid 0.239121 -0.213721)
							(end 0.2032 -0.2286)
						)
						(arc
							(start -0.2032 -0.2286)
							(mid -0.239121 -0.213721)
							(end -0.254 -0.1778)
						)
					)
					(width 0)
					(fill yes)
				)
			)
		)
	)
	(footprint ""
		(layer "B.Cu")
		(at 26.289 -32.385 180)
		(property "Reference" "PC47"
			(at 0 0 0)
			(layer "B.SilkS")
			(hide yes)
			(effects
				(font
					(size 1.27 1.27)
				)
				(justify mirror)
			)
		)
		(property "Value" "SC22U6D3V3MX-1-GP"
			(at 0.0254 -2.0193 180)
			(unlocked yes)
			(layer "B.Fab")
			(hide yes)
			(effects
				(font
					(size 1.016 1.016)
					(thickness 0.1524)
				)
				(justify mirror)
			)
		)
		(property "Device Type" "C603H40"
			(at 0.0254 -3.5433 180)
			(unlocked yes)
			(layer "B.Fab")
			(hide yes)
			(effects
				(font
					(size 1.016 1.016)
					(thickness 0.1524)
				)
				(justify mirror)
			)
		)
		(duplicate_pad_numbers_are_jumpers no)
		(fp_line
			(start 0.4064 0)
			(end -0.4064 0)
			(stroke
				(width 0.2286)
				(type default)
			)
			(layer "B.SilkS")
		)
		(fp_rect
			(start 0.635 1.1811)
			(end -0.635 -1.1811)
			(stroke
				(width 0)
				(type default)
			)
			(fill no)
			(layer "B.CrtYd")
		)
		(fp_rect
			(start 0.635 1.1811)
			(end -0.635 -1.1811)
			(stroke
				(width 0)
				(type default)
			)
			(fill no)
			(layer "B.Fab")
		)
		(pad "1" smd custom
			(at 0 -0.6604)
			(size 0.19685 0.19685)
			(layers "B.Cu" "B.Mask" "B.Paste")
			(net "P1V0")
			(options
				(clearance outline)
				(anchor circle)
			)
			(primitives
				(gr_poly
					(pts
						(arc
							(start 0.508 0.2921)
							(mid 0.478242 0.363942)
							(end 0.4064 0.3937)
						)
						(arc
							(start -0.4064 0.3937)
							(mid -0.478242 0.363942)
							(end -0.508 0.2921)
						)
						(arc
							(start -0.508 -0.2921)
							(mid -0.478242 -0.363942)
							(end -0.4064 -0.3937)
						)
						(arc
							(start 0.4064 -0.3937)
							(mid 0.478242 -0.363942)
							(end 0.508 -0.2921)
						)
					)
					(width 0)
					(fill yes)
				)
			)
		)
		(pad "2" smd custom
			(at 0 0.6604)
			(size 0.19685 0.19685)
			(layers "B.Cu" "B.Mask" "B.Paste")
			(net "GND")
			(options
				(clearance outline)
				(anchor circle)
			)
			(primitives
				(gr_poly
					(pts
						(arc
							(start 0.508 0.2921)
							(mid 0.478242 0.363942)
							(end 0.4064 0.3937)
						)
						(arc
							(start -0.4064 0.3937)
							(mid -0.478242 0.363942)
							(end -0.508 0.2921)
						)
						(arc
							(start -0.508 -0.2921)
							(mid -0.478242 -0.363942)
							(end -0.4064 -0.3937)
						)
						(arc
							(start 0.4064 -0.3937)
							(mid 0.478242 -0.363942)
							(end 0.508 -0.2921)
						)
					)
					(width 0)
					(fill yes)
				)
			)
		)
	)
	(footprint ""
		(layer "B.Cu")
		(at 58.039 -15.24 -90)
		(property "Reference" "R434"
			(at 0 0 90)
			(layer "B.SilkS")
			(hide yes)
			(effects
				(font
					(size 1.27 1.27)
				)
				(justify mirror)
			)
		)
		(property "Value" "1KR2F-3-GP"
			(at -1.7907 -1.1176 270)
			(unlocked yes)
			(layer "B.Fab")
			(hide yes)
			(effects
				(font
					(size 1.016 1.016)
					(thickness 0.1524)
				)
				(justify mirror)
			)
		)
		(property "Device Type" "R402H16"
			(at -1.7907 -2.6416 270)
			(unlocked yes)
			(layer "B.Fab")
			(hide yes)
			(effects
				(font
					(size 1.016 1.016)
					(thickness 0.1524)
				)
				(justify mirror)
			)
		)
		(duplicate_pad_numbers_are_jumpers no)
		(fp_rect
			(start 0.381 0.8382)
			(end -0.381 -0.8382)
			(stroke
				(width 0)
				(type default)
			)
			(fill no)
			(layer "B.CrtYd")
		)
		(fp_rect
			(start 0.381 0.8382)
			(end -0.381 -0.8382)
			(stroke
				(width 0)
				(type default)
			)
			(fill no)
			(layer "B.Fab")
		)
		(pad "1" smd custom
			(at 0 -0.4318 90)
			(size 0.127 0.127)
			(layers "B.Cu" "B.Mask" "B.Paste")
			(net "P3V3")
			(options
				(clearance outline)
				(anchor circle)
			)
			(primitives
				(gr_poly
					(pts
						(arc
							(start -0.2032 0.2794)
							(mid -0.239121 0.264521)
							(end -0.254 0.2286)
						)
						(arc
							(start -0.254 -0.2286)
							(mid -0.239121 -0.264521)
							(end -0.2032 -0.2794)
						)
						(arc
							(start 0.2032 -0.2794)
							(mid 0.239121 -0.264521)
							(end 0.254 -0.2286)
						)
						(arc
							(start 0.254 0.2286)
							(mid 0.239121 0.264521)
							(end 0.2032 0.2794)
						)
					)
					(width 0)
					(fill yes)
				)
			)
		)
		(pad "2" smd custom
			(at 0 0.4318 90)
			(size 0.127 0.127)
			(layers "B.Cu" "B.Mask" "B.Paste")
			(net "PMU_BUF_PLTRST#")
			(options
				(clearance outline)
				(anchor circle)
			)
			(primitives
				(gr_poly
					(pts
						(arc
							(start -0.2032 0.2794)
							(mid -0.239121 0.264521)
							(end -0.254 0.2286)
						)
						(arc
							(start -0.254 -0.2286)
							(mid -0.239121 -0.264521)
							(end -0.2032 -0.2794)
						)
						(arc
							(start 0.2032 -0.2794)
							(mid 0.239121 -0.264521)
							(end 0.254 -0.2286)
						)
						(arc
							(start 0.254 0.2286)
							(mid 0.239121 0.264521)
							(end 0.2032 0.2794)
						)
					)
					(width 0)
					(fill yes)
				)
			)
		)
	)
	(footprint ""
		(layer "B.Cu")
		(at 15.875 -23.114 -90)
		(property "Reference" "PR90"
			(at 0 0 90)
			(layer "B.SilkS")
			(hide yes)
			(effects
				(font
					(size 1.27 1.27)
				)
				(justify mirror)
			)
		)
		(property "Value" "10KR2F-2-GP"
			(at -1.7907 -1.1176 270)
			(unlocked yes)
			(layer "B.Fab")
			(hide yes)
			(effects
				(font
					(size 1.016 1.016)
					(thickness 0.1524)
				)
				(justify mirror)
			)
		)
		(property "Device Type" "R402H16"
			(at -1.7907 -2.6416 270)
			(unlocked yes)
			(layer "B.Fab")
			(hide yes)
			(effects
				(font
					(size 1.016 1.016)
					(thickness 0.1524)
				)
				(justify mirror)
			)
		)
		(duplicate_pad_numbers_are_jumpers no)
		(fp_rect
			(start 0.381 0.8382)
			(end -0.381 -0.8382)
			(stroke
				(width 0)
				(type default)
			)
			(fill no)
			(layer "B.CrtYd")
		)
		(fp_rect
			(start 0.381 0.8382)
			(end -0.381 -0.8382)
			(stroke
				(width 0)
				(type default)
			)
			(fill no)
			(layer "B.Fab")
		)
		(pad "1" smd custom
			(at 0 -0.4318 90)
			(size 0.127 0.127)
			(layers "B.Cu" "B.Mask" "B.Paste")
			(net "PG_P1V0")
			(options
				(clearance outline)
				(anchor circle)
			)
			(primitives
				(gr_poly
					(pts
						(arc
							(start -0.2032 0.2794)
							(mid -0.239121 0.264521)
							(end -0.254 0.2286)
						)
						(arc
							(start -0.254 -0.2286)
							(mid -0.239121 -0.264521)
							(end -0.2032 -0.2794)
						)
						(arc
							(start 0.2032 -0.2794)
							(mid 0.239121 -0.264521)
							(end 0.254 -0.2286)
						)
						(arc
							(start 0.254 0.2286)
							(mid 0.239121 0.264521)
							(end 0.2032 0.2794)
						)
					)
					(width 0)
					(fill yes)
				)
			)
		)
		(pad "2" smd custom
			(at 0 0.4318 90)
			(size 0.127 0.127)
			(layers "B.Cu" "B.Mask" "B.Paste")
			(net "P1V0_VREG")
			(options
				(clearance outline)
				(anchor circle)
			)
			(primitives
				(gr_poly
					(pts
						(arc
							(start -0.2032 0.2794)
							(mid -0.239121 0.264521)
							(end -0.254 0.2286)
						)
						(arc
							(start -0.254 -0.2286)
							(mid -0.239121 -0.264521)
							(end -0.2032 -0.2794)
						)
						(arc
							(start 0.2032 -0.2794)
							(mid 0.239121 -0.264521)
							(end 0.254 -0.2286)
						)
						(arc
							(start 0.254 0.2286)
							(mid 0.239121 0.264521)
							(end 0.2032 0.2794)
						)
					)
					(width 0)
					(fill yes)
				)
			)
		)
	)
	(footprint ""
		(layer "B.Cu")
		(at 38.989 -49.6062 90)
		(property "Reference" "R128"
			(at 0 0 90)
			(layer "B.SilkS")
			(hide yes)
			(effects
				(font
					(size 1.27 1.27)
				)
				(justify mirror)
			)
		)
		(property "Value" "0R2J-2-GP"
			(at -1.7907 -1.1176 90)
			(unlocked yes)
			(layer "B.Fab")
			(hide yes)
			(effects
				(font
					(size 1.016 1.016)
					(thickness 0.1524)
				)
				(justify mirror)
			)
		)
		(property "Device Type" "R402H16"
			(at -1.7907 -2.6416 90)
			(unlocked yes)
			(layer "B.Fab")
			(hide yes)
			(effects
				(font
					(size 1.016 1.016)
					(thickness 0.1524)
				)
				(justify mirror)
			)
		)
		(duplicate_pad_numbers_are_jumpers no)
		(fp_rect
			(start 0.381 0.8382)
			(end -0.381 -0.8382)
			(stroke
				(width 0)
				(type default)
			)
			(fill no)
			(layer "B.CrtYd")
		)
		(fp_rect
			(start 0.381 0.8382)
			(end -0.381 -0.8382)
			(stroke
				(width 0)
				(type default)
			)
			(fill no)
			(layer "B.Fab")
		)
		(pad "1" smd custom
			(at 0 -0.4318 270)
			(size 0.127 0.127)
			(layers "B.Cu" "B.Mask" "B.Paste")
			(net "SMB_HOST_LV_DATA")
			(options
				(clearance outline)
				(anchor circle)
			)
			(primitives
				(gr_poly
					(pts
						(arc
							(start -0.2032 0.2794)
							(mid -0.239121 0.264521)
							(end -0.254 0.2286)
						)
						(arc
							(start -0.254 -0.2286)
							(mid -0.239121 -0.264521)
							(end -0.2032 -0.2794)
						)
						(arc
							(start 0.2032 -0.2794)
							(mid 0.239121 -0.264521)
							(end 0.254 -0.2286)
						)
						(arc
							(start 0.254 0.2286)
							(mid 0.239121 0.264521)
							(end 0.2032 0.2794)
						)
					)
					(width 0)
					(fill yes)
				)
			)
		)
		(pad "2" smd custom
			(at 0 0.4318 270)
			(size 0.127 0.127)
			(layers "B.Cu" "B.Mask" "B.Paste")
			(net "SMB_CLKGEN_R_DATA")
			(options
				(clearance outline)
				(anchor circle)
			)
			(primitives
				(gr_poly
					(pts
						(arc
							(start -0.2032 0.2794)
							(mid -0.239121 0.264521)
							(end -0.254 0.2286)
						)
						(arc
							(start -0.254 -0.2286)
							(mid -0.239121 -0.264521)
							(end -0.2032 -0.2794)
						)
						(arc
							(start 0.2032 -0.2794)
							(mid 0.239121 -0.264521)
							(end 0.254 -0.2286)
						)
						(arc
							(start 0.254 0.2286)
							(mid 0.239121 0.264521)
							(end 0.2032 0.2794)
						)
					)
					(width 0)
					(fill yes)
				)
			)
		)
	)
	(footprint ""
		(layer "B.Cu")
		(at 78.867 -15.748)
		(property "Reference" "PC205"
			(at 0 0 0)
			(layer "B.SilkS")
			(hide yes)
			(effects
				(font
					(size 1.27 1.27)
				)
				(justify mirror)
			)
		)
		(property "Value" "SCD1U16V2KX-3GP"
			(at -1.1811 -2.7051 0)
			(unlocked yes)
			(layer "B.Fab")
			(hide yes)
			(effects
				(font
					(size 1.016 1.016)
					(thickness 0.1524)
				)
				(justify mirror)
			)
		)
		(property "Device Type" "C402H22"
			(at -1.1811 -4.2291 0)
			(unlocked yes)
			(layer "B.Fab")
			(hide yes)
			(effects
				(font
					(size 1.016 1.016)
					(thickness 0.1524)
				)
				(justify mirror)
			)
		)
		(duplicate_pad_numbers_are_jumpers no)
		(fp_rect
			(start 0.381 0.7366)
			(end -0.381 -0.7366)
			(stroke
				(width 0)
				(type default)
			)
			(fill no)
			(layer "B.CrtYd")
		)
		(fp_rect
			(start 0.381 0.7366)
			(end -0.381 -0.7366)
			(stroke
				(width 0)
				(type default)
			)
			(fill no)
			(layer "B.Fab")
		)
		(pad "1" smd custom
			(at 0 -0.4572 180)
			(size 0.1143 0.1143)
			(layers "B.Cu" "B.Mask" "B.Paste")
			(net "TPS74801_P1V35_IN")
			(options
				(clearance outline)
				(anchor circle)
			)
			(primitives
				(gr_poly
					(pts
						(arc
							(start -0.254 0.1778)
							(mid -0.239121 0.213721)
							(end -0.2032 0.2286)
						)
						(arc
							(start 0.2032 0.2286)
							(mid 0.239121 0.213721)
							(end 0.254 0.1778)
						)
						(arc
							(start 0.254 -0.1778)
							(mid 0.239121 -0.213721)
							(end 0.2032 -0.2286)
						)
						(arc
							(start -0.2032 -0.2286)
							(mid -0.239121 -0.213721)
							(end -0.254 -0.1778)
						)
					)
					(width 0)
					(fill yes)
				)
			)
		)
		(pad "2" smd custom
			(at 0 0.4572 180)
			(size 0.1143 0.1143)
			(layers "B.Cu" "B.Mask" "B.Paste")
			(net "GND")
			(options
				(clearance outline)
				(anchor circle)
			)
			(primitives
				(gr_poly
					(pts
						(arc
							(start -0.254 0.1778)
							(mid -0.239121 0.213721)
							(end -0.2032 0.2286)
						)
						(arc
							(start 0.2032 0.2286)
							(mid 0.239121 0.213721)
							(end 0.254 0.1778)
						)
						(arc
							(start 0.254 -0.1778)
							(mid 0.239121 -0.213721)
							(end 0.2032 -0.2286)
						)
						(arc
							(start -0.2032 -0.2286)
							(mid -0.239121 -0.213721)
							(end -0.254 -0.1778)
						)
					)
					(width 0)
					(fill yes)
				)
			)
		)
	)
	(footprint ""
		(layer "B.Cu")
		(at 93.599 -25.4 90)
		(property "Reference" "C246"
			(at 0 0 90)
			(layer "B.SilkS")
			(hide yes)
			(effects
				(font
					(size 1.27 1.27)
				)
				(justify mirror)
			)
		)
		(property "Value" "SC1U10V2KX-1GP"
			(at -1.1811 -2.7051 90)
			(unlocked yes)
			(layer "B.Fab")
			(hide yes)
			(effects
				(font
					(size 1.016 1.016)
					(thickness 0.1524)
				)
				(justify mirror)
			)
		)
		(property "Device Type" "C402H22"
			(at -1.1811 -4.2291 90)
			(unlocked yes)
			(layer "B.Fab")
			(hide yes)
			(effects
				(font
					(size 1.016 1.016)
					(thickness 0.1524)
				)
				(justify mirror)
			)
		)
		(duplicate_pad_numbers_are_jumpers no)
		(fp_rect
			(start 0.381 0.7366)
			(end -0.381 -0.7366)
			(stroke
				(width 0)
				(type default)
			)
			(fill no)
			(layer "B.CrtYd")
		)
		(fp_rect
			(start 0.381 0.7366)
			(end -0.381 -0.7366)
			(stroke
				(width 0)
				(type default)
			)
			(fill no)
			(layer "B.Fab")
		)
		(pad "1" smd custom
			(at 0 -0.4572 270)
			(size 0.1143 0.1143)
			(layers "B.Cu" "B.Mask" "B.Paste")
			(net "P1V0")
			(options
				(clearance outline)
				(anchor circle)
			)
			(primitives
				(gr_poly
					(pts
						(arc
							(start -0.254 0.1778)
							(mid -0.239121 0.213721)
							(end -0.2032 0.2286)
						)
						(arc
							(start 0.2032 0.2286)
							(mid 0.239121 0.213721)
							(end 0.254 0.1778)
						)
						(arc
							(start 0.254 -0.1778)
							(mid 0.239121 -0.213721)
							(end 0.2032 -0.2286)
						)
						(arc
							(start -0.2032 -0.2286)
							(mid -0.239121 -0.213721)
							(end -0.254 -0.1778)
						)
					)
					(width 0)
					(fill yes)
				)
			)
		)
		(pad "2" smd custom
			(at 0 0.4572 270)
			(size 0.1143 0.1143)
			(layers "B.Cu" "B.Mask" "B.Paste")
			(net "GND")
			(options
				(clearance outline)
				(anchor circle)
			)
			(primitives
				(gr_poly
					(pts
						(arc
							(start -0.254 0.1778)
							(mid -0.239121 0.213721)
							(end -0.2032 0.2286)
						)
						(arc
							(start 0.2032 0.2286)
							(mid 0.239121 0.213721)
							(end 0.254 0.1778)
						)
						(arc
							(start 0.254 -0.1778)
							(mid 0.239121 -0.213721)
							(end 0.2032 -0.2286)
						)
						(arc
							(start -0.2032 -0.2286)
							(mid -0.239121 -0.213721)
							(end -0.254 -0.1778)
						)
					)
					(width 0)
					(fill yes)
				)
			)
		)
	)
	(footprint ""
		(layer "B.Cu")
		(at 80.01 -37.592 -90)
		(property "Reference" "R334"
			(at 0 0 90)
			(layer "B.SilkS")
			(hide yes)
			(effects
				(font
					(size 1.27 1.27)
				)
				(justify mirror)
			)
		)
		(property "Value" "33R2F-3-GP"
			(at -0.064008 -3.993896 270)
			(unlocked yes)
			(layer "B.Fab")
			(hide yes)
			(effects
				(font
					(size 1.016 1.016)
					(thickness 0.1524)
				)
				(justify mirror)
			)
		)
		(property "Device Type" "R402H16"
			(at -0.064008 -5.517896 270)
			(unlocked yes)
			(layer "B.Fab")
			(hide yes)
			(effects
				(font
					(size 1.016 1.016)
					(thickness 0.1524)
				)
				(justify mirror)
			)
		)
		(duplicate_pad_numbers_are_jumpers no)
		(fp_rect
			(start 0.381 0.8382)
			(end -0.381 -0.8382)
			(stroke
				(width 0)
				(type default)
			)
			(fill no)
			(layer "B.CrtYd")
		)
		(fp_rect
			(start 0.381 0.8382)
			(end -0.381 -0.8382)
			(stroke
				(width 0)
				(type default)
			)
			(fill no)
			(layer "B.Fab")
		)
		(pad "1" smd custom
			(at 0 -0.4318 90)
			(size 0.127 0.127)
			(layers "B.Cu" "B.Mask" "B.Paste")
			(net "PMU_SUS_CLK_CPU")
			(options
				(clearance outline)
				(anchor circle)
			)
			(primitives
				(gr_poly
					(pts
						(arc
							(start -0.2032 0.2794)
							(mid -0.239121 0.264521)
							(end -0.254 0.2286)
						)
						(arc
							(start -0.254 -0.2286)
							(mid -0.239121 -0.264521)
							(end -0.2032 -0.2794)
						)
						(arc
							(start 0.2032 -0.2794)
							(mid 0.239121 -0.264521)
							(end 0.254 -0.2286)
						)
						(arc
							(start 0.254 0.2286)
							(mid 0.239121 0.264521)
							(end 0.2032 0.2794)
						)
					)
					(width 0)
					(fill yes)
				)
			)
		)
		(pad "2" smd custom
			(at 0 0.4318 90)
			(size 0.127 0.127)
			(layers "B.Cu" "B.Mask" "B.Paste")
			(net "PMU_SUS_CLK")
			(options
				(clearance outline)
				(anchor circle)
			)
			(primitives
				(gr_poly
					(pts
						(arc
							(start -0.2032 0.2794)
							(mid -0.239121 0.264521)
							(end -0.254 0.2286)
						)
						(arc
							(start -0.254 -0.2286)
							(mid -0.239121 -0.264521)
							(end -0.2032 -0.2794)
						)
						(arc
							(start 0.2032 -0.2794)
							(mid 0.239121 -0.264521)
							(end 0.254 -0.2286)
						)
						(arc
							(start 0.254 0.2286)
							(mid 0.239121 0.264521)
							(end 0.2032 0.2794)
						)
					)
					(width 0)
					(fill yes)
				)
			)
		)
	)
	(footprint ""
		(layer "B.Cu")
		(at 16.764 -34.417 90)
		(property "Reference" "PR189"
			(at 0 0 90)
			(layer "B.SilkS")
			(hide yes)
			(effects
				(font
					(size 1.27 1.27)
				)
				(justify mirror)
			)
		)
		(property "Value" "0R2J-2-GP"
			(at -1.7907 -1.1176 90)
			(unlocked yes)
			(layer "B.Fab")
			(hide yes)
			(effects
				(font
					(size 1.016 1.016)
					(thickness 0.1524)
				)
				(justify mirror)
			)
		)
		(property "Device Type" "R402H16"
			(at -1.7907 -2.6416 90)
			(unlocked yes)
			(layer "B.Fab")
			(hide yes)
			(effects
				(font
					(size 1.016 1.016)
					(thickness 0.1524)
				)
				(justify mirror)
			)
		)
		(duplicate_pad_numbers_are_jumpers no)
		(fp_rect
			(start 0.381 0.8382)
			(end -0.381 -0.8382)
			(stroke
				(width 0)
				(type default)
			)
			(fill no)
			(layer "B.CrtYd")
		)
		(fp_rect
			(start 0.381 0.8382)
			(end -0.381 -0.8382)
			(stroke
				(width 0)
				(type default)
			)
			(fill no)
			(layer "B.Fab")
		)
		(pad "1" smd custom
			(at 0 -0.4318 270)
			(size 0.127 0.127)
			(layers "B.Cu" "B.Mask" "B.Paste")
			(net "P3V3_STBY_ROVP")
			(options
				(clearance outline)
				(anchor circle)
			)
			(primitives
				(gr_poly
					(pts
						(arc
							(start -0.2032 0.2794)
							(mid -0.239121 0.264521)
							(end -0.254 0.2286)
						)
						(arc
							(start -0.254 -0.2286)
							(mid -0.239121 -0.264521)
							(end -0.2032 -0.2794)
						)
						(arc
							(start 0.2032 -0.2794)
							(mid 0.239121 -0.264521)
							(end 0.254 -0.2286)
						)
						(arc
							(start 0.254 0.2286)
							(mid 0.239121 0.264521)
							(end 0.2032 0.2794)
						)
					)
					(width 0)
					(fill yes)
				)
			)
		)
		(pad "2" smd custom
			(at 0 0.4318 270)
			(size 0.127 0.127)
			(layers "B.Cu" "B.Mask" "B.Paste")
			(net "AGND_P3V3_STBY")
			(options
				(clearance outline)
				(anchor circle)
			)
			(primitives
				(gr_poly
					(pts
						(arc
							(start -0.2032 0.2794)
							(mid -0.239121 0.264521)
							(end -0.254 0.2286)
						)
						(arc
							(start -0.254 -0.2286)
							(mid -0.239121 -0.264521)
							(end -0.2032 -0.2794)
						)
						(arc
							(start 0.2032 -0.2794)
							(mid 0.239121 -0.264521)
							(end 0.254 -0.2286)
						)
						(arc
							(start 0.254 0.2286)
							(mid 0.239121 0.264521)
							(end 0.2032 0.2794)
						)
					)
					(width 0)
					(fill yes)
				)
			)
		)
	)
	(footprint ""
		(layer "B.Cu")
		(at 103.3018 -43.958002 90)
		(property "Reference" "C163"
			(at 0 0 90)
			(layer "B.SilkS")
			(hide yes)
			(effects
				(font
					(size 1.27 1.27)
				)
				(justify mirror)
			)
		)
		(property "Value" "SC1U10V2KX-1GP"
			(at -1.1811 -2.7051 90)
			(unlocked yes)
			(layer "B.Fab")
			(hide yes)
			(effects
				(font
					(size 1.016 1.016)
					(thickness 0.1524)
				)
				(justify mirror)
			)
		)
		(property "Device Type" "C402H22"
			(at -1.1811 -4.2291 90)
			(unlocked yes)
			(layer "B.Fab")
			(hide yes)
			(effects
				(font
					(size 1.016 1.016)
					(thickness 0.1524)
				)
				(justify mirror)
			)
		)
		(duplicate_pad_numbers_are_jumpers no)
		(fp_rect
			(start 0.381 0.7366)
			(end -0.381 -0.7366)
			(stroke
				(width 0)
				(type default)
			)
			(fill no)
			(layer "B.CrtYd")
		)
		(fp_rect
			(start 0.381 0.7366)
			(end -0.381 -0.7366)
			(stroke
				(width 0)
				(type default)
			)
			(fill no)
			(layer "B.Fab")
		)
		(pad "1" smd custom
			(at 0 -0.4572 270)
			(size 0.1143 0.1143)
			(layers "B.Cu" "B.Mask" "B.Paste")
			(net "P1V0")
			(options
				(clearance outline)
				(anchor circle)
			)
			(primitives
				(gr_poly
					(pts
						(arc
							(start -0.254 0.1778)
							(mid -0.239121 0.213721)
							(end -0.2032 0.2286)
						)
						(arc
							(start 0.2032 0.2286)
							(mid 0.239121 0.213721)
							(end 0.254 0.1778)
						)
						(arc
							(start 0.254 -0.1778)
							(mid 0.239121 -0.213721)
							(end 0.2032 -0.2286)
						)
						(arc
							(start -0.2032 -0.2286)
							(mid -0.239121 -0.213721)
							(end -0.254 -0.1778)
						)
					)
					(width 0)
					(fill yes)
				)
			)
		)
		(pad "2" smd custom
			(at 0 0.4572 270)
			(size 0.1143 0.1143)
			(layers "B.Cu" "B.Mask" "B.Paste")
			(net "GND")
			(options
				(clearance outline)
				(anchor circle)
			)
			(primitives
				(gr_poly
					(pts
						(arc
							(start -0.254 0.1778)
							(mid -0.239121 0.213721)
							(end -0.2032 0.2286)
						)
						(arc
							(start 0.2032 0.2286)
							(mid 0.239121 0.213721)
							(end 0.254 0.1778)
						)
						(arc
							(start 0.254 -0.1778)
							(mid 0.239121 -0.213721)
							(end 0.2032 -0.2286)
						)
						(arc
							(start -0.2032 -0.2286)
							(mid -0.239121 -0.213721)
							(end -0.254 -0.1778)
						)
					)
					(width 0)
					(fill yes)
				)
			)
		)
	)
	(footprint ""
		(layer "B.Cu")
		(at 74.041 -32.512 90)
		(property "Reference" "R367"
			(at 0 0 90)
			(layer "B.SilkS")
			(hide yes)
			(effects
				(font
					(size 1.27 1.27)
				)
				(justify mirror)
			)
		)
		(property "Value" "1KR2F-3-GP"
			(at -1.7907 -1.1176 90)
			(unlocked yes)
			(layer "B.Fab")
			(hide yes)
			(effects
				(font
					(size 1.016 1.016)
					(thickness 0.1524)
				)
				(justify mirror)
			)
		)
		(property "Device Type" "R402H16"
			(at -1.7907 -2.6416 90)
			(unlocked yes)
			(layer "B.Fab")
			(hide yes)
			(effects
				(font
					(size 1.016 1.016)
					(thickness 0.1524)
				)
				(justify mirror)
			)
		)
		(duplicate_pad_numbers_are_jumpers no)
		(fp_rect
			(start 0.381 0.8382)
			(end -0.381 -0.8382)
			(stroke
				(width 0)
				(type default)
			)
			(fill no)
			(layer "B.CrtYd")
		)
		(fp_rect
			(start 0.381 0.8382)
			(end -0.381 -0.8382)
			(stroke
				(width 0)
				(type default)
			)
			(fill no)
			(layer "B.Fab")
		)
		(pad "1" smd custom
			(at 0 -0.4318 270)
			(size 0.127 0.127)
			(layers "B.Cu" "B.Mask" "B.Paste")
			(net "P3V3_CPU")
			(options
				(clearance outline)
				(anchor circle)
			)
			(primitives
				(gr_poly
					(pts
						(arc
							(start -0.2032 0.2794)
							(mid -0.239121 0.264521)
							(end -0.254 0.2286)
						)
						(arc
							(start -0.254 -0.2286)
							(mid -0.239121 -0.264521)
							(end -0.2032 -0.2794)
						)
						(arc
							(start 0.2032 -0.2794)
							(mid 0.239121 -0.264521)
							(end 0.254 -0.2286)
						)
						(arc
							(start 0.254 0.2286)
							(mid 0.239121 0.264521)
							(end 0.2032 0.2794)
						)
					)
					(width 0)
					(fill yes)
				)
			)
		)
		(pad "2" smd custom
			(at 0 0.4318 270)
			(size 0.127 0.127)
			(layers "B.Cu" "B.Mask" "B.Paste")
			(net "GBE_WOL")
			(options
				(clearance outline)
				(anchor circle)
			)
			(primitives
				(gr_poly
					(pts
						(arc
							(start -0.2032 0.2794)
							(mid -0.239121 0.264521)
							(end -0.254 0.2286)
						)
						(arc
							(start -0.254 -0.2286)
							(mid -0.239121 -0.264521)
							(end -0.2032 -0.2794)
						)
						(arc
							(start 0.2032 -0.2794)
							(mid 0.239121 -0.264521)
							(end 0.254 -0.2286)
						)
						(arc
							(start 0.254 0.2286)
							(mid 0.239121 0.264521)
							(end 0.2032 0.2794)
						)
					)
					(width 0)
					(fill yes)
				)
			)
		)
	)
	(footprint ""
		(layer "B.Cu")
		(at 39.116 -30.48 180)
		(property "Reference" "C114"
			(at 0 0 0)
			(layer "B.SilkS")
			(hide yes)
			(effects
				(font
					(size 1.27 1.27)
				)
				(justify mirror)
			)
		)
		(property "Value" "SC1U10V2KX-1GP"
			(at -1.1811 -2.7051 180)
			(unlocked yes)
			(layer "B.Fab")
			(hide yes)
			(effects
				(font
					(size 1.016 1.016)
					(thickness 0.1524)
				)
				(justify mirror)
			)
		)
		(property "Device Type" "C402H22"
			(at -1.1811 -4.2291 180)
			(unlocked yes)
			(layer "B.Fab")
			(hide yes)
			(effects
				(font
					(size 1.016 1.016)
					(thickness 0.1524)
				)
				(justify mirror)
			)
		)
		(duplicate_pad_numbers_are_jumpers no)
		(fp_rect
			(start 0.381 0.7366)
			(end -0.381 -0.7366)
			(stroke
				(width 0)
				(type default)
			)
			(fill no)
			(layer "B.CrtYd")
		)
		(fp_rect
			(start 0.381 0.7366)
			(end -0.381 -0.7366)
			(stroke
				(width 0)
				(type default)
			)
			(fill no)
			(layer "B.Fab")
		)
		(pad "1" smd custom
			(at 0 -0.4572)
			(size 0.1143 0.1143)
			(layers "B.Cu" "B.Mask" "B.Paste")
			(net "P1V0")
			(options
				(clearance outline)
				(anchor circle)
			)
			(primitives
				(gr_poly
					(pts
						(arc
							(start -0.254 0.1778)
							(mid -0.239121 0.213721)
							(end -0.2032 0.2286)
						)
						(arc
							(start 0.2032 0.2286)
							(mid 0.239121 0.213721)
							(end 0.254 0.1778)
						)
						(arc
							(start 0.254 -0.1778)
							(mid 0.239121 -0.213721)
							(end 0.2032 -0.2286)
						)
						(arc
							(start -0.2032 -0.2286)
							(mid -0.239121 -0.213721)
							(end -0.254 -0.1778)
						)
					)
					(width 0)
					(fill yes)
				)
			)
		)
		(pad "2" smd custom
			(at 0 0.4572)
			(size 0.1143 0.1143)
			(layers "B.Cu" "B.Mask" "B.Paste")
			(net "GND")
			(options
				(clearance outline)
				(anchor circle)
			)
			(primitives
				(gr_poly
					(pts
						(arc
							(start -0.254 0.1778)
							(mid -0.239121 0.213721)
							(end -0.2032 0.2286)
						)
						(arc
							(start 0.2032 0.2286)
							(mid 0.239121 0.213721)
							(end 0.254 0.1778)
						)
						(arc
							(start 0.254 -0.1778)
							(mid 0.239121 -0.213721)
							(end 0.2032 -0.2286)
						)
						(arc
							(start -0.2032 -0.2286)
							(mid -0.239121 -0.213721)
							(end -0.254 -0.1778)
						)
					)
					(width 0)
					(fill yes)
				)
			)
		)
	)
	(footprint ""
		(layer "B.Cu")
		(at 76.835 -18.1864 -90)
		(property "Reference" "PC198"
			(at 0 0 90)
			(layer "B.SilkS")
			(hide yes)
			(effects
				(font
					(size 1.27 1.27)
				)
				(justify mirror)
			)
		)
		(property "Value" "SC10U6D3V5KX-4GP"
			(at 0.0762 -6.1214 270)
			(unlocked yes)
			(layer "B.Fab")
			(hide yes)
			(effects
				(font
					(size 1.016 1.016)
					(thickness 0.1524)
				)
				(justify mirror)
			)
		)
		(property "Device Type" "C805H58"
			(at 0.0762 -8.1534 270)
			(unlocked yes)
			(layer "B.Fab")
			(hide yes)
			(effects
				(font
					(size 1.016 1.016)
					(thickness 0.1524)
				)
				(justify mirror)
			)
		)
		(duplicate_pad_numbers_are_jumpers no)
		(fp_line
			(start -0.6096 0)
			(end 0.6096 0)
			(stroke
				(width 0.3048)
				(type default)
			)
			(layer "B.SilkS")
		)
		(fp_poly
			(pts
				(xy 0.9017 1.4351) (xy -0.9017 1.4351) (xy -0.9017 -1.4351) (xy 0.9017 -1.4351)
			)
			(stroke
				(width 0)
				(type default)
			)
			(fill no)
			(layer "B.CrtYd")
		)
		(fp_poly
			(pts
				(xy -0.9017 1.4351) (xy -0.9017 -1.4351) (xy 0.9017 -1.4351) (xy 0.9017 1.4351)
			)
			(stroke
				(width 0)
				(type default)
			)
			(fill no)
			(layer "B.Fab")
		)
		(pad "1" smd rect
			(at 0 -0.8382 90)
			(size 1.5494 0.9398)
			(layers "B.Cu" "B.Mask" "B.Paste")
			(net "TPS74801_P1V35_IN")
		)
		(pad "2" smd rect
			(at 0 0.8382 90)
			(size 1.5494 0.9398)
			(layers "B.Cu" "B.Mask" "B.Paste")
			(net "GND")
		)
	)
	(footprint ""
		(layer "B.Cu")
		(at 197.7136 -60.452 -90)
		(property "Reference" "PC163"
			(at 0 0 90)
			(layer "B.SilkS")
			(hide yes)
			(effects
				(font
					(size 1.27 1.27)
				)
				(justify mirror)
			)
		)
		(property "Value" "SC22U6D3V5MX-2GP"
			(at 0 -4.9022 270)
			(unlocked yes)
			(layer "B.Fab")
			(hide yes)
			(effects
				(font
					(size 1.016 1.016)
					(thickness 0.1524)
				)
				(justify mirror)
			)
		)
		(property "Device Type" "C805H58"
			(at 0 -6.8072 270)
			(unlocked yes)
			(layer "B.Fab")
			(hide yes)
			(effects
				(font
					(size 1.016 1.016)
					(thickness 0.1524)
				)
				(justify mirror)
			)
		)
		(duplicate_pad_numbers_are_jumpers no)
		(fp_line
			(start -0.6096 0)
			(end 0.6096 0)
			(stroke
				(width 0.3048)
				(type default)
			)
			(layer "B.SilkS")
		)
		(fp_poly
			(pts
				(xy 0.9017 1.4351) (xy -0.9017 1.4351) (xy -0.9017 -1.4351) (xy 0.9017 -1.4351)
			)
			(stroke
				(width 0)
				(type default)
			)
			(fill no)
			(layer "B.CrtYd")
		)
		(fp_poly
			(pts
				(xy -0.9017 1.4351) (xy -0.9017 -1.4351) (xy 0.9017 -1.4351) (xy 0.9017 1.4351)
			)
			(stroke
				(width 0)
				(type default)
			)
			(fill no)
			(layer "B.Fab")
		)
		(pad "1" smd rect
			(at 0 -0.8382 90)
			(size 1.5494 0.9398)
			(layers "B.Cu" "B.Mask" "B.Paste")
			(net "PV_VDDR")
		)
		(pad "2" smd rect
			(at 0 0.8382 90)
			(size 1.5494 0.9398)
			(layers "B.Cu" "B.Mask" "B.Paste")
			(net "GND")
		)
	)
	(footprint ""
		(layer "B.Cu")
		(at 69.215 -62.865 90)
		(property "Reference" "R172"
			(at 0 0 90)
			(layer "B.SilkS")
			(hide yes)
			(effects
				(font
					(size 1.27 1.27)
				)
				(justify mirror)
			)
		)
		(property "Value" "10KR2F-2-GP"
			(at -1.7907 -1.1176 90)
			(unlocked yes)
			(layer "B.Fab")
			(hide yes)
			(effects
				(font
					(size 1.016 1.016)
					(thickness 0.1524)
				)
				(justify mirror)
			)
		)
		(property "Device Type" "R402H16"
			(at -1.7907 -2.6416 90)
			(unlocked yes)
			(layer "B.Fab")
			(hide yes)
			(effects
				(font
					(size 1.016 1.016)
					(thickness 0.1524)
				)
				(justify mirror)
			)
		)
		(duplicate_pad_numbers_are_jumpers no)
		(fp_rect
			(start 0.381 0.8382)
			(end -0.381 -0.8382)
			(stroke
				(width 0)
				(type default)
			)
			(fill no)
			(layer "B.CrtYd")
		)
		(fp_rect
			(start 0.381 0.8382)
			(end -0.381 -0.8382)
			(stroke
				(width 0)
				(type default)
			)
			(fill no)
			(layer "B.Fab")
		)
		(pad "1" smd custom
			(at 0 -0.4318 270)
			(size 0.127 0.127)
			(layers "B.Cu" "B.Mask" "B.Paste")
			(net "P12V")
			(options
				(clearance outline)
				(anchor circle)
			)
			(primitives
				(gr_poly
					(pts
						(arc
							(start -0.2032 0.2794)
							(mid -0.239121 0.264521)
							(end -0.254 0.2286)
						)
						(arc
							(start -0.254 -0.2286)
							(mid -0.239121 -0.264521)
							(end -0.2032 -0.2794)
						)
						(arc
							(start 0.2032 -0.2794)
							(mid 0.239121 -0.264521)
							(end 0.254 -0.2286)
						)
						(arc
							(start 0.254 0.2286)
							(mid 0.239121 0.264521)
							(end 0.2032 0.2794)
						)
					)
					(width 0)
					(fill yes)
				)
			)
		)
		(pad "2" smd custom
			(at 0 0.4318 270)
			(size 0.127 0.127)
			(layers "B.Cu" "B.Mask" "B.Paste")
			(net "P12V_SENSE")
			(options
				(clearance outline)
				(anchor circle)
			)
			(primitives
				(gr_poly
					(pts
						(arc
							(start -0.2032 0.2794)
							(mid -0.239121 0.264521)
							(end -0.254 0.2286)
						)
						(arc
							(start -0.254 -0.2286)
							(mid -0.239121 -0.264521)
							(end -0.2032 -0.2794)
						)
						(arc
							(start 0.2032 -0.2794)
							(mid 0.239121 -0.264521)
							(end 0.254 -0.2286)
						)
						(arc
							(start 0.254 0.2286)
							(mid 0.239121 0.264521)
							(end 0.2032 0.2794)
						)
					)
					(width 0)
					(fill yes)
				)
			)
		)
	)
	(footprint ""
		(layer "B.Cu")
		(at 112.141 -7.239)
		(property "Reference" "U40"
			(at 0 0 0)
			(layer "B.SilkS")
			(hide yes)
			(effects
				(font
					(size 1.27 1.27)
				)
				(justify mirror)
			)
		)
		(property "Value" "SNLVC1G126DCKR-GP"
			(at 0 -8.0772 0)
			(unlocked yes)
			(layer "B.Fab")
			(hide yes)
			(effects
				(font
					(size 1.016 1.016)
					(thickness 0.1524)
				)
				(justify mirror)
			)
		)
		(property "Device Type" "SC70-5H44"
			(at 0 -9.6012 0)
			(unlocked yes)
			(layer "B.Fab")
			(hide yes)
			(effects
				(font
					(size 1.016 1.016)
					(thickness 0.1524)
				)
				(justify mirror)
			)
		)
		(duplicate_pad_numbers_are_jumpers no)
		(fp_line
			(start -1.0033 -0.3302)
			(end -1.0033 0.3302)
			(stroke
				(width 0.1524)
				(type default)
			)
			(layer "B.SilkS")
		)
		(fp_line
			(start -1.0033 0.3302)
			(end 1.0033 0.3302)
			(stroke
				(width 0.1524)
				(type default)
			)
			(layer "B.SilkS")
		)
		(fp_line
			(start 1.0033 -0.3302)
			(end -1.0033 -0.3302)
			(stroke
				(width 0.1524)
				(type default)
			)
			(layer "B.SilkS")
		)
		(fp_line
			(start 1.0033 0.3302)
			(end 1.0033 -0.3302)
			(stroke
				(width 0.1524)
				(type default)
			)
			(layer "B.SilkS")
		)
		(fp_poly
			(pts
				(xy 1.0033 1.4859) (xy 1.0033 0.8001) (xy 1.1811 0.8001) (xy 1.1811 -0.8001) (xy 1.0033 -0.8001)
				(xy 1.0033 -1.4859) (xy -1.0033 -1.4859) (xy -1.0033 -0.8001) (xy -1.1811 -0.8001) (xy -1.1811 0.8001)
				(xy -1.0033 0.8001) (xy -1.0033 1.4859) (xy -0.2921 1.4859) (xy -0.2921 0.8001) (xy 0.2921 0.8001)
				(xy 0.2921 1.4859)
			)
			(stroke
				(width 0)
				(type default)
			)
			(fill no)
			(layer "B.CrtYd")
		)
		(fp_poly
			(pts
				(xy 1.0033 1.4859) (xy 1.0033 0.8001) (xy 1.1811 0.8001) (xy 1.1811 -0.8001) (xy 1.0033 -0.8001)
				(xy 1.0033 -1.4859) (xy -1.0033 -1.4859) (xy -1.0033 -0.8001) (xy -1.1811 -0.8001) (xy -1.1811 0.8001)
				(xy -1.0033 0.8001) (xy -1.0033 1.4859) (xy -0.2921 1.4859) (xy -0.2921 0.8001) (xy 0.2921 0.8001)
				(xy 0.2921 1.4859)
			)
			(stroke
				(width 0)
				(type default)
			)
			(fill no)
			(layer "B.Fab")
		)
		(pad "1" smd rect
			(at -0.65024 -0.93472 180)
			(size 0.3556 0.762)
			(layers "B.Cu" "B.Mask" "B.Paste")
			(net "PMU_PLTRST#")
		)
		(pad "2" smd rect
			(at 0 -0.93472 180)
			(size 0.3556 0.762)
			(layers "B.Cu" "B.Mask" "B.Paste")
			(net "IRQ_MCERR#")
		)
		(pad "3" smd rect
			(at 0.65024 -0.93472 180)
			(size 0.3556 0.762)
			(layers "B.Cu" "B.Mask" "B.Paste")
			(net "GND")
		)
		(pad "4" smd rect
			(at 0.65024 0.93472 180)
			(size 0.3556 0.762)
			(layers "B.Cu" "B.Mask" "B.Paste")
			(net "IRQ_LV_MCERR#")
		)
		(pad "5" smd rect
			(at -0.65024 0.93472 180)
			(size 0.3556 0.762)
			(layers "B.Cu" "B.Mask" "B.Paste")
			(net "P3V3")
		)
	)
	(footprint ""
		(layer "B.Cu")
		(at 68.834 -46.228)
		(property "Reference" "R294"
			(at 0 0 0)
			(layer "B.SilkS")
			(hide yes)
			(effects
				(font
					(size 1.27 1.27)
				)
				(justify mirror)
			)
		)
		(property "Value" "1KR2F-3-GP"
			(at -0.064008 -3.993896 0)
			(unlocked yes)
			(layer "B.Fab")
			(hide yes)
			(effects
				(font
					(size 1.016 1.016)
					(thickness 0.1524)
				)
				(justify mirror)
			)
		)
		(property "Device Type" "R402H16"
			(at -0.064008 -5.517896 0)
			(unlocked yes)
			(layer "B.Fab")
			(hide yes)
			(effects
				(font
					(size 1.016 1.016)
					(thickness 0.1524)
				)
				(justify mirror)
			)
		)
		(duplicate_pad_numbers_are_jumpers no)
		(fp_rect
			(start 0.381 0.8382)
			(end -0.381 -0.8382)
			(stroke
				(width 0)
				(type default)
			)
			(fill no)
			(layer "B.CrtYd")
		)
		(fp_rect
			(start 0.381 0.8382)
			(end -0.381 -0.8382)
			(stroke
				(width 0)
				(type default)
			)
			(fill no)
			(layer "B.Fab")
		)
		(pad "1" smd custom
			(at 0 -0.4318 180)
			(size 0.127 0.127)
			(layers "B.Cu" "B.Mask" "B.Paste")
			(net "IRQ_NMI_R")
			(options
				(clearance outline)
				(anchor circle)
			)
			(primitives
				(gr_poly
					(pts
						(arc
							(start -0.2032 0.2794)
							(mid -0.239121 0.264521)
							(end -0.254 0.2286)
						)
						(arc
							(start -0.254 -0.2286)
							(mid -0.239121 -0.264521)
							(end -0.2032 -0.2794)
						)
						(arc
							(start 0.2032 -0.2794)
							(mid 0.239121 -0.264521)
							(end 0.254 -0.2286)
						)
						(arc
							(start 0.254 0.2286)
							(mid 0.239121 0.264521)
							(end 0.2032 0.2794)
						)
					)
					(width 0)
					(fill yes)
				)
			)
		)
		(pad "2" smd custom
			(at 0 0.4318 180)
			(size 0.127 0.127)
			(layers "B.Cu" "B.Mask" "B.Paste")
			(net "GND")
			(options
				(clearance outline)
				(anchor circle)
			)
			(primitives
				(gr_poly
					(pts
						(arc
							(start -0.2032 0.2794)
							(mid -0.239121 0.264521)
							(end -0.254 0.2286)
						)
						(arc
							(start -0.254 -0.2286)
							(mid -0.239121 -0.264521)
							(end -0.2032 -0.2794)
						)
						(arc
							(start 0.2032 -0.2794)
							(mid 0.239121 -0.264521)
							(end 0.254 -0.2286)
						)
						(arc
							(start 0.254 0.2286)
							(mid 0.239121 0.264521)
							(end 0.2032 0.2794)
						)
					)
					(width 0)
					(fill yes)
				)
			)
		)
	)
	(footprint ""
		(layer "B.Cu")
		(at 154.9908 -59.5884)
		(property "Reference" "C324"
			(at 0 0 0)
			(layer "B.SilkS")
			(hide yes)
			(effects
				(font
					(size 1.27 1.27)
				)
				(justify mirror)
			)
		)
		(property "Value" "SCD1U16V2KX-3GP"
			(at -1.8923 -1.2065 0)
			(unlocked yes)
			(layer "B.Fab")
			(hide yes)
			(effects
				(font
					(size 1.016 1.016)
					(thickness 0.1524)
				)
				(justify mirror)
			)
		)
		(property "Device Type" "C402H22"
			(at -1.8923 -2.7305 0)
			(unlocked yes)
			(layer "B.Fab")
			(hide yes)
			(effects
				(font
					(size 1.016 1.016)
					(thickness 0.1524)
				)
				(justify mirror)
			)
		)
		(duplicate_pad_numbers_are_jumpers no)
		(fp_rect
			(start 0.381 0.7366)
			(end -0.381 -0.7366)
			(stroke
				(width 0)
				(type default)
			)
			(fill no)
			(layer "B.CrtYd")
		)
		(fp_rect
			(start 0.381 0.7366)
			(end -0.381 -0.7366)
			(stroke
				(width 0)
				(type default)
			)
			(fill no)
			(layer "B.Fab")
		)
		(pad "1" smd custom
			(at 0 -0.4572 180)
			(size 0.1143 0.1143)
			(layers "B.Cu" "B.Mask" "B.Paste")
			(net "PV_VDDR")
			(options
				(clearance outline)
				(anchor circle)
			)
			(primitives
				(gr_poly
					(pts
						(arc
							(start -0.254 0.1778)
							(mid -0.239121 0.213721)
							(end -0.2032 0.2286)
						)
						(arc
							(start 0.2032 0.2286)
							(mid 0.239121 0.213721)
							(end 0.254 0.1778)
						)
						(arc
							(start 0.254 -0.1778)
							(mid 0.239121 -0.213721)
							(end 0.2032 -0.2286)
						)
						(arc
							(start -0.2032 -0.2286)
							(mid -0.239121 -0.213721)
							(end -0.254 -0.1778)
						)
					)
					(width 0)
					(fill yes)
				)
			)
		)
		(pad "2" smd custom
			(at 0 0.4572 180)
			(size 0.1143 0.1143)
			(layers "B.Cu" "B.Mask" "B.Paste")
			(net "GND")
			(options
				(clearance outline)
				(anchor circle)
			)
			(primitives
				(gr_poly
					(pts
						(arc
							(start -0.254 0.1778)
							(mid -0.239121 0.213721)
							(end -0.2032 0.2286)
						)
						(arc
							(start 0.2032 0.2286)
							(mid 0.239121 0.213721)
							(end 0.254 0.1778)
						)
						(arc
							(start 0.254 -0.1778)
							(mid 0.239121 -0.213721)
							(end 0.2032 -0.2286)
						)
						(arc
							(start -0.2032 -0.2286)
							(mid -0.239121 -0.213721)
							(end -0.254 -0.1778)
						)
					)
					(width 0)
					(fill yes)
				)
			)
		)
	)
	(footprint ""
		(layer "B.Cu")
		(at 203.708 -64.0842 90)
		(property "Reference" "PC153"
			(at 0 0 90)
			(layer "B.SilkS")
			(hide yes)
			(effects
				(font
					(size 1.27 1.27)
				)
				(justify mirror)
			)
		)
		(property "Value" "SC10U6D3V3MX-GP"
			(at 0.0254 -2.0193 90)
			(unlocked yes)
			(layer "B.Fab")
			(hide yes)
			(effects
				(font
					(size 1.016 1.016)
					(thickness 0.1524)
				)
				(justify mirror)
			)
		)
		(property "Device Type" "C603H38"
			(at 0.0254 -3.5433 90)
			(unlocked yes)
			(layer "B.Fab")
			(hide yes)
			(effects
				(font
					(size 1.016 1.016)
					(thickness 0.1524)
				)
				(justify mirror)
			)
		)
		(duplicate_pad_numbers_are_jumpers no)
		(fp_line
			(start 0.4064 0)
			(end -0.4064 0)
			(stroke
				(width 0.2286)
				(type default)
			)
			(layer "B.SilkS")
		)
		(fp_rect
			(start 0.635 1.1811)
			(end -0.635 -1.1811)
			(stroke
				(width 0)
				(type default)
			)
			(fill no)
			(layer "B.CrtYd")
		)
		(fp_rect
			(start 0.635 1.1811)
			(end -0.635 -1.1811)
			(stroke
				(width 0)
				(type default)
			)
			(fill no)
			(layer "B.Fab")
		)
		(pad "1" smd custom
			(at 0 -0.6604 270)
			(size 0.19685 0.19685)
			(layers "B.Cu" "B.Mask" "B.Paste")
			(net "PV_VDDR")
			(options
				(clearance outline)
				(anchor circle)
			)
			(primitives
				(gr_poly
					(pts
						(arc
							(start 0.508 0.2921)
							(mid 0.478242 0.363942)
							(end 0.4064 0.3937)
						)
						(arc
							(start -0.4064 0.3937)
							(mid -0.478242 0.363942)
							(end -0.508 0.2921)
						)
						(arc
							(start -0.508 -0.2921)
							(mid -0.478242 -0.363942)
							(end -0.4064 -0.3937)
						)
						(arc
							(start 0.4064 -0.3937)
							(mid 0.478242 -0.363942)
							(end 0.508 -0.2921)
						)
					)
					(width 0)
					(fill yes)
				)
			)
		)
		(pad "2" smd custom
			(at 0 0.6604 270)
			(size 0.19685 0.19685)
			(layers "B.Cu" "B.Mask" "B.Paste")
			(net "GND")
			(options
				(clearance outline)
				(anchor circle)
			)
			(primitives
				(gr_poly
					(pts
						(arc
							(start 0.508 0.2921)
							(mid 0.478242 0.363942)
							(end 0.4064 0.3937)
						)
						(arc
							(start -0.4064 0.3937)
							(mid -0.478242 0.363942)
							(end -0.508 0.2921)
						)
						(arc
							(start -0.508 -0.2921)
							(mid -0.478242 -0.363942)
							(end -0.4064 -0.3937)
						)
						(arc
							(start 0.4064 -0.3937)
							(mid 0.478242 -0.363942)
							(end 0.508 -0.2921)
						)
					)
					(width 0)
					(fill yes)
				)
			)
		)
	)
	(footprint ""
		(layer "B.Cu")
		(at 43.3832 -16.7894)
		(property "Reference" "R355"
			(at 0 0 0)
			(layer "B.SilkS")
			(hide yes)
			(effects
				(font
					(size 1.27 1.27)
				)
				(justify mirror)
			)
		)
		(property "Value" "33R2F-3-GP"
			(at -0.064008 -3.993896 0)
			(unlocked yes)
			(layer "B.Fab")
			(hide yes)
			(effects
				(font
					(size 1.016 1.016)
					(thickness 0.1524)
				)
				(justify mirror)
			)
		)
		(property "Device Type" "R402H16"
			(at -0.064008 -5.517896 0)
			(unlocked yes)
			(layer "B.Fab")
			(hide yes)
			(effects
				(font
					(size 1.016 1.016)
					(thickness 0.1524)
				)
				(justify mirror)
			)
		)
		(duplicate_pad_numbers_are_jumpers no)
		(fp_rect
			(start 0.381 0.8382)
			(end -0.381 -0.8382)
			(stroke
				(width 0)
				(type default)
			)
			(fill no)
			(layer "B.CrtYd")
		)
		(fp_rect
			(start 0.381 0.8382)
			(end -0.381 -0.8382)
			(stroke
				(width 0)
				(type default)
			)
			(fill no)
			(layer "B.Fab")
		)
		(pad "1" smd custom
			(at 0 -0.4318 180)
			(size 0.127 0.127)
			(layers "B.Cu" "B.Mask" "B.Paste")
			(net "CLK_100M_CLKBUFF_ENET_R_DN")
			(options
				(clearance outline)
				(anchor circle)
			)
			(primitives
				(gr_poly
					(pts
						(arc
							(start -0.2032 0.2794)
							(mid -0.239121 0.264521)
							(end -0.254 0.2286)
						)
						(arc
							(start -0.254 -0.2286)
							(mid -0.239121 -0.264521)
							(end -0.2032 -0.2794)
						)
						(arc
							(start 0.2032 -0.2794)
							(mid 0.239121 -0.264521)
							(end 0.254 -0.2286)
						)
						(arc
							(start 0.254 0.2286)
							(mid 0.239121 0.264521)
							(end 0.2032 0.2794)
						)
					)
					(width 0)
					(fill yes)
				)
			)
		)
		(pad "2" smd custom
			(at 0 0.4318 180)
			(size 0.127 0.127)
			(layers "B.Cu" "B.Mask" "B.Paste")
			(net "CLK_100M_CLKBUFF_ENET_DN")
			(options
				(clearance outline)
				(anchor circle)
			)
			(primitives
				(gr_poly
					(pts
						(arc
							(start -0.2032 0.2794)
							(mid -0.239121 0.264521)
							(end -0.254 0.2286)
						)
						(arc
							(start -0.254 -0.2286)
							(mid -0.239121 -0.264521)
							(end -0.2032 -0.2794)
						)
						(arc
							(start 0.2032 -0.2794)
							(mid 0.239121 -0.264521)
							(end 0.254 -0.2286)
						)
						(arc
							(start 0.254 0.2286)
							(mid 0.239121 0.264521)
							(end 0.2032 0.2794)
						)
					)
					(width 0)
					(fill yes)
				)
			)
		)
	)
	(footprint ""
		(layer "B.Cu")
		(at 186.69 -31.6992)
		(property "Reference" "PR145"
			(at 0 0 0)
			(layer "B.SilkS")
			(hide yes)
			(effects
				(font
					(size 1.27 1.27)
				)
				(justify mirror)
			)
		)
		(property "Value" "8K45R2F-2-GP"
			(at -1.7907 -1.1176 0)
			(unlocked yes)
			(layer "B.Fab")
			(hide yes)
			(effects
				(font
					(size 1.016 1.016)
					(thickness 0.1524)
				)
				(justify mirror)
			)
		)
		(property "Device Type" "R402H16"
			(at -1.7907 -2.6416 0)
			(unlocked yes)
			(layer "B.Fab")
			(hide yes)
			(effects
				(font
					(size 1.016 1.016)
					(thickness 0.1524)
				)
				(justify mirror)
			)
		)
		(duplicate_pad_numbers_are_jumpers no)
		(fp_rect
			(start 0.381 0.8382)
			(end -0.381 -0.8382)
			(stroke
				(width 0)
				(type default)
			)
			(fill no)
			(layer "B.CrtYd")
		)
		(fp_rect
			(start 0.381 0.8382)
			(end -0.381 -0.8382)
			(stroke
				(width 0)
				(type default)
			)
			(fill no)
			(layer "B.Fab")
		)
		(pad "1" smd custom
			(at 0 -0.4318 180)
			(size 0.127 0.127)
			(layers "B.Cu" "B.Mask" "B.Paste")
			(net "VR_PVDDR_A_NTC")
			(options
				(clearance outline)
				(anchor circle)
			)
			(primitives
				(gr_poly
					(pts
						(arc
							(start -0.2032 0.2794)
							(mid -0.239121 0.264521)
							(end -0.254 0.2286)
						)
						(arc
							(start -0.254 -0.2286)
							(mid -0.239121 -0.264521)
							(end -0.2032 -0.2794)
						)
						(arc
							(start 0.2032 -0.2794)
							(mid 0.239121 -0.264521)
							(end 0.254 -0.2286)
						)
						(arc
							(start 0.254 0.2286)
							(mid 0.239121 0.264521)
							(end 0.2032 0.2794)
						)
					)
					(width 0)
					(fill yes)
				)
			)
		)
		(pad "2" smd custom
			(at 0 0.4318 180)
			(size 0.127 0.127)
			(layers "B.Cu" "B.Mask" "B.Paste")
			(net "VR_PVDDR_A_NTC_R")
			(options
				(clearance outline)
				(anchor circle)
			)
			(primitives
				(gr_poly
					(pts
						(arc
							(start -0.2032 0.2794)
							(mid -0.239121 0.264521)
							(end -0.254 0.2286)
						)
						(arc
							(start -0.254 -0.2286)
							(mid -0.239121 -0.264521)
							(end -0.2032 -0.2794)
						)
						(arc
							(start 0.2032 -0.2794)
							(mid 0.239121 -0.264521)
							(end 0.254 -0.2286)
						)
						(arc
							(start 0.254 0.2286)
							(mid 0.239121 0.264521)
							(end 0.2032 0.2794)
						)
					)
					(width 0)
					(fill yes)
				)
			)
		)
	)
	(footprint ""
		(layer "B.Cu")
		(at 203.073 -54.0512 90)
		(property "Reference" "PC157"
			(at 0 0 90)
			(layer "B.SilkS")
			(hide yes)
			(effects
				(font
					(size 1.27 1.27)
				)
				(justify mirror)
			)
		)
		(property "Value" "SC100U6D3V0MX-2GP"
			(at 2.3368 -3.5052 90)
			(unlocked yes)
			(layer "B.Fab")
			(hide yes)
			(effects
				(font
					(size 1.016 1.016)
					(thickness 0.1524)
				)
				(justify mirror)
			)
		)
		(property "Device Type" "C1210H107"
			(at 2.3368 -5.0292 90)
			(unlocked yes)
			(layer "B.Fab")
			(hide yes)
			(effects
				(font
					(size 1.016 1.016)
					(thickness 0.1524)
				)
				(justify mirror)
			)
		)
		(duplicate_pad_numbers_are_jumpers no)
		(fp_rect
			(start 1.4986 1.9685)
			(end -1.4986 -1.9685)
			(stroke
				(width 0)
				(type default)
			)
			(fill no)
			(layer "B.CrtYd")
		)
		(fp_rect
			(start 1.4986 1.9685)
			(end -1.4986 -1.9685)
			(stroke
				(width 0)
				(type default)
			)
			(fill no)
			(layer "B.Fab")
		)
		(pad "1" smd rect
			(at 0 -1.2446 270)
			(size 2.7432 1.1938)
			(layers "B.Cu" "B.Mask" "B.Paste")
			(net "PV_VDDR")
		)
		(pad "2" smd rect
			(at 0 1.2446 270)
			(size 2.7432 1.1938)
			(layers "B.Cu" "B.Mask" "B.Paste")
			(net "GND")
		)
	)
	(footprint ""
		(layer "B.Cu")
		(at 21.6408 -61.087)
		(property "Reference" "PC14"
			(at 0 0 0)
			(layer "B.SilkS")
			(hide yes)
			(effects
				(font
					(size 1.27 1.27)
				)
				(justify mirror)
			)
		)
		(property "Value" "SCD01U16V2KX-3GP"
			(at -1.8923 -1.2065 0)
			(unlocked yes)
			(layer "B.Fab")
			(hide yes)
			(effects
				(font
					(size 1.016 1.016)
					(thickness 0.1524)
				)
				(justify mirror)
			)
		)
		(property "Device Type" "C402H22"
			(at -1.8923 -2.7305 0)
			(unlocked yes)
			(layer "B.Fab")
			(hide yes)
			(effects
				(font
					(size 1.016 1.016)
					(thickness 0.1524)
				)
				(justify mirror)
			)
		)
		(duplicate_pad_numbers_are_jumpers no)
		(fp_rect
			(start 0.381 0.7366)
			(end -0.381 -0.7366)
			(stroke
				(width 0)
				(type default)
			)
			(fill no)
			(layer "B.CrtYd")
		)
		(fp_rect
			(start 0.381 0.7366)
			(end -0.381 -0.7366)
			(stroke
				(width 0)
				(type default)
			)
			(fill no)
			(layer "B.Fab")
		)
		(pad "1" smd custom
			(at 0 -0.4572 180)
			(size 0.1143 0.1143)
			(layers "B.Cu" "B.Mask" "B.Paste")
			(net "VR_PVNN_RTN")
			(options
				(clearance outline)
				(anchor circle)
			)
			(primitives
				(gr_poly
					(pts
						(arc
							(start -0.254 0.1778)
							(mid -0.239121 0.213721)
							(end -0.2032 0.2286)
						)
						(arc
							(start 0.2032 0.2286)
							(mid 0.239121 0.213721)
							(end 0.254 0.1778)
						)
						(arc
							(start 0.254 -0.1778)
							(mid 0.239121 -0.213721)
							(end 0.2032 -0.2286)
						)
						(arc
							(start -0.2032 -0.2286)
							(mid -0.239121 -0.213721)
							(end -0.254 -0.1778)
						)
					)
					(width 0)
					(fill yes)
				)
			)
		)
		(pad "2" smd custom
			(at 0 0.4572 180)
			(size 0.1143 0.1143)
			(layers "B.Cu" "B.Mask" "B.Paste")
			(net "GND")
			(options
				(clearance outline)
				(anchor circle)
			)
			(primitives
				(gr_poly
					(pts
						(arc
							(start -0.254 0.1778)
							(mid -0.239121 0.213721)
							(end -0.2032 0.2286)
						)
						(arc
							(start 0.2032 0.2286)
							(mid 0.239121 0.213721)
							(end 0.254 0.1778)
						)
						(arc
							(start 0.254 -0.1778)
							(mid 0.239121 -0.213721)
							(end 0.2032 -0.2286)
						)
						(arc
							(start -0.2032 -0.2286)
							(mid -0.239121 -0.213721)
							(end -0.254 -0.1778)
						)
					)
					(width 0)
					(fill yes)
				)
			)
		)
	)
	(footprint ""
		(layer "B.Cu")
		(at 100.457 -19.431)
		(property "Reference" "C256"
			(at 0 0 0)
			(layer "B.SilkS")
			(hide yes)
			(effects
				(font
					(size 1.27 1.27)
				)
				(justify mirror)
			)
		)
		(property "Value" "SC1U10V2KX-1GP"
			(at -1.1811 -2.7051 0)
			(unlocked yes)
			(layer "B.Fab")
			(hide yes)
			(effects
				(font
					(size 1.016 1.016)
					(thickness 0.1524)
				)
				(justify mirror)
			)
		)
		(property "Device Type" "C402H22"
			(at -1.1811 -4.2291 0)
			(unlocked yes)
			(layer "B.Fab")
			(hide yes)
			(effects
				(font
					(size 1.016 1.016)
					(thickness 0.1524)
				)
				(justify mirror)
			)
		)
		(duplicate_pad_numbers_are_jumpers no)
		(fp_rect
			(start 0.381 0.7366)
			(end -0.381 -0.7366)
			(stroke
				(width 0)
				(type default)
			)
			(fill no)
			(layer "B.CrtYd")
		)
		(fp_rect
			(start 0.381 0.7366)
			(end -0.381 -0.7366)
			(stroke
				(width 0)
				(type default)
			)
			(fill no)
			(layer "B.Fab")
		)
		(pad "1" smd custom
			(at 0 -0.4572 180)
			(size 0.1143 0.1143)
			(layers "B.Cu" "B.Mask" "B.Paste")
			(net "VCCCLKDDR1")
			(options
				(clearance outline)
				(anchor circle)
			)
			(primitives
				(gr_poly
					(pts
						(arc
							(start -0.254 0.1778)
							(mid -0.239121 0.213721)
							(end -0.2032 0.2286)
						)
						(arc
							(start 0.2032 0.2286)
							(mid 0.239121 0.213721)
							(end 0.254 0.1778)
						)
						(arc
							(start 0.254 -0.1778)
							(mid 0.239121 -0.213721)
							(end 0.2032 -0.2286)
						)
						(arc
							(start -0.2032 -0.2286)
							(mid -0.239121 -0.213721)
							(end -0.254 -0.1778)
						)
					)
					(width 0)
					(fill yes)
				)
			)
		)
		(pad "2" smd custom
			(at 0 0.4572 180)
			(size 0.1143 0.1143)
			(layers "B.Cu" "B.Mask" "B.Paste")
			(net "GND")
			(options
				(clearance outline)
				(anchor circle)
			)
			(primitives
				(gr_poly
					(pts
						(arc
							(start -0.254 0.1778)
							(mid -0.239121 0.213721)
							(end -0.2032 0.2286)
						)
						(arc
							(start 0.2032 0.2286)
							(mid 0.239121 0.213721)
							(end 0.254 0.1778)
						)
						(arc
							(start 0.254 -0.1778)
							(mid 0.239121 -0.213721)
							(end 0.2032 -0.2286)
						)
						(arc
							(start -0.2032 -0.2286)
							(mid -0.239121 -0.213721)
							(end -0.254 -0.1778)
						)
					)
					(width 0)
					(fill yes)
				)
			)
		)
	)
	(footprint ""
		(layer "B.Cu")
		(at 35.814 -51.054 -90)
		(property "Reference" "R252"
			(at 0 0 90)
			(layer "B.SilkS")
			(hide yes)
			(effects
				(font
					(size 1.27 1.27)
				)
				(justify mirror)
			)
		)
		(property "Value" "4K75R2F-1-GP"
			(at -1.7907 -1.1176 270)
			(unlocked yes)
			(layer "B.Fab")
			(hide yes)
			(effects
				(font
					(size 1.016 1.016)
					(thickness 0.1524)
				)
				(justify mirror)
			)
		)
		(property "Device Type" "R402H16"
			(at -1.7907 -2.6416 270)
			(unlocked yes)
			(layer "B.Fab")
			(hide yes)
			(effects
				(font
					(size 1.016 1.016)
					(thickness 0.1524)
				)
				(justify mirror)
			)
		)
		(duplicate_pad_numbers_are_jumpers no)
		(fp_rect
			(start 0.381 0.8382)
			(end -0.381 -0.8382)
			(stroke
				(width 0)
				(type default)
			)
			(fill no)
			(layer "B.CrtYd")
		)
		(fp_rect
			(start 0.381 0.8382)
			(end -0.381 -0.8382)
			(stroke
				(width 0)
				(type default)
			)
			(fill no)
			(layer "B.Fab")
		)
		(pad "1" smd custom
			(at 0 -0.4318 90)
			(size 0.127 0.127)
			(layers "B.Cu" "B.Mask" "B.Paste")
			(net "P3V3_STBY")
			(options
				(clearance outline)
				(anchor circle)
			)
			(primitives
				(gr_poly
					(pts
						(arc
							(start -0.2032 0.2794)
							(mid -0.239121 0.264521)
							(end -0.254 0.2286)
						)
						(arc
							(start -0.254 -0.2286)
							(mid -0.239121 -0.264521)
							(end -0.2032 -0.2794)
						)
						(arc
							(start 0.2032 -0.2794)
							(mid 0.239121 -0.264521)
							(end 0.254 -0.2286)
						)
						(arc
							(start 0.254 0.2286)
							(mid 0.239121 0.264521)
							(end 0.2032 0.2794)
						)
					)
					(width 0)
					(fill yes)
				)
			)
		)
		(pad "2" smd custom
			(at 0 0.4318 90)
			(size 0.127 0.127)
			(layers "B.Cu" "B.Mask" "B.Paste")
			(net "P1V5_STBY_EN")
			(options
				(clearance outline)
				(anchor circle)
			)
			(primitives
				(gr_poly
					(pts
						(arc
							(start -0.2032 0.2794)
							(mid -0.239121 0.264521)
							(end -0.254 0.2286)
						)
						(arc
							(start -0.254 -0.2286)
							(mid -0.239121 -0.264521)
							(end -0.2032 -0.2794)
						)
						(arc
							(start 0.2032 -0.2794)
							(mid 0.239121 -0.264521)
							(end 0.254 -0.2286)
						)
						(arc
							(start 0.254 0.2286)
							(mid 0.239121 0.264521)
							(end 0.2032 0.2794)
						)
					)
					(width 0)
					(fill yes)
				)
			)
		)
	)
	(footprint ""
		(layer "B.Cu")
		(at 73.7108 -38.7858)
		(property "Reference" "R93"
			(at 0 0 0)
			(layer "B.SilkS")
			(hide yes)
			(effects
				(font
					(size 1.27 1.27)
				)
				(justify mirror)
			)
		)
		(property "Value" "1KR2F-3-GP"
			(at -0.064008 -3.993896 0)
			(unlocked yes)
			(layer "B.Fab")
			(hide yes)
			(effects
				(font
					(size 1.016 1.016)
					(thickness 0.1524)
				)
				(justify mirror)
			)
		)
		(property "Device Type" "R402H16"
			(at -0.064008 -5.517896 0)
			(unlocked yes)
			(layer "B.Fab")
			(hide yes)
			(effects
				(font
					(size 1.016 1.016)
					(thickness 0.1524)
				)
				(justify mirror)
			)
		)
		(duplicate_pad_numbers_are_jumpers no)
		(fp_rect
			(start 0.381 0.8382)
			(end -0.381 -0.8382)
			(stroke
				(width 0)
				(type default)
			)
			(fill no)
			(layer "B.CrtYd")
		)
		(fp_rect
			(start 0.381 0.8382)
			(end -0.381 -0.8382)
			(stroke
				(width 0)
				(type default)
			)
			(fill no)
			(layer "B.Fab")
		)
		(pad "1" smd custom
			(at 0 -0.4318 180)
			(size 0.127 0.127)
			(layers "B.Cu" "B.Mask" "B.Paste")
			(net "GND")
			(options
				(clearance outline)
				(anchor circle)
			)
			(primitives
				(gr_poly
					(pts
						(arc
							(start -0.2032 0.2794)
							(mid -0.239121 0.264521)
							(end -0.254 0.2286)
						)
						(arc
							(start -0.254 -0.2286)
							(mid -0.239121 -0.264521)
							(end -0.2032 -0.2794)
						)
						(arc
							(start 0.2032 -0.2794)
							(mid 0.239121 -0.264521)
							(end 0.254 -0.2286)
						)
						(arc
							(start 0.254 0.2286)
							(mid 0.239121 0.264521)
							(end 0.2032 0.2794)
						)
					)
					(width 0)
					(fill yes)
				)
			)
		)
		(pad "2" smd custom
			(at 0 0.4318 180)
			(size 0.127 0.127)
			(layers "B.Cu" "B.Mask" "B.Paste")
			(net "FLEX_CLK_SE0")
			(options
				(clearance outline)
				(anchor circle)
			)
			(primitives
				(gr_poly
					(pts
						(arc
							(start -0.2032 0.2794)
							(mid -0.239121 0.264521)
							(end -0.254 0.2286)
						)
						(arc
							(start -0.254 -0.2286)
							(mid -0.239121 -0.264521)
							(end -0.2032 -0.2794)
						)
						(arc
							(start 0.2032 -0.2794)
							(mid 0.239121 -0.264521)
							(end 0.254 -0.2286)
						)
						(arc
							(start 0.254 0.2286)
							(mid 0.239121 0.264521)
							(end 0.2032 0.2794)
						)
					)
					(width 0)
					(fill yes)
				)
			)
		)
	)
	(footprint ""
		(layer "B.Cu")
		(at 201.2696 -35.5346 90)
		(property "Reference" "LED8"
			(at 0 0 90)
			(layer "B.SilkS")
			(hide yes)
			(effects
				(font
					(size 1.27 1.27)
				)
				(justify mirror)
			)
		)
		(property "Value" "LED-YG-51-GP"
			(at 0.0381 -2.6162 90)
			(unlocked yes)
			(layer "B.Fab")
			(hide yes)
			(effects
				(font
					(size 1.016 1.016)
					(thickness 0.1524)
				)
				(justify mirror)
			)
		)
		(property "Device Type" "LED1608AKH40"
			(at 0.0381 -4.1402 90)
			(unlocked yes)
			(layer "B.Fab")
			(hide yes)
			(effects
				(font
					(size 1.016 1.016)
					(thickness 0.1524)
				)
				(justify mirror)
			)
		)
		(duplicate_pad_numbers_are_jumpers no)
		(fp_line
			(start 0.5334 1.3081)
			(end -0.5334 1.3081)
			(stroke
				(width 0.254)
				(type default)
			)
			(layer "B.SilkS")
		)
		(fp_rect
			(start 0.6604 1.1811)
			(end -0.6604 -1.1811)
			(stroke
				(width 0)
				(type default)
			)
			(fill no)
			(layer "B.CrtYd")
		)
		(fp_rect
			(start 0.6604 1.1811)
			(end -0.6604 -1.1811)
			(stroke
				(width 0)
				(type default)
			)
			(fill no)
			(layer "B.Fab")
		)
		(pad "A" smd rect
			(at 0 -0.652526 270)
			(size 1.0668 0.8128)
			(layers "B.Cu" "B.Mask" "B.Paste")
			(net "PORT80_R_BIT3")
		)
		(pad "K" smd rect
			(at 0 0.652526 270)
			(size 1.0668 0.8128)
			(layers "B.Cu" "B.Mask" "B.Paste")
			(net "PORT80_BIT3")
		)
	)
	(footprint ""
		(layer "B.Cu")
		(at 203.708 -66.675 90)
		(property "Reference" "PC167"
			(at 0 0 90)
			(layer "B.SilkS")
			(hide yes)
			(effects
				(font
					(size 1.27 1.27)
				)
				(justify mirror)
			)
		)
		(property "Value" "SC10U6D3V3MX-GP"
			(at 0.0254 -2.0193 90)
			(unlocked yes)
			(layer "B.Fab")
			(hide yes)
			(effects
				(font
					(size 1.016 1.016)
					(thickness 0.1524)
				)
				(justify mirror)
			)
		)
		(property "Device Type" "C603H38"
			(at 0.0254 -3.5433 90)
			(unlocked yes)
			(layer "B.Fab")
			(hide yes)
			(effects
				(font
					(size 1.016 1.016)
					(thickness 0.1524)
				)
				(justify mirror)
			)
		)
		(duplicate_pad_numbers_are_jumpers no)
		(fp_line
			(start 0.4064 0)
			(end -0.4064 0)
			(stroke
				(width 0.2286)
				(type default)
			)
			(layer "B.SilkS")
		)
		(fp_rect
			(start 0.635 1.1811)
			(end -0.635 -1.1811)
			(stroke
				(width 0)
				(type default)
			)
			(fill no)
			(layer "B.CrtYd")
		)
		(fp_rect
			(start 0.635 1.1811)
			(end -0.635 -1.1811)
			(stroke
				(width 0)
				(type default)
			)
			(fill no)
			(layer "B.Fab")
		)
		(pad "1" smd custom
			(at 0 -0.6604 270)
			(size 0.19685 0.19685)
			(layers "B.Cu" "B.Mask" "B.Paste")
			(net "PV_VDDR")
			(options
				(clearance outline)
				(anchor circle)
			)
			(primitives
				(gr_poly
					(pts
						(arc
							(start 0.508 0.2921)
							(mid 0.478242 0.363942)
							(end 0.4064 0.3937)
						)
						(arc
							(start -0.4064 0.3937)
							(mid -0.478242 0.363942)
							(end -0.508 0.2921)
						)
						(arc
							(start -0.508 -0.2921)
							(mid -0.478242 -0.363942)
							(end -0.4064 -0.3937)
						)
						(arc
							(start 0.4064 -0.3937)
							(mid 0.478242 -0.363942)
							(end 0.508 -0.2921)
						)
					)
					(width 0)
					(fill yes)
				)
			)
		)
		(pad "2" smd custom
			(at 0 0.6604 270)
			(size 0.19685 0.19685)
			(layers "B.Cu" "B.Mask" "B.Paste")
			(net "GND")
			(options
				(clearance outline)
				(anchor circle)
			)
			(primitives
				(gr_poly
					(pts
						(arc
							(start 0.508 0.2921)
							(mid 0.478242 0.363942)
							(end 0.4064 0.3937)
						)
						(arc
							(start -0.4064 0.3937)
							(mid -0.478242 0.363942)
							(end -0.508 0.2921)
						)
						(arc
							(start -0.508 -0.2921)
							(mid -0.478242 -0.363942)
							(end -0.4064 -0.3937)
						)
						(arc
							(start 0.4064 -0.3937)
							(mid 0.478242 -0.363942)
							(end 0.508 -0.2921)
						)
					)
					(width 0)
					(fill yes)
				)
			)
		)
	)
	(footprint ""
		(layer "B.Cu")
		(at 81.915 -65.786)
		(property "Reference" "R284"
			(at 0 0 0)
			(layer "B.SilkS")
			(hide yes)
			(effects
				(font
					(size 1.27 1.27)
				)
				(justify mirror)
			)
		)
		(property "Value" "4K7R2F-GP"
			(at -0.064008 -3.993896 0)
			(unlocked yes)
			(layer "B.Fab")
			(hide yes)
			(effects
				(font
					(size 1.016 1.016)
					(thickness 0.1524)
				)
				(justify mirror)
			)
		)
		(property "Device Type" "R402H16"
			(at -0.064008 -5.517896 0)
			(unlocked yes)
			(layer "B.Fab")
			(hide yes)
			(effects
				(font
					(size 1.016 1.016)
					(thickness 0.1524)
				)
				(justify mirror)
			)
		)
		(duplicate_pad_numbers_are_jumpers no)
		(fp_rect
			(start 0.381 0.8382)
			(end -0.381 -0.8382)
			(stroke
				(width 0)
				(type default)
			)
			(fill no)
			(layer "B.CrtYd")
		)
		(fp_rect
			(start 0.381 0.8382)
			(end -0.381 -0.8382)
			(stroke
				(width 0)
				(type default)
			)
			(fill no)
			(layer "B.Fab")
		)
		(pad "1" smd custom
			(at 0 -0.4318 180)
			(size 0.127 0.127)
			(layers "B.Cu" "B.Mask" "B.Paste")
			(net "P1V0")
			(options
				(clearance outline)
				(anchor circle)
			)
			(primitives
				(gr_poly
					(pts
						(arc
							(start -0.2032 0.2794)
							(mid -0.239121 0.264521)
							(end -0.254 0.2286)
						)
						(arc
							(start -0.254 -0.2286)
							(mid -0.239121 -0.264521)
							(end -0.2032 -0.2794)
						)
						(arc
							(start 0.2032 -0.2794)
							(mid 0.239121 -0.264521)
							(end 0.254 -0.2286)
						)
						(arc
							(start 0.254 0.2286)
							(mid 0.239121 0.264521)
							(end 0.2032 0.2794)
						)
					)
					(width 0)
					(fill yes)
				)
			)
		)
		(pad "2" smd custom
			(at 0 0.4318 180)
			(size 0.127 0.127)
			(layers "B.Cu" "B.Mask" "B.Paste")
			(net "SVID_CPU_CLK")
			(options
				(clearance outline)
				(anchor circle)
			)
			(primitives
				(gr_poly
					(pts
						(arc
							(start -0.2032 0.2794)
							(mid -0.239121 0.264521)
							(end -0.254 0.2286)
						)
						(arc
							(start -0.254 -0.2286)
							(mid -0.239121 -0.264521)
							(end -0.2032 -0.2794)
						)
						(arc
							(start 0.2032 -0.2794)
							(mid 0.239121 -0.264521)
							(end 0.254 -0.2286)
						)
						(arc
							(start 0.254 0.2286)
							(mid 0.239121 0.264521)
							(end 0.2032 0.2794)
						)
					)
					(width 0)
					(fill yes)
				)
			)
		)
	)
	(footprint ""
		(layer "B.Cu")
		(at 87.884 -23.241 -90)
		(property "Reference" "C251"
			(at 0 0 90)
			(layer "B.SilkS")
			(hide yes)
			(effects
				(font
					(size 1.27 1.27)
				)
				(justify mirror)
			)
		)
		(property "Value" "SC2D2U10V2KX-GP"
			(at -1.1811 -2.7051 270)
			(unlocked yes)
			(layer "B.Fab")
			(hide yes)
			(effects
				(font
					(size 1.016 1.016)
					(thickness 0.1524)
				)
				(justify mirror)
			)
		)
		(property "Device Type" "C402H22"
			(at -1.1811 -4.2291 270)
			(unlocked yes)
			(layer "B.Fab")
			(hide yes)
			(effects
				(font
					(size 1.016 1.016)
					(thickness 0.1524)
				)
				(justify mirror)
			)
		)
		(duplicate_pad_numbers_are_jumpers no)
		(fp_rect
			(start 0.381 0.7366)
			(end -0.381 -0.7366)
			(stroke
				(width 0)
				(type default)
			)
			(fill no)
			(layer "B.CrtYd")
		)
		(fp_rect
			(start 0.381 0.7366)
			(end -0.381 -0.7366)
			(stroke
				(width 0)
				(type default)
			)
			(fill no)
			(layer "B.Fab")
		)
		(pad "1" smd custom
			(at 0 -0.4572 90)
			(size 0.1143 0.1143)
			(layers "B.Cu" "B.Mask" "B.Paste")
			(net "P1V0")
			(options
				(clearance outline)
				(anchor circle)
			)
			(primitives
				(gr_poly
					(pts
						(arc
							(start -0.254 0.1778)
							(mid -0.239121 0.213721)
							(end -0.2032 0.2286)
						)
						(arc
							(start 0.2032 0.2286)
							(mid 0.239121 0.213721)
							(end 0.254 0.1778)
						)
						(arc
							(start 0.254 -0.1778)
							(mid 0.239121 -0.213721)
							(end 0.2032 -0.2286)
						)
						(arc
							(start -0.2032 -0.2286)
							(mid -0.239121 -0.213721)
							(end -0.254 -0.1778)
						)
					)
					(width 0)
					(fill yes)
				)
			)
		)
		(pad "2" smd custom
			(at 0 0.4572 90)
			(size 0.1143 0.1143)
			(layers "B.Cu" "B.Mask" "B.Paste")
			(net "GND")
			(options
				(clearance outline)
				(anchor circle)
			)
			(primitives
				(gr_poly
					(pts
						(arc
							(start -0.254 0.1778)
							(mid -0.239121 0.213721)
							(end -0.2032 0.2286)
						)
						(arc
							(start 0.2032 0.2286)
							(mid 0.239121 0.213721)
							(end 0.254 0.1778)
						)
						(arc
							(start 0.254 -0.1778)
							(mid 0.239121 -0.213721)
							(end 0.2032 -0.2286)
						)
						(arc
							(start -0.2032 -0.2286)
							(mid -0.239121 -0.213721)
							(end -0.254 -0.1778)
						)
					)
					(width 0)
					(fill yes)
				)
			)
		)
	)
	(footprint ""
		(layer "B.Cu")
		(at 185.2676 -26.3652)
		(property "Reference" "PR148"
			(at 0 0 0)
			(layer "B.SilkS")
			(hide yes)
			(effects
				(font
					(size 1.27 1.27)
				)
				(justify mirror)
			)
		)
		(property "Value" "3K65R2F-1-GP"
			(at -1.7907 -1.1176 0)
			(unlocked yes)
			(layer "B.Fab")
			(hide yes)
			(effects
				(font
					(size 1.016 1.016)
					(thickness 0.1524)
				)
				(justify mirror)
			)
		)
		(property "Device Type" "R402H16"
			(at -1.7907 -2.6416 0)
			(unlocked yes)
			(layer "B.Fab")
			(hide yes)
			(effects
				(font
					(size 1.016 1.016)
					(thickness 0.1524)
				)
				(justify mirror)
			)
		)
		(duplicate_pad_numbers_are_jumpers no)
		(fp_rect
			(start 0.381 0.8382)
			(end -0.381 -0.8382)
			(stroke
				(width 0)
				(type default)
			)
			(fill no)
			(layer "B.CrtYd")
		)
		(fp_rect
			(start 0.381 0.8382)
			(end -0.381 -0.8382)
			(stroke
				(width 0)
				(type default)
			)
			(fill no)
			(layer "B.Fab")
		)
		(pad "1" smd custom
			(at 0 -0.4318 180)
			(size 0.127 0.127)
			(layers "B.Cu" "B.Mask" "B.Paste")
			(net "VR_PVDDRA_ISUMP1")
			(options
				(clearance outline)
				(anchor circle)
			)
			(primitives
				(gr_poly
					(pts
						(arc
							(start -0.2032 0.2794)
							(mid -0.239121 0.264521)
							(end -0.254 0.2286)
						)
						(arc
							(start -0.254 -0.2286)
							(mid -0.239121 -0.264521)
							(end -0.2032 -0.2794)
						)
						(arc
							(start 0.2032 -0.2794)
							(mid 0.239121 -0.264521)
							(end 0.254 -0.2286)
						)
						(arc
							(start 0.254 0.2286)
							(mid 0.239121 0.264521)
							(end 0.2032 0.2794)
						)
					)
					(width 0)
					(fill yes)
				)
			)
		)
		(pad "2" smd custom
			(at 0 0.4318 180)
			(size 0.127 0.127)
			(layers "B.Cu" "B.Mask" "B.Paste")
			(net "VR_PVDDRA_R_IS")
			(options
				(clearance outline)
				(anchor circle)
			)
			(primitives
				(gr_poly
					(pts
						(arc
							(start -0.2032 0.2794)
							(mid -0.239121 0.264521)
							(end -0.254 0.2286)
						)
						(arc
							(start -0.254 -0.2286)
							(mid -0.239121 -0.264521)
							(end -0.2032 -0.2794)
						)
						(arc
							(start 0.2032 -0.2794)
							(mid 0.239121 -0.264521)
							(end 0.254 -0.2286)
						)
						(arc
							(start 0.254 0.2286)
							(mid 0.239121 0.264521)
							(end 0.2032 0.2794)
						)
					)
					(width 0)
					(fill yes)
				)
			)
		)
	)
	(footprint ""
		(layer "B.Cu")
		(at 197.4596 -63.3222 -90)
		(property "Reference" "PC158"
			(at 0 0 90)
			(layer "B.SilkS")
			(hide yes)
			(effects
				(font
					(size 1.27 1.27)
				)
				(justify mirror)
			)
		)
		(property "Value" "SC10U6D3V3MX-GP"
			(at 0.0254 -2.0193 270)
			(unlocked yes)
			(layer "B.Fab")
			(hide yes)
			(effects
				(font
					(size 1.016 1.016)
					(thickness 0.1524)
				)
				(justify mirror)
			)
		)
		(property "Device Type" "C603H38"
			(at 0.0254 -3.5433 270)
			(unlocked yes)
			(layer "B.Fab")
			(hide yes)
			(effects
				(font
					(size 1.016 1.016)
					(thickness 0.1524)
				)
				(justify mirror)
			)
		)
		(duplicate_pad_numbers_are_jumpers no)
		(fp_line
			(start 0.4064 0)
			(end -0.4064 0)
			(stroke
				(width 0.2286)
				(type default)
			)
			(layer "B.SilkS")
		)
		(fp_rect
			(start 0.635 1.1811)
			(end -0.635 -1.1811)
			(stroke
				(width 0)
				(type default)
			)
			(fill no)
			(layer "B.CrtYd")
		)
		(fp_rect
			(start 0.635 1.1811)
			(end -0.635 -1.1811)
			(stroke
				(width 0)
				(type default)
			)
			(fill no)
			(layer "B.Fab")
		)
		(pad "1" smd custom
			(at 0 -0.6604 90)
			(size 0.19685 0.19685)
			(layers "B.Cu" "B.Mask" "B.Paste")
			(net "PV_VDDR")
			(options
				(clearance outline)
				(anchor circle)
			)
			(primitives
				(gr_poly
					(pts
						(arc
							(start 0.508 0.2921)
							(mid 0.478242 0.363942)
							(end 0.4064 0.3937)
						)
						(arc
							(start -0.4064 0.3937)
							(mid -0.478242 0.363942)
							(end -0.508 0.2921)
						)
						(arc
							(start -0.508 -0.2921)
							(mid -0.478242 -0.363942)
							(end -0.4064 -0.3937)
						)
						(arc
							(start 0.4064 -0.3937)
							(mid 0.478242 -0.363942)
							(end 0.508 -0.2921)
						)
					)
					(width 0)
					(fill yes)
				)
			)
		)
		(pad "2" smd custom
			(at 0 0.6604 90)
			(size 0.19685 0.19685)
			(layers "B.Cu" "B.Mask" "B.Paste")
			(net "GND")
			(options
				(clearance outline)
				(anchor circle)
			)
			(primitives
				(gr_poly
					(pts
						(arc
							(start 0.508 0.2921)
							(mid 0.478242 0.363942)
							(end 0.4064 0.3937)
						)
						(arc
							(start -0.4064 0.3937)
							(mid -0.478242 0.363942)
							(end -0.508 0.2921)
						)
						(arc
							(start -0.508 -0.2921)
							(mid -0.478242 -0.363942)
							(end -0.4064 -0.3937)
						)
						(arc
							(start 0.4064 -0.3937)
							(mid 0.478242 -0.363942)
							(end 0.508 -0.2921)
						)
					)
					(width 0)
					(fill yes)
				)
			)
		)
	)
	(footprint ""
		(layer "B.Cu")
		(at 104.3686 -66.7512 -90)
		(property "Reference" "PR5"
			(at 0 0 90)
			(layer "B.SilkS")
			(hide yes)
			(effects
				(font
					(size 1.27 1.27)
				)
				(justify mirror)
			)
		)
		(property "Value" "0R2J-2-GP"
			(at -1.7907 -1.1176 270)
			(unlocked yes)
			(layer "B.Fab")
			(hide yes)
			(effects
				(font
					(size 1.016 1.016)
					(thickness 0.1524)
				)
				(justify mirror)
			)
		)
		(property "Device Type" "R402H16"
			(at -1.7907 -2.6416 270)
			(unlocked yes)
			(layer "B.Fab")
			(hide yes)
			(effects
				(font
					(size 1.016 1.016)
					(thickness 0.1524)
				)
				(justify mirror)
			)
		)
		(duplicate_pad_numbers_are_jumpers no)
		(fp_rect
			(start 0.381 0.8382)
			(end -0.381 -0.8382)
			(stroke
				(width 0)
				(type default)
			)
			(fill no)
			(layer "B.CrtYd")
		)
		(fp_rect
			(start 0.381 0.8382)
			(end -0.381 -0.8382)
			(stroke
				(width 0)
				(type default)
			)
			(fill no)
			(layer "B.Fab")
		)
		(pad "1" smd custom
			(at 0 -0.4318 90)
			(size 0.127 0.127)
			(layers "B.Cu" "B.Mask" "B.Paste")
			(net "VCCRAMCPUSI1_SENSE")
			(options
				(clearance outline)
				(anchor circle)
			)
			(primitives
				(gr_poly
					(pts
						(arc
							(start -0.2032 0.2794)
							(mid -0.239121 0.264521)
							(end -0.254 0.2286)
						)
						(arc
							(start -0.254 -0.2286)
							(mid -0.239121 -0.264521)
							(end -0.2032 -0.2794)
						)
						(arc
							(start 0.2032 -0.2794)
							(mid 0.239121 -0.264521)
							(end 0.254 -0.2286)
						)
						(arc
							(start 0.254 0.2286)
							(mid 0.239121 0.264521)
							(end 0.2032 0.2794)
						)
					)
					(width 0)
					(fill yes)
				)
			)
		)
		(pad "2" smd custom
			(at 0 0.4318 90)
			(size 0.127 0.127)
			(layers "B.Cu" "B.Mask" "B.Paste")
			(net "VR_P1V1_VFBR")
			(options
				(clearance outline)
				(anchor circle)
			)
			(primitives
				(gr_poly
					(pts
						(arc
							(start -0.2032 0.2794)
							(mid -0.239121 0.264521)
							(end -0.254 0.2286)
						)
						(arc
							(start -0.254 -0.2286)
							(mid -0.239121 -0.264521)
							(end -0.2032 -0.2794)
						)
						(arc
							(start 0.2032 -0.2794)
							(mid 0.239121 -0.264521)
							(end 0.254 -0.2286)
						)
						(arc
							(start 0.254 0.2286)
							(mid 0.239121 0.264521)
							(end 0.2032 0.2794)
						)
					)
					(width 0)
					(fill yes)
				)
			)
		)
	)
	(footprint ""
		(layer "B.Cu")
		(at 92.71 -37.592)
		(property "Reference" "C182"
			(at 0 0 0)
			(layer "B.SilkS")
			(hide yes)
			(effects
				(font
					(size 1.27 1.27)
				)
				(justify mirror)
			)
		)
		(property "Value" "SC1U10V2KX-1GP"
			(at -1.1811 -2.7051 0)
			(unlocked yes)
			(layer "B.Fab")
			(hide yes)
			(effects
				(font
					(size 1.016 1.016)
					(thickness 0.1524)
				)
				(justify mirror)
			)
		)
		(property "Device Type" "C402H22"
			(at -1.1811 -4.2291 0)
			(unlocked yes)
			(layer "B.Fab")
			(hide yes)
			(effects
				(font
					(size 1.016 1.016)
					(thickness 0.1524)
				)
				(justify mirror)
			)
		)
		(duplicate_pad_numbers_are_jumpers no)
		(fp_rect
			(start 0.381 0.7366)
			(end -0.381 -0.7366)
			(stroke
				(width 0)
				(type default)
			)
			(fill no)
			(layer "B.CrtYd")
		)
		(fp_rect
			(start 0.381 0.7366)
			(end -0.381 -0.7366)
			(stroke
				(width 0)
				(type default)
			)
			(fill no)
			(layer "B.Fab")
		)
		(pad "1" smd custom
			(at 0 -0.4572 180)
			(size 0.1143 0.1143)
			(layers "B.Cu" "B.Mask" "B.Paste")
			(net "P1V0")
			(options
				(clearance outline)
				(anchor circle)
			)
			(primitives
				(gr_poly
					(pts
						(arc
							(start -0.254 0.1778)
							(mid -0.239121 0.213721)
							(end -0.2032 0.2286)
						)
						(arc
							(start 0.2032 0.2286)
							(mid 0.239121 0.213721)
							(end 0.254 0.1778)
						)
						(arc
							(start 0.254 -0.1778)
							(mid 0.239121 -0.213721)
							(end 0.2032 -0.2286)
						)
						(arc
							(start -0.2032 -0.2286)
							(mid -0.239121 -0.213721)
							(end -0.254 -0.1778)
						)
					)
					(width 0)
					(fill yes)
				)
			)
		)
		(pad "2" smd custom
			(at 0 0.4572 180)
			(size 0.1143 0.1143)
			(layers "B.Cu" "B.Mask" "B.Paste")
			(net "GND")
			(options
				(clearance outline)
				(anchor circle)
			)
			(primitives
				(gr_poly
					(pts
						(arc
							(start -0.254 0.1778)
							(mid -0.239121 0.213721)
							(end -0.2032 0.2286)
						)
						(arc
							(start 0.2032 0.2286)
							(mid 0.239121 0.213721)
							(end 0.254 0.1778)
						)
						(arc
							(start 0.254 -0.1778)
							(mid 0.239121 -0.213721)
							(end 0.2032 -0.2286)
						)
						(arc
							(start -0.2032 -0.2286)
							(mid -0.239121 -0.213721)
							(end -0.254 -0.1778)
						)
					)
					(width 0)
					(fill yes)
				)
			)
		)
	)
	(footprint ""
		(layer "B.Cu")
		(at 93.599 -26.162 90)
		(property "Reference" "C245"
			(at 0 0 90)
			(layer "B.SilkS")
			(hide yes)
			(effects
				(font
					(size 1.27 1.27)
				)
				(justify mirror)
			)
		)
		(property "Value" "SC1U10V2KX-1GP"
			(at -1.1811 -2.7051 90)
			(unlocked yes)
			(layer "B.Fab")
			(hide yes)
			(effects
				(font
					(size 1.016 1.016)
					(thickness 0.1524)
				)
				(justify mirror)
			)
		)
		(property "Device Type" "C402H22"
			(at -1.1811 -4.2291 90)
			(unlocked yes)
			(layer "B.Fab")
			(hide yes)
			(effects
				(font
					(size 1.016 1.016)
					(thickness 0.1524)
				)
				(justify mirror)
			)
		)
		(duplicate_pad_numbers_are_jumpers no)
		(fp_rect
			(start 0.381 0.7366)
			(end -0.381 -0.7366)
			(stroke
				(width 0)
				(type default)
			)
			(fill no)
			(layer "B.CrtYd")
		)
		(fp_rect
			(start 0.381 0.7366)
			(end -0.381 -0.7366)
			(stroke
				(width 0)
				(type default)
			)
			(fill no)
			(layer "B.Fab")
		)
		(pad "1" smd custom
			(at 0 -0.4572 270)
			(size 0.1143 0.1143)
			(layers "B.Cu" "B.Mask" "B.Paste")
			(net "P1V0")
			(options
				(clearance outline)
				(anchor circle)
			)
			(primitives
				(gr_poly
					(pts
						(arc
							(start -0.254 0.1778)
							(mid -0.239121 0.213721)
							(end -0.2032 0.2286)
						)
						(arc
							(start 0.2032 0.2286)
							(mid 0.239121 0.213721)
							(end 0.254 0.1778)
						)
						(arc
							(start 0.254 -0.1778)
							(mid 0.239121 -0.213721)
							(end 0.2032 -0.2286)
						)
						(arc
							(start -0.2032 -0.2286)
							(mid -0.239121 -0.213721)
							(end -0.254 -0.1778)
						)
					)
					(width 0)
					(fill yes)
				)
			)
		)
		(pad "2" smd custom
			(at 0 0.4572 270)
			(size 0.1143 0.1143)
			(layers "B.Cu" "B.Mask" "B.Paste")
			(net "GND")
			(options
				(clearance outline)
				(anchor circle)
			)
			(primitives
				(gr_poly
					(pts
						(arc
							(start -0.254 0.1778)
							(mid -0.239121 0.213721)
							(end -0.2032 0.2286)
						)
						(arc
							(start 0.2032 0.2286)
							(mid 0.239121 0.213721)
							(end 0.254 0.1778)
						)
						(arc
							(start 0.254 -0.1778)
							(mid 0.239121 -0.213721)
							(end 0.2032 -0.2286)
						)
						(arc
							(start -0.2032 -0.2286)
							(mid -0.239121 -0.213721)
							(end -0.254 -0.1778)
						)
					)
					(width 0)
					(fill yes)
				)
			)
		)
	)
	(footprint ""
		(layer "B.Cu")
		(at 73.152 -50.673 -90)
		(property "Reference" "R263"
			(at 0 0 90)
			(layer "B.SilkS")
			(hide yes)
			(effects
				(font
					(size 1.27 1.27)
				)
				(justify mirror)
			)
		)
		(property "Value" "330R2F-GP"
			(at -0.064008 -3.993896 270)
			(unlocked yes)
			(layer "B.Fab")
			(hide yes)
			(effects
				(font
					(size 1.016 1.016)
					(thickness 0.1524)
				)
				(justify mirror)
			)
		)
		(property "Device Type" "R402H16"
			(at -0.064008 -5.517896 270)
			(unlocked yes)
			(layer "B.Fab")
			(hide yes)
			(effects
				(font
					(size 1.016 1.016)
					(thickness 0.1524)
				)
				(justify mirror)
			)
		)
		(duplicate_pad_numbers_are_jumpers no)
		(fp_rect
			(start 0.381 0.8382)
			(end -0.381 -0.8382)
			(stroke
				(width 0)
				(type default)
			)
			(fill no)
			(layer "B.CrtYd")
		)
		(fp_rect
			(start 0.381 0.8382)
			(end -0.381 -0.8382)
			(stroke
				(width 0)
				(type default)
			)
			(fill no)
			(layer "B.Fab")
		)
		(pad "1" smd custom
			(at 0 -0.4318 90)
			(size 0.127 0.127)
			(layers "B.Cu" "B.Mask" "B.Paste")
			(net "P1V0")
			(options
				(clearance outline)
				(anchor circle)
			)
			(primitives
				(gr_poly
					(pts
						(arc
							(start -0.2032 0.2794)
							(mid -0.239121 0.264521)
							(end -0.254 0.2286)
						)
						(arc
							(start -0.254 -0.2286)
							(mid -0.239121 -0.264521)
							(end -0.2032 -0.2794)
						)
						(arc
							(start 0.2032 -0.2794)
							(mid 0.239121 -0.264521)
							(end 0.254 -0.2286)
						)
						(arc
							(start 0.254 0.2286)
							(mid 0.239121 0.264521)
							(end 0.2032 0.2794)
						)
					)
					(width 0)
					(fill yes)
				)
			)
		)
		(pad "2" smd custom
			(at 0 0.4318 90)
			(size 0.127 0.127)
			(layers "B.Cu" "B.Mask" "B.Paste")
			(net "MEMORY_HOT_N_LV_B1")
			(options
				(clearance outline)
				(anchor circle)
			)
			(primitives
				(gr_poly
					(pts
						(arc
							(start -0.2032 0.2794)
							(mid -0.239121 0.264521)
							(end -0.254 0.2286)
						)
						(arc
							(start -0.254 -0.2286)
							(mid -0.239121 -0.264521)
							(end -0.2032 -0.2794)
						)
						(arc
							(start 0.2032 -0.2794)
							(mid 0.239121 -0.264521)
							(end 0.254 -0.2286)
						)
						(arc
							(start 0.254 0.2286)
							(mid 0.239121 0.264521)
							(end 0.2032 0.2794)
						)
					)
					(width 0)
					(fill yes)
				)
			)
		)
	)
	(footprint ""
		(layer "B.Cu")
		(at 119.38 -61.595 -90)
		(property "Reference" "C102"
			(at 0 0 90)
			(layer "B.SilkS")
			(hide yes)
			(effects
				(font
					(size 1.27 1.27)
				)
				(justify mirror)
			)
		)
		(property "Value" "SC1U6D3V2KX-GP"
			(at -1.1811 -2.7051 270)
			(unlocked yes)
			(layer "B.Fab")
			(hide yes)
			(effects
				(font
					(size 1.016 1.016)
					(thickness 0.1524)
				)
				(justify mirror)
			)
		)
		(property "Device Type" "C402H22"
			(at -1.1811 -4.2291 270)
			(unlocked yes)
			(layer "B.Fab")
			(hide yes)
			(effects
				(font
					(size 1.016 1.016)
					(thickness 0.1524)
				)
				(justify mirror)
			)
		)
		(duplicate_pad_numbers_are_jumpers no)
		(fp_rect
			(start 0.381 0.7366)
			(end -0.381 -0.7366)
			(stroke
				(width 0)
				(type default)
			)
			(fill no)
			(layer "B.CrtYd")
		)
		(fp_rect
			(start 0.381 0.7366)
			(end -0.381 -0.7366)
			(stroke
				(width 0)
				(type default)
			)
			(fill no)
			(layer "B.Fab")
		)
		(pad "1" smd custom
			(at 0 -0.4572 90)
			(size 0.1143 0.1143)
			(layers "B.Cu" "B.Mask" "B.Paste")
			(net "PV_VTT_DDR_A")
			(options
				(clearance outline)
				(anchor circle)
			)
			(primitives
				(gr_poly
					(pts
						(arc
							(start -0.254 0.1778)
							(mid -0.239121 0.213721)
							(end -0.2032 0.2286)
						)
						(arc
							(start 0.2032 0.2286)
							(mid 0.239121 0.213721)
							(end 0.254 0.1778)
						)
						(arc
							(start 0.254 -0.1778)
							(mid 0.239121 -0.213721)
							(end 0.2032 -0.2286)
						)
						(arc
							(start -0.2032 -0.2286)
							(mid -0.239121 -0.213721)
							(end -0.254 -0.1778)
						)
					)
					(width 0)
					(fill yes)
				)
			)
		)
		(pad "2" smd custom
			(at 0 0.4572 90)
			(size 0.1143 0.1143)
			(layers "B.Cu" "B.Mask" "B.Paste")
			(net "GND")
			(options
				(clearance outline)
				(anchor circle)
			)
			(primitives
				(gr_poly
					(pts
						(arc
							(start -0.254 0.1778)
							(mid -0.239121 0.213721)
							(end -0.2032 0.2286)
						)
						(arc
							(start 0.2032 0.2286)
							(mid 0.239121 0.213721)
							(end 0.254 0.1778)
						)
						(arc
							(start 0.254 -0.1778)
							(mid 0.239121 -0.213721)
							(end 0.2032 -0.2286)
						)
						(arc
							(start -0.2032 -0.2286)
							(mid -0.239121 -0.213721)
							(end -0.254 -0.1778)
						)
					)
					(width 0)
					(fill yes)
				)
			)
		)
	)
	(footprint ""
		(layer "B.Cu")
		(at 104.14 -31.766002 180)
		(property "Reference" "R356"
			(at 0 0 0)
			(layer "B.SilkS")
			(hide yes)
			(effects
				(font
					(size 1.27 1.27)
				)
				(justify mirror)
			)
		)
		(property "Value" "1KR2F-3-GP"
			(at -0.064008 -3.993896 180)
			(unlocked yes)
			(layer "B.Fab")
			(hide yes)
			(effects
				(font
					(size 1.016 1.016)
					(thickness 0.1524)
				)
				(justify mirror)
			)
		)
		(property "Device Type" "R402H16"
			(at -0.064008 -5.517896 180)
			(unlocked yes)
			(layer "B.Fab")
			(hide yes)
			(effects
				(font
					(size 1.016 1.016)
					(thickness 0.1524)
				)
				(justify mirror)
			)
		)
		(duplicate_pad_numbers_are_jumpers no)
		(fp_rect
			(start 0.381 0.8382)
			(end -0.381 -0.8382)
			(stroke
				(width 0)
				(type default)
			)
			(fill no)
			(layer "B.CrtYd")
		)
		(fp_rect
			(start 0.381 0.8382)
			(end -0.381 -0.8382)
			(stroke
				(width 0)
				(type default)
			)
			(fill no)
			(layer "B.Fab")
		)
		(pad "1" smd custom
			(at 0 -0.4318)
			(size 0.127 0.127)
			(layers "B.Cu" "B.Mask" "B.Paste")
			(net "PV_VDDR")
			(options
				(clearance outline)
				(anchor circle)
			)
			(primitives
				(gr_poly
					(pts
						(arc
							(start -0.2032 0.2794)
							(mid -0.239121 0.264521)
							(end -0.254 0.2286)
						)
						(arc
							(start -0.254 -0.2286)
							(mid -0.239121 -0.264521)
							(end -0.2032 -0.2794)
						)
						(arc
							(start 0.2032 -0.2794)
							(mid 0.239121 -0.264521)
							(end 0.254 -0.2286)
						)
						(arc
							(start 0.254 0.2286)
							(mid 0.239121 0.264521)
							(end 0.2032 0.2794)
						)
					)
					(width 0)
					(fill yes)
				)
			)
		)
		(pad "2" smd custom
			(at 0 0.4318)
			(size 0.127 0.127)
			(layers "B.Cu" "B.Mask" "B.Paste")
			(net "PWRGD_DDR3_VCCA")
			(options
				(clearance outline)
				(anchor circle)
			)
			(primitives
				(gr_poly
					(pts
						(arc
							(start -0.2032 0.2794)
							(mid -0.239121 0.264521)
							(end -0.254 0.2286)
						)
						(arc
							(start -0.254 -0.2286)
							(mid -0.239121 -0.264521)
							(end -0.2032 -0.2794)
						)
						(arc
							(start 0.2032 -0.2794)
							(mid 0.239121 -0.264521)
							(end 0.254 -0.2286)
						)
						(arc
							(start 0.254 0.2286)
							(mid 0.239121 0.264521)
							(end 0.2032 0.2794)
						)
					)
					(width 0)
					(fill yes)
				)
			)
		)
	)
	(footprint ""
		(layer "B.Cu")
		(at 32.385 -25.273 180)
		(property "Reference" "PR102"
			(at 0 0 0)
			(layer "B.SilkS")
			(hide yes)
			(effects
				(font
					(size 1.27 1.27)
				)
				(justify mirror)
			)
		)
		(property "Value" "10D7R2F-GP"
			(at -1.7907 -1.1176 180)
			(unlocked yes)
			(layer "B.Fab")
			(hide yes)
			(effects
				(font
					(size 1.016 1.016)
					(thickness 0.1524)
				)
				(justify mirror)
			)
		)
		(property "Device Type" "R402H16"
			(at -1.7907 -2.6416 180)
			(unlocked yes)
			(layer "B.Fab")
			(hide yes)
			(effects
				(font
					(size 1.016 1.016)
					(thickness 0.1524)
				)
				(justify mirror)
			)
		)
		(duplicate_pad_numbers_are_jumpers no)
		(fp_rect
			(start 0.381 0.8382)
			(end -0.381 -0.8382)
			(stroke
				(width 0)
				(type default)
			)
			(fill no)
			(layer "B.CrtYd")
		)
		(fp_rect
			(start 0.381 0.8382)
			(end -0.381 -0.8382)
			(stroke
				(width 0)
				(type default)
			)
			(fill no)
			(layer "B.Fab")
		)
		(pad "1" smd custom
			(at 0 -0.4318)
			(size 0.127 0.127)
			(layers "B.Cu" "B.Mask" "B.Paste")
			(net "P1V0_VFB_R")
			(options
				(clearance outline)
				(anchor circle)
			)
			(primitives
				(gr_poly
					(pts
						(arc
							(start -0.2032 0.2794)
							(mid -0.239121 0.264521)
							(end -0.254 0.2286)
						)
						(arc
							(start -0.254 -0.2286)
							(mid -0.239121 -0.264521)
							(end -0.2032 -0.2794)
						)
						(arc
							(start 0.2032 -0.2794)
							(mid 0.239121 -0.264521)
							(end 0.254 -0.2286)
						)
						(arc
							(start 0.254 0.2286)
							(mid 0.239121 0.264521)
							(end 0.2032 0.2794)
						)
					)
					(width 0)
					(fill yes)
				)
			)
		)
		(pad "2" smd custom
			(at 0 0.4318)
			(size 0.127 0.127)
			(layers "B.Cu" "B.Mask" "B.Paste")
			(net "P1V0")
			(options
				(clearance outline)
				(anchor circle)
			)
			(primitives
				(gr_poly
					(pts
						(arc
							(start -0.2032 0.2794)
							(mid -0.239121 0.264521)
							(end -0.254 0.2286)
						)
						(arc
							(start -0.254 -0.2286)
							(mid -0.239121 -0.264521)
							(end -0.2032 -0.2794)
						)
						(arc
							(start 0.2032 -0.2794)
							(mid 0.239121 -0.264521)
							(end 0.254 -0.2286)
						)
						(arc
							(start 0.254 0.2286)
							(mid 0.239121 0.264521)
							(end 0.2032 0.2794)
						)
					)
					(width 0)
					(fill yes)
				)
			)
		)
	)
	(footprint ""
		(layer "B.Cu")
		(at 47.371 -15.9004)
		(property "Reference" "R420"
			(at 0 0 0)
			(layer "B.SilkS")
			(hide yes)
			(effects
				(font
					(size 1.27 1.27)
				)
				(justify mirror)
			)
		)
		(property "Value" "33R2F-3-GP"
			(at -1.7907 -1.1176 0)
			(unlocked yes)
			(layer "B.Fab")
			(hide yes)
			(effects
				(font
					(size 1.016 1.016)
					(thickness 0.1524)
				)
				(justify mirror)
			)
		)
		(property "Device Type" "R402H16"
			(at -1.7907 -2.6416 0)
			(unlocked yes)
			(layer "B.Fab")
			(hide yes)
			(effects
				(font
					(size 1.016 1.016)
					(thickness 0.1524)
				)
				(justify mirror)
			)
		)
		(duplicate_pad_numbers_are_jumpers no)
		(fp_rect
			(start 0.381 0.8382)
			(end -0.381 -0.8382)
			(stroke
				(width 0)
				(type default)
			)
			(fill no)
			(layer "B.CrtYd")
		)
		(fp_rect
			(start 0.381 0.8382)
			(end -0.381 -0.8382)
			(stroke
				(width 0)
				(type default)
			)
			(fill no)
			(layer "B.Fab")
		)
		(pad "1" smd custom
			(at 0 -0.4318 180)
			(size 0.127 0.127)
			(layers "B.Cu" "B.Mask" "B.Paste")
			(net "CLK_100M_PCIE2_REFCLK_R_DN")
			(options
				(clearance outline)
				(anchor circle)
			)
			(primitives
				(gr_poly
					(pts
						(arc
							(start -0.2032 0.2794)
							(mid -0.239121 0.264521)
							(end -0.254 0.2286)
						)
						(arc
							(start -0.254 -0.2286)
							(mid -0.239121 -0.264521)
							(end -0.2032 -0.2794)
						)
						(arc
							(start 0.2032 -0.2794)
							(mid 0.239121 -0.264521)
							(end 0.254 -0.2286)
						)
						(arc
							(start 0.254 0.2286)
							(mid 0.239121 0.264521)
							(end 0.2032 0.2794)
						)
					)
					(width 0)
					(fill yes)
				)
			)
		)
		(pad "2" smd custom
			(at 0 0.4318 180)
			(size 0.127 0.127)
			(layers "B.Cu" "B.Mask" "B.Paste")
			(net "CLK_100M_PCIE2_REFCLK_DN")
			(options
				(clearance outline)
				(anchor circle)
			)
			(primitives
				(gr_poly
					(pts
						(arc
							(start -0.2032 0.2794)
							(mid -0.239121 0.264521)
							(end -0.254 0.2286)
						)
						(arc
							(start -0.254 -0.2286)
							(mid -0.239121 -0.264521)
							(end -0.2032 -0.2794)
						)
						(arc
							(start 0.2032 -0.2794)
							(mid 0.239121 -0.264521)
							(end 0.254 -0.2286)
						)
						(arc
							(start 0.254 0.2286)
							(mid 0.239121 0.264521)
							(end 0.2032 0.2794)
						)
					)
					(width 0)
					(fill yes)
				)
			)
		)
	)
	(footprint ""
		(layer "B.Cu")
		(at 74.3458 -19.9136)
		(property "Reference" "PC120"
			(at 0 0 0)
			(layer "B.SilkS")
			(hide yes)
			(effects
				(font
					(size 1.27 1.27)
				)
				(justify mirror)
			)
		)
		(property "Value" "SC22U6D3V5MX-2GP"
			(at 0 -4.9022 0)
			(unlocked yes)
			(layer "B.Fab")
			(hide yes)
			(effects
				(font
					(size 1.016 1.016)
					(thickness 0.1524)
				)
				(justify mirror)
			)
		)
		(property "Device Type" "C805H58"
			(at 0 -6.8072 0)
			(unlocked yes)
			(layer "B.Fab")
			(hide yes)
			(effects
				(font
					(size 1.016 1.016)
					(thickness 0.1524)
				)
				(justify mirror)
			)
		)
		(duplicate_pad_numbers_are_jumpers no)
		(fp_line
			(start -0.6096 0)
			(end 0.6096 0)
			(stroke
				(width 0.3048)
				(type default)
			)
			(layer "B.SilkS")
		)
		(fp_poly
			(pts
				(xy 0.9017 1.4351) (xy -0.9017 1.4351) (xy -0.9017 -1.4351) (xy 0.9017 -1.4351)
			)
			(stroke
				(width 0)
				(type default)
			)
			(fill no)
			(layer "B.CrtYd")
		)
		(fp_poly
			(pts
				(xy -0.9017 1.4351) (xy -0.9017 -1.4351) (xy 0.9017 -1.4351) (xy 0.9017 1.4351)
			)
			(stroke
				(width 0)
				(type default)
			)
			(fill no)
			(layer "B.Fab")
		)
		(pad "1" smd rect
			(at 0 -0.8382 180)
			(size 1.5494 0.9398)
			(layers "B.Cu" "B.Mask" "B.Paste")
			(net "VR_PVIN_P1V8_STBY")
		)
		(pad "2" smd rect
			(at 0 0.8382 180)
			(size 1.5494 0.9398)
			(layers "B.Cu" "B.Mask" "B.Paste")
			(net "GND")
		)
	)
	(footprint ""
		(layer "B.Cu")
		(at 90.678 -68.072)
		(property "Reference" "PC26"
			(at 0 0 0)
			(layer "B.SilkS")
			(hide yes)
			(effects
				(font
					(size 1.27 1.27)
				)
				(justify mirror)
			)
		)
		(property "Value" "SC10U6D3V5KX-4GP"
			(at 0.0762 -6.1214 0)
			(unlocked yes)
			(layer "B.Fab")
			(hide yes)
			(effects
				(font
					(size 1.016 1.016)
					(thickness 0.1524)
				)
				(justify mirror)
			)
		)
		(property "Device Type" "C805H58"
			(at 0.0762 -8.1534 0)
			(unlocked yes)
			(layer "B.Fab")
			(hide yes)
			(effects
				(font
					(size 1.016 1.016)
					(thickness 0.1524)
				)
				(justify mirror)
			)
		)
		(duplicate_pad_numbers_are_jumpers no)
		(fp_line
			(start -0.6096 0)
			(end 0.6096 0)
			(stroke
				(width 0.3048)
				(type default)
			)
			(layer "B.SilkS")
		)
		(fp_poly
			(pts
				(xy 0.9017 1.4351) (xy -0.9017 1.4351) (xy -0.9017 -1.4351) (xy 0.9017 -1.4351)
			)
			(stroke
				(width 0)
				(type default)
			)
			(fill no)
			(layer "B.CrtYd")
		)
		(fp_poly
			(pts
				(xy -0.9017 1.4351) (xy -0.9017 -1.4351) (xy 0.9017 -1.4351) (xy 0.9017 1.4351)
			)
			(stroke
				(width 0)
				(type default)
			)
			(fill no)
			(layer "B.Fab")
		)
		(pad "1" smd rect
			(at 0 -0.8382 180)
			(size 1.5494 0.9398)
			(layers "B.Cu" "B.Mask" "B.Paste")
			(net "VR_P1V1_PVIN")
		)
		(pad "2" smd rect
			(at 0 0.8382 180)
			(size 1.5494 0.9398)
			(layers "B.Cu" "B.Mask" "B.Paste")
			(net "GND")
		)
	)
	(footprint ""
		(layer "B.Cu")
		(at 101.1682 -44.6532 180)
		(property "Reference" "R309"
			(at 0 0 0)
			(layer "B.SilkS")
			(hide yes)
			(effects
				(font
					(size 1.27 1.27)
				)
				(justify mirror)
			)
		)
		(property "Value" "30D1R2F-L-GP"
			(at -0.064008 -3.993896 180)
			(unlocked yes)
			(layer "B.Fab")
			(hide yes)
			(effects
				(font
					(size 1.016 1.016)
					(thickness 0.1524)
				)
				(justify mirror)
			)
		)
		(property "Device Type" "R402H16"
			(at -0.064008 -5.517896 180)
			(unlocked yes)
			(layer "B.Fab")
			(hide yes)
			(effects
				(font
					(size 1.016 1.016)
					(thickness 0.1524)
				)
				(justify mirror)
			)
		)
		(duplicate_pad_numbers_are_jumpers no)
		(fp_rect
			(start 0.381 0.8382)
			(end -0.381 -0.8382)
			(stroke
				(width 0)
				(type default)
			)
			(fill no)
			(layer "B.CrtYd")
		)
		(fp_rect
			(start 0.381 0.8382)
			(end -0.381 -0.8382)
			(stroke
				(width 0)
				(type default)
			)
			(fill no)
			(layer "B.Fab")
		)
		(pad "1" smd custom
			(at 0 -0.4318)
			(size 0.127 0.127)
			(layers "B.Cu" "B.Mask" "B.Paste")
			(net "M_A_DQPU")
			(options
				(clearance outline)
				(anchor circle)
			)
			(primitives
				(gr_poly
					(pts
						(arc
							(start -0.2032 0.2794)
							(mid -0.239121 0.264521)
							(end -0.254 0.2286)
						)
						(arc
							(start -0.254 -0.2286)
							(mid -0.239121 -0.264521)
							(end -0.2032 -0.2794)
						)
						(arc
							(start 0.2032 -0.2794)
							(mid 0.239121 -0.264521)
							(end 0.254 -0.2286)
						)
						(arc
							(start 0.254 0.2286)
							(mid 0.239121 0.264521)
							(end 0.2032 0.2794)
						)
					)
					(width 0)
					(fill yes)
				)
			)
		)
		(pad "2" smd custom
			(at 0 0.4318)
			(size 0.127 0.127)
			(layers "B.Cu" "B.Mask" "B.Paste")
			(net "GND")
			(options
				(clearance outline)
				(anchor circle)
			)
			(primitives
				(gr_poly
					(pts
						(arc
							(start -0.2032 0.2794)
							(mid -0.239121 0.264521)
							(end -0.254 0.2286)
						)
						(arc
							(start -0.254 -0.2286)
							(mid -0.239121 -0.264521)
							(end -0.2032 -0.2794)
						)
						(arc
							(start 0.2032 -0.2794)
							(mid 0.239121 -0.264521)
							(end 0.254 -0.2286)
						)
						(arc
							(start 0.254 0.2286)
							(mid 0.239121 0.264521)
							(end 0.2032 0.2794)
						)
					)
					(width 0)
					(fill yes)
				)
			)
		)
	)
	(footprint ""
		(layer "B.Cu")
		(at 77.47 -61.8744)
		(property "Reference" "C85"
			(at 0 0 0)
			(layer "B.SilkS")
			(hide yes)
			(effects
				(font
					(size 1.27 1.27)
				)
				(justify mirror)
			)
		)
		(property "Value" "SCD1U16V2KX-3GP"
			(at -1.1811 -2.7051 0)
			(unlocked yes)
			(layer "B.Fab")
			(hide yes)
			(effects
				(font
					(size 1.016 1.016)
					(thickness 0.1524)
				)
				(justify mirror)
			)
		)
		(property "Device Type" "C402H22"
			(at -1.1811 -4.2291 0)
			(unlocked yes)
			(layer "B.Fab")
			(hide yes)
			(effects
				(font
					(size 1.016 1.016)
					(thickness 0.1524)
				)
				(justify mirror)
			)
		)
		(duplicate_pad_numbers_are_jumpers no)
		(fp_rect
			(start 0.381 0.7366)
			(end -0.381 -0.7366)
			(stroke
				(width 0)
				(type default)
			)
			(fill no)
			(layer "B.CrtYd")
		)
		(fp_rect
			(start 0.381 0.7366)
			(end -0.381 -0.7366)
			(stroke
				(width 0)
				(type default)
			)
			(fill no)
			(layer "B.Fab")
		)
		(pad "1" smd custom
			(at 0 -0.4572 180)
			(size 0.1143 0.1143)
			(layers "B.Cu" "B.Mask" "B.Paste")
			(net "PVCCP_SENSE")
			(options
				(clearance outline)
				(anchor circle)
			)
			(primitives
				(gr_poly
					(pts
						(arc
							(start -0.254 0.1778)
							(mid -0.239121 0.213721)
							(end -0.2032 0.2286)
						)
						(arc
							(start 0.2032 0.2286)
							(mid 0.239121 0.213721)
							(end 0.254 0.1778)
						)
						(arc
							(start 0.254 -0.1778)
							(mid 0.239121 -0.213721)
							(end 0.2032 -0.2286)
						)
						(arc
							(start -0.2032 -0.2286)
							(mid -0.239121 -0.213721)
							(end -0.254 -0.1778)
						)
					)
					(width 0)
					(fill yes)
				)
			)
		)
		(pad "2" smd custom
			(at 0 0.4572 180)
			(size 0.1143 0.1143)
			(layers "B.Cu" "B.Mask" "B.Paste")
			(net "GND")
			(options
				(clearance outline)
				(anchor circle)
			)
			(primitives
				(gr_poly
					(pts
						(arc
							(start -0.254 0.1778)
							(mid -0.239121 0.213721)
							(end -0.2032 0.2286)
						)
						(arc
							(start 0.2032 0.2286)
							(mid 0.239121 0.213721)
							(end 0.254 0.1778)
						)
						(arc
							(start 0.254 -0.1778)
							(mid 0.239121 -0.213721)
							(end 0.2032 -0.2286)
						)
						(arc
							(start -0.2032 -0.2286)
							(mid -0.239121 -0.213721)
							(end -0.254 -0.1778)
						)
					)
					(width 0)
					(fill yes)
				)
			)
		)
	)
	(footprint ""
		(layer "B.Cu")
		(at 119.38 -59.182 -90)
		(property "Reference" "C111"
			(at 0 0 90)
			(layer "B.SilkS")
			(hide yes)
			(effects
				(font
					(size 1.27 1.27)
				)
				(justify mirror)
			)
		)
		(property "Value" "SC10U6D3V3MX-GP"
			(at 0 -2.8194 270)
			(unlocked yes)
			(layer "B.Fab")
			(hide yes)
			(effects
				(font
					(size 1.016 1.016)
					(thickness 0.1524)
				)
				(justify mirror)
			)
		)
		(property "Device Type" "C603H38"
			(at 0 -4.3434 270)
			(unlocked yes)
			(layer "B.Fab")
			(hide yes)
			(effects
				(font
					(size 1.016 1.016)
					(thickness 0.1524)
				)
				(justify mirror)
			)
		)
		(duplicate_pad_numbers_are_jumpers no)
		(fp_line
			(start 0.4064 0)
			(end -0.4064 0)
			(stroke
				(width 0.2286)
				(type default)
			)
			(layer "B.SilkS")
		)
		(fp_rect
			(start 0.635 1.1811)
			(end -0.635 -1.1811)
			(stroke
				(width 0)
				(type default)
			)
			(fill no)
			(layer "B.CrtYd")
		)
		(fp_rect
			(start 0.635 1.1811)
			(end -0.635 -1.1811)
			(stroke
				(width 0)
				(type default)
			)
			(fill no)
			(layer "B.Fab")
		)
		(pad "1" smd custom
			(at 0 -0.6604 90)
			(size 0.19685 0.19685)
			(layers "B.Cu" "B.Mask" "B.Paste")
			(net "PV_VTT_DDR_A")
			(options
				(clearance outline)
				(anchor circle)
			)
			(primitives
				(gr_poly
					(pts
						(arc
							(start 0.508 0.2921)
							(mid 0.478242 0.363942)
							(end 0.4064 0.3937)
						)
						(arc
							(start -0.4064 0.3937)
							(mid -0.478242 0.363942)
							(end -0.508 0.2921)
						)
						(arc
							(start -0.508 -0.2921)
							(mid -0.478242 -0.363942)
							(end -0.4064 -0.3937)
						)
						(arc
							(start 0.4064 -0.3937)
							(mid 0.478242 -0.363942)
							(end 0.508 -0.2921)
						)
					)
					(width 0)
					(fill yes)
				)
			)
		)
		(pad "2" smd custom
			(at 0 0.6604 90)
			(size 0.19685 0.19685)
			(layers "B.Cu" "B.Mask" "B.Paste")
			(net "GND")
			(options
				(clearance outline)
				(anchor circle)
			)
			(primitives
				(gr_poly
					(pts
						(arc
							(start 0.508 0.2921)
							(mid 0.478242 0.363942)
							(end 0.4064 0.3937)
						)
						(arc
							(start -0.4064 0.3937)
							(mid -0.478242 0.363942)
							(end -0.508 0.2921)
						)
						(arc
							(start -0.508 -0.2921)
							(mid -0.478242 -0.363942)
							(end -0.4064 -0.3937)
						)
						(arc
							(start 0.4064 -0.3937)
							(mid 0.478242 -0.363942)
							(end 0.508 -0.2921)
						)
					)
					(width 0)
					(fill yes)
				)
			)
		)
	)
	(footprint ""
		(layer "B.Cu")
		(at 67.183 -30.5308 -90)
		(property "Reference" "C282"
			(at 0 0 90)
			(layer "B.SilkS")
			(hide yes)
			(effects
				(font
					(size 1.27 1.27)
				)
				(justify mirror)
			)
		)
		(property "Value" "SCD01U16V2KX-3GP"
			(at -1.1811 -2.7051 270)
			(unlocked yes)
			(layer "B.Fab")
			(hide yes)
			(effects
				(font
					(size 1.016 1.016)
					(thickness 0.1524)
				)
				(justify mirror)
			)
		)
		(property "Device Type" "C402H22"
			(at -1.1811 -4.2291 270)
			(unlocked yes)
			(layer "B.Fab")
			(hide yes)
			(effects
				(font
					(size 1.016 1.016)
					(thickness 0.1524)
				)
				(justify mirror)
			)
		)
		(duplicate_pad_numbers_are_jumpers no)
		(fp_rect
			(start 0.381 0.7366)
			(end -0.381 -0.7366)
			(stroke
				(width 0)
				(type default)
			)
			(fill no)
			(layer "B.CrtYd")
		)
		(fp_rect
			(start 0.381 0.7366)
			(end -0.381 -0.7366)
			(stroke
				(width 0)
				(type default)
			)
			(fill no)
			(layer "B.Fab")
		)
		(pad "1" smd custom
			(at 0 -0.4572 90)
			(size 0.1143 0.1143)
			(layers "B.Cu" "B.Mask" "B.Paste")
			(net "SATA3_RX_DP0")
			(options
				(clearance outline)
				(anchor circle)
			)
			(primitives
				(gr_poly
					(pts
						(arc
							(start -0.254 0.1778)
							(mid -0.239121 0.213721)
							(end -0.2032 0.2286)
						)
						(arc
							(start 0.2032 0.2286)
							(mid 0.239121 0.213721)
							(end 0.254 0.1778)
						)
						(arc
							(start 0.254 -0.1778)
							(mid 0.239121 -0.213721)
							(end 0.2032 -0.2286)
						)
						(arc
							(start -0.2032 -0.2286)
							(mid -0.239121 -0.213721)
							(end -0.254 -0.1778)
						)
					)
					(width 0)
					(fill yes)
				)
			)
		)
		(pad "2" smd custom
			(at 0 0.4572 90)
			(size 0.1143 0.1143)
			(layers "B.Cu" "B.Mask" "B.Paste")
			(net "SATA3_RX_C_DP0")
			(options
				(clearance outline)
				(anchor circle)
			)
			(primitives
				(gr_poly
					(pts
						(arc
							(start -0.254 0.1778)
							(mid -0.239121 0.213721)
							(end -0.2032 0.2286)
						)
						(arc
							(start 0.2032 0.2286)
							(mid 0.239121 0.213721)
							(end 0.254 0.1778)
						)
						(arc
							(start 0.254 -0.1778)
							(mid 0.239121 -0.213721)
							(end 0.2032 -0.2286)
						)
						(arc
							(start -0.2032 -0.2286)
							(mid -0.239121 -0.213721)
							(end -0.254 -0.1778)
						)
					)
					(width 0)
					(fill yes)
				)
			)
		)
	)
	(footprint ""
		(layer "B.Cu")
		(at 83.185 -21.59 90)
		(property "Reference" "PC194"
			(at 0 0 90)
			(layer "B.SilkS")
			(hide yes)
			(effects
				(font
					(size 1.27 1.27)
				)
				(justify mirror)
			)
		)
		(property "Value" "SC470P50V2KX-3GP"
			(at -1.1811 -2.7051 90)
			(unlocked yes)
			(layer "B.Fab")
			(hide yes)
			(effects
				(font
					(size 1.016 1.016)
					(thickness 0.1524)
				)
				(justify mirror)
			)
		)
		(property "Device Type" "C402H22"
			(at -1.1811 -4.2291 90)
			(unlocked yes)
			(layer "B.Fab")
			(hide yes)
			(effects
				(font
					(size 1.016 1.016)
					(thickness 0.1524)
				)
				(justify mirror)
			)
		)
		(duplicate_pad_numbers_are_jumpers no)
		(fp_rect
			(start 0.381 0.7366)
			(end -0.381 -0.7366)
			(stroke
				(width 0)
				(type default)
			)
			(fill no)
			(layer "B.CrtYd")
		)
		(fp_rect
			(start 0.381 0.7366)
			(end -0.381 -0.7366)
			(stroke
				(width 0)
				(type default)
			)
			(fill no)
			(layer "B.Fab")
		)
		(pad "1" smd custom
			(at 0 -0.4572 270)
			(size 0.1143 0.1143)
			(layers "B.Cu" "B.Mask" "B.Paste")
			(net "GND")
			(options
				(clearance outline)
				(anchor circle)
			)
			(primitives
				(gr_poly
					(pts
						(arc
							(start -0.254 0.1778)
							(mid -0.239121 0.213721)
							(end -0.2032 0.2286)
						)
						(arc
							(start 0.2032 0.2286)
							(mid 0.239121 0.213721)
							(end 0.254 0.1778)
						)
						(arc
							(start 0.254 -0.1778)
							(mid 0.239121 -0.213721)
							(end 0.2032 -0.2286)
						)
						(arc
							(start -0.2032 -0.2286)
							(mid -0.239121 -0.213721)
							(end -0.254 -0.1778)
						)
					)
					(width 0)
					(fill yes)
				)
			)
		)
		(pad "2" smd custom
			(at 0 0.4572 270)
			(size 0.1143 0.1143)
			(layers "B.Cu" "B.Mask" "B.Paste")
			(net "TPS74801_1V35_SS")
			(options
				(clearance outline)
				(anchor circle)
			)
			(primitives
				(gr_poly
					(pts
						(arc
							(start -0.254 0.1778)
							(mid -0.239121 0.213721)
							(end -0.2032 0.2286)
						)
						(arc
							(start 0.2032 0.2286)
							(mid 0.239121 0.213721)
							(end 0.254 0.1778)
						)
						(arc
							(start 0.254 -0.1778)
							(mid 0.239121 -0.213721)
							(end 0.2032 -0.2286)
						)
						(arc
							(start -0.2032 -0.2286)
							(mid -0.239121 -0.213721)
							(end -0.254 -0.1778)
						)
					)
					(width 0)
					(fill yes)
				)
			)
		)
	)
	(footprint ""
		(layer "B.Cu")
		(at 19.939 -64.77)
		(property "Reference" "PR21"
			(at 0 0 0)
			(layer "B.SilkS")
			(hide yes)
			(effects
				(font
					(size 1.27 1.27)
				)
				(justify mirror)
			)
		)
		(property "Value" "0R2J-2-GP"
			(at -1.7907 -1.1176 0)
			(unlocked yes)
			(layer "B.Fab")
			(hide yes)
			(effects
				(font
					(size 1.016 1.016)
					(thickness 0.1524)
				)
				(justify mirror)
			)
		)
		(property "Device Type" "R402H16"
			(at -1.7907 -2.6416 0)
			(unlocked yes)
			(layer "B.Fab")
			(hide yes)
			(effects
				(font
					(size 1.016 1.016)
					(thickness 0.1524)
				)
				(justify mirror)
			)
		)
		(duplicate_pad_numbers_are_jumpers no)
		(fp_rect
			(start 0.381 0.8382)
			(end -0.381 -0.8382)
			(stroke
				(width 0)
				(type default)
			)
			(fill no)
			(layer "B.CrtYd")
		)
		(fp_rect
			(start 0.381 0.8382)
			(end -0.381 -0.8382)
			(stroke
				(width 0)
				(type default)
			)
			(fill no)
			(layer "B.Fab")
		)
		(pad "1" smd custom
			(at 0 -0.4318 180)
			(size 0.127 0.127)
			(layers "B.Cu" "B.Mask" "B.Paste")
			(net "GND")
			(options
				(clearance outline)
				(anchor circle)
			)
			(primitives
				(gr_poly
					(pts
						(arc
							(start -0.2032 0.2794)
							(mid -0.239121 0.264521)
							(end -0.254 0.2286)
						)
						(arc
							(start -0.254 -0.2286)
							(mid -0.239121 -0.264521)
							(end -0.2032 -0.2794)
						)
						(arc
							(start 0.2032 -0.2794)
							(mid 0.239121 -0.264521)
							(end 0.254 -0.2286)
						)
						(arc
							(start 0.254 0.2286)
							(mid 0.239121 0.264521)
							(end 0.2032 0.2794)
						)
					)
					(width 0)
					(fill yes)
				)
			)
		)
		(pad "2" smd custom
			(at 0 0.4318 180)
			(size 0.127 0.127)
			(layers "B.Cu" "B.Mask" "B.Paste")
			(net "VR_PVNN_RTN")
			(options
				(clearance outline)
				(anchor circle)
			)
			(primitives
				(gr_poly
					(pts
						(arc
							(start -0.2032 0.2794)
							(mid -0.239121 0.264521)
							(end -0.254 0.2286)
						)
						(arc
							(start -0.254 -0.2286)
							(mid -0.239121 -0.264521)
							(end -0.2032 -0.2794)
						)
						(arc
							(start 0.2032 -0.2794)
							(mid 0.239121 -0.264521)
							(end 0.254 -0.2286)
						)
						(arc
							(start 0.254 0.2286)
							(mid 0.239121 0.264521)
							(end 0.2032 0.2794)
						)
					)
					(width 0)
					(fill yes)
				)
			)
		)
	)
	(footprint ""
		(layer "B.Cu")
		(at 197.358 -35.306 90)
		(property "Reference" "R497"
			(at 0 0 90)
			(layer "B.SilkS")
			(hide yes)
			(effects
				(font
					(size 1.27 1.27)
				)
				(justify mirror)
			)
		)
		(property "Value" "10KR2F-2-GP"
			(at -1.7907 -1.1176 90)
			(unlocked yes)
			(layer "B.Fab")
			(hide yes)
			(effects
				(font
					(size 1.016 1.016)
					(thickness 0.1524)
				)
				(justify mirror)
			)
		)
		(property "Device Type" "R402H16"
			(at -1.7907 -2.6416 90)
			(unlocked yes)
			(layer "B.Fab")
			(hide yes)
			(effects
				(font
					(size 1.016 1.016)
					(thickness 0.1524)
				)
				(justify mirror)
			)
		)
		(duplicate_pad_numbers_are_jumpers no)
		(fp_rect
			(start 0.381 0.8382)
			(end -0.381 -0.8382)
			(stroke
				(width 0)
				(type default)
			)
			(fill no)
			(layer "B.CrtYd")
		)
		(fp_rect
			(start 0.381 0.8382)
			(end -0.381 -0.8382)
			(stroke
				(width 0)
				(type default)
			)
			(fill no)
			(layer "B.Fab")
		)
		(pad "1" smd custom
			(at 0 -0.4318 270)
			(size 0.127 0.127)
			(layers "B.Cu" "B.Mask" "B.Paste")
			(net "VDDR_5VBIAS")
			(options
				(clearance outline)
				(anchor circle)
			)
			(primitives
				(gr_poly
					(pts
						(arc
							(start -0.2032 0.2794)
							(mid -0.239121 0.264521)
							(end -0.254 0.2286)
						)
						(arc
							(start -0.254 -0.2286)
							(mid -0.239121 -0.264521)
							(end -0.2032 -0.2794)
						)
						(arc
							(start 0.2032 -0.2794)
							(mid 0.239121 -0.264521)
							(end 0.254 -0.2286)
						)
						(arc
							(start 0.254 0.2286)
							(mid 0.239121 0.264521)
							(end 0.2032 0.2794)
						)
					)
					(width 0)
					(fill yes)
				)
			)
		)
		(pad "2" smd custom
			(at 0 0.4318 270)
			(size 0.127 0.127)
			(layers "B.Cu" "B.Mask" "B.Paste")
			(net "GND")
			(options
				(clearance outline)
				(anchor circle)
			)
			(primitives
				(gr_poly
					(pts
						(arc
							(start -0.2032 0.2794)
							(mid -0.239121 0.264521)
							(end -0.254 0.2286)
						)
						(arc
							(start -0.254 -0.2286)
							(mid -0.239121 -0.264521)
							(end -0.2032 -0.2794)
						)
						(arc
							(start 0.2032 -0.2794)
							(mid 0.239121 -0.264521)
							(end 0.254 -0.2286)
						)
						(arc
							(start 0.254 0.2286)
							(mid 0.239121 0.264521)
							(end 0.2032 0.2794)
						)
					)
					(width 0)
					(fill yes)
				)
			)
		)
	)
	(footprint ""
		(layer "B.Cu")
		(at 73.7108 -23.0124 90)
		(property "Reference" "PR172"
			(at 0 0 90)
			(layer "B.SilkS")
			(hide yes)
			(effects
				(font
					(size 1.27 1.27)
				)
				(justify mirror)
			)
		)
		(property "Value" "10KR2F-2-GP"
			(at -1.7907 -1.1176 90)
			(unlocked yes)
			(layer "B.Fab")
			(hide yes)
			(effects
				(font
					(size 1.016 1.016)
					(thickness 0.1524)
				)
				(justify mirror)
			)
		)
		(property "Device Type" "R402H16"
			(at -1.7907 -2.6416 90)
			(unlocked yes)
			(layer "B.Fab")
			(hide yes)
			(effects
				(font
					(size 1.016 1.016)
					(thickness 0.1524)
				)
				(justify mirror)
			)
		)
		(duplicate_pad_numbers_are_jumpers no)
		(fp_rect
			(start 0.381 0.8382)
			(end -0.381 -0.8382)
			(stroke
				(width 0)
				(type default)
			)
			(fill no)
			(layer "B.CrtYd")
		)
		(fp_rect
			(start 0.381 0.8382)
			(end -0.381 -0.8382)
			(stroke
				(width 0)
				(type default)
			)
			(fill no)
			(layer "B.Fab")
		)
		(pad "1" smd custom
			(at 0 -0.4318 270)
			(size 0.127 0.127)
			(layers "B.Cu" "B.Mask" "B.Paste")
			(net "P1V8_STBY_PG")
			(options
				(clearance outline)
				(anchor circle)
			)
			(primitives
				(gr_poly
					(pts
						(arc
							(start -0.2032 0.2794)
							(mid -0.239121 0.264521)
							(end -0.254 0.2286)
						)
						(arc
							(start -0.254 -0.2286)
							(mid -0.239121 -0.264521)
							(end -0.2032 -0.2794)
						)
						(arc
							(start 0.2032 -0.2794)
							(mid 0.239121 -0.264521)
							(end 0.254 -0.2286)
						)
						(arc
							(start 0.254 0.2286)
							(mid 0.239121 0.264521)
							(end 0.2032 0.2794)
						)
					)
					(width 0)
					(fill yes)
				)
			)
		)
		(pad "2" smd custom
			(at 0 0.4318 270)
			(size 0.127 0.127)
			(layers "B.Cu" "B.Mask" "B.Paste")
			(net "P3V3_STBY")
			(options
				(clearance outline)
				(anchor circle)
			)
			(primitives
				(gr_poly
					(pts
						(arc
							(start -0.2032 0.2794)
							(mid -0.239121 0.264521)
							(end -0.254 0.2286)
						)
						(arc
							(start -0.254 -0.2286)
							(mid -0.239121 -0.264521)
							(end -0.2032 -0.2794)
						)
						(arc
							(start 0.2032 -0.2794)
							(mid 0.239121 -0.264521)
							(end 0.254 -0.2286)
						)
						(arc
							(start 0.254 0.2286)
							(mid 0.239121 0.264521)
							(end 0.2032 0.2794)
						)
					)
					(width 0)
					(fill yes)
				)
			)
		)
	)
	(footprint ""
		(layer "B.Cu")
		(at 106.68 -52.705 180)
		(property "Reference" "C131"
			(at 0 0 0)
			(layer "B.SilkS")
			(hide yes)
			(effects
				(font
					(size 1.27 1.27)
				)
				(justify mirror)
			)
		)
		(property "Value" "SC1U10V2KX-1GP"
			(at -1.1811 -2.7051 180)
			(unlocked yes)
			(layer "B.Fab")
			(hide yes)
			(effects
				(font
					(size 1.016 1.016)
					(thickness 0.1524)
				)
				(justify mirror)
			)
		)
		(property "Device Type" "C402H22"
			(at -1.1811 -4.2291 180)
			(unlocked yes)
			(layer "B.Fab")
			(hide yes)
			(effects
				(font
					(size 1.016 1.016)
					(thickness 0.1524)
				)
				(justify mirror)
			)
		)
		(duplicate_pad_numbers_are_jumpers no)
		(fp_rect
			(start 0.381 0.7366)
			(end -0.381 -0.7366)
			(stroke
				(width 0)
				(type default)
			)
			(fill no)
			(layer "B.CrtYd")
		)
		(fp_rect
			(start 0.381 0.7366)
			(end -0.381 -0.7366)
			(stroke
				(width 0)
				(type default)
			)
			(fill no)
			(layer "B.Fab")
		)
		(pad "1" smd custom
			(at 0 -0.4572)
			(size 0.1143 0.1143)
			(layers "B.Cu" "B.Mask" "B.Paste")
			(net "PV_VDDR")
			(options
				(clearance outline)
				(anchor circle)
			)
			(primitives
				(gr_poly
					(pts
						(arc
							(start -0.254 0.1778)
							(mid -0.239121 0.213721)
							(end -0.2032 0.2286)
						)
						(arc
							(start 0.2032 0.2286)
							(mid 0.239121 0.213721)
							(end 0.254 0.1778)
						)
						(arc
							(start 0.254 -0.1778)
							(mid 0.239121 -0.213721)
							(end 0.2032 -0.2286)
						)
						(arc
							(start -0.2032 -0.2286)
							(mid -0.239121 -0.213721)
							(end -0.254 -0.1778)
						)
					)
					(width 0)
					(fill yes)
				)
			)
		)
		(pad "2" smd custom
			(at 0 0.4572)
			(size 0.1143 0.1143)
			(layers "B.Cu" "B.Mask" "B.Paste")
			(net "GND")
			(options
				(clearance outline)
				(anchor circle)
			)
			(primitives
				(gr_poly
					(pts
						(arc
							(start -0.254 0.1778)
							(mid -0.239121 0.213721)
							(end -0.2032 0.2286)
						)
						(arc
							(start 0.2032 0.2286)
							(mid 0.239121 0.213721)
							(end 0.254 0.1778)
						)
						(arc
							(start 0.254 -0.1778)
							(mid 0.239121 -0.213721)
							(end 0.2032 -0.2286)
						)
						(arc
							(start -0.2032 -0.2286)
							(mid -0.239121 -0.213721)
							(end -0.254 -0.1778)
						)
					)
					(width 0)
					(fill yes)
				)
			)
		)
	)
	(footprint ""
		(layer "B.Cu")
		(at 204.089 -30.861 90)
		(property "Reference" "C348"
			(at 0 0 90)
			(layer "B.SilkS")
			(hide yes)
			(effects
				(font
					(size 1.27 1.27)
				)
				(justify mirror)
			)
		)
		(property "Value" "SCD1U16V2KX-3GP"
			(at -1.8923 -1.2065 90)
			(unlocked yes)
			(layer "B.Fab")
			(hide yes)
			(effects
				(font
					(size 1.016 1.016)
					(thickness 0.1524)
				)
				(justify mirror)
			)
		)
		(property "Device Type" "C402H22"
			(at -1.8923 -2.7305 90)
			(unlocked yes)
			(layer "B.Fab")
			(hide yes)
			(effects
				(font
					(size 1.016 1.016)
					(thickness 0.1524)
				)
				(justify mirror)
			)
		)
		(duplicate_pad_numbers_are_jumpers no)
		(fp_rect
			(start 0.381 0.7366)
			(end -0.381 -0.7366)
			(stroke
				(width 0)
				(type default)
			)
			(fill no)
			(layer "B.CrtYd")
		)
		(fp_rect
			(start 0.381 0.7366)
			(end -0.381 -0.7366)
			(stroke
				(width 0)
				(type default)
			)
			(fill no)
			(layer "B.Fab")
		)
		(pad "1" smd custom
			(at 0 -0.4572 270)
			(size 0.1143 0.1143)
			(layers "B.Cu" "B.Mask" "B.Paste")
			(net "PV_VDDR")
			(options
				(clearance outline)
				(anchor circle)
			)
			(primitives
				(gr_poly
					(pts
						(arc
							(start -0.254 0.1778)
							(mid -0.239121 0.213721)
							(end -0.2032 0.2286)
						)
						(arc
							(start 0.2032 0.2286)
							(mid 0.239121 0.213721)
							(end 0.254 0.1778)
						)
						(arc
							(start 0.254 -0.1778)
							(mid 0.239121 -0.213721)
							(end 0.2032 -0.2286)
						)
						(arc
							(start -0.2032 -0.2286)
							(mid -0.239121 -0.213721)
							(end -0.254 -0.1778)
						)
					)
					(width 0)
					(fill yes)
				)
			)
		)
		(pad "2" smd custom
			(at 0 0.4572 270)
			(size 0.1143 0.1143)
			(layers "B.Cu" "B.Mask" "B.Paste")
			(net "GND")
			(options
				(clearance outline)
				(anchor circle)
			)
			(primitives
				(gr_poly
					(pts
						(arc
							(start -0.254 0.1778)
							(mid -0.239121 0.213721)
							(end -0.2032 0.2286)
						)
						(arc
							(start 0.2032 0.2286)
							(mid 0.239121 0.213721)
							(end 0.254 0.1778)
						)
						(arc
							(start 0.254 -0.1778)
							(mid 0.239121 -0.213721)
							(end 0.2032 -0.2286)
						)
						(arc
							(start -0.2032 -0.2286)
							(mid -0.239121 -0.213721)
							(end -0.254 -0.1778)
						)
					)
					(width 0)
					(fill yes)
				)
			)
		)
	)
	(footprint ""
		(layer "B.Cu")
		(at 199.300084 -68.799964 90)
		(property "Reference" "LED14"
			(at 0 0 90)
			(layer "B.SilkS")
			(hide yes)
			(effects
				(font
					(size 1.27 1.27)
				)
				(justify mirror)
			)
		)
		(property "Value" "LED-Y-11-GP"
			(at 0.0508 -2.6035 90)
			(unlocked yes)
			(layer "B.Fab")
			(hide yes)
			(effects
				(font
					(size 1.016 1.016)
					(thickness 0.1524)
				)
				(justify mirror)
			)
		)
		(property "Device Type" "19-21UBC-1"
			(at 0.0508 -4.1275 90)
			(unlocked yes)
			(layer "B.Fab")
			(hide yes)
			(effects
				(font
					(size 1.016 1.016)
					(thickness 0.1524)
				)
				(justify mirror)
			)
		)
		(duplicate_pad_numbers_are_jumpers no)
		(fp_line
			(start 0.5461 -1.3081)
			(end -0.5207 -1.3081)
			(stroke
				(width 0.254)
				(type default)
			)
			(layer "B.SilkS")
		)
		(fp_rect
			(start 0.6604 1.1811)
			(end -0.6604 -1.1811)
			(stroke
				(width 0)
				(type default)
			)
			(fill no)
			(layer "B.CrtYd")
		)
		(fp_rect
			(start 0.6604 1.1811)
			(end -0.6604 -1.1811)
			(stroke
				(width 0)
				(type default)
			)
			(fill no)
			(layer "B.Fab")
		)
		(pad "1" smd rect
			(at 0 -0.652526 270)
			(size 1.0668 0.8128)
			(layers "B.Cu" "B.Mask" "B.Paste")
			(net "BEEP_LED_D")
		)
		(pad "2" smd rect
			(at 0 0.652526 270)
			(size 1.0668 0.8128)
			(layers "B.Cu" "B.Mask" "B.Paste")
			(net "BEEP_LED")
		)
	)
	(footprint ""
		(layer "B.Cu")
		(at 201.2696 -34.1884 90)
		(property "Reference" "LED7"
			(at 0 0 90)
			(layer "B.SilkS")
			(hide yes)
			(effects
				(font
					(size 1.27 1.27)
				)
				(justify mirror)
			)
		)
		(property "Value" "LED-YG-51-GP"
			(at 0.0381 -2.6162 90)
			(unlocked yes)
			(layer "B.Fab")
			(hide yes)
			(effects
				(font
					(size 1.016 1.016)
					(thickness 0.1524)
				)
				(justify mirror)
			)
		)
		(property "Device Type" "LED1608AKH40"
			(at 0.0381 -4.1402 90)
			(unlocked yes)
			(layer "B.Fab")
			(hide yes)
			(effects
				(font
					(size 1.016 1.016)
					(thickness 0.1524)
				)
				(justify mirror)
			)
		)
		(duplicate_pad_numbers_are_jumpers no)
		(fp_line
			(start 0.5334 1.3081)
			(end -0.5334 1.3081)
			(stroke
				(width 0.254)
				(type default)
			)
			(layer "B.SilkS")
		)
		(fp_rect
			(start 0.6604 1.1811)
			(end -0.6604 -1.1811)
			(stroke
				(width 0)
				(type default)
			)
			(fill no)
			(layer "B.CrtYd")
		)
		(fp_rect
			(start 0.6604 1.1811)
			(end -0.6604 -1.1811)
			(stroke
				(width 0)
				(type default)
			)
			(fill no)
			(layer "B.Fab")
		)
		(pad "A" smd rect
			(at 0 -0.652526 270)
			(size 1.0668 0.8128)
			(layers "B.Cu" "B.Mask" "B.Paste")
			(net "PORT80_R_BIT2")
		)
		(pad "K" smd rect
			(at 0 0.652526 270)
			(size 1.0668 0.8128)
			(layers "B.Cu" "B.Mask" "B.Paste")
			(net "PORT80_BIT2")
		)
	)
	(footprint ""
		(layer "B.Cu")
		(at 35.687 -20.447)
		(property "Reference" "R451"
			(at 0 0 0)
			(layer "B.SilkS")
			(hide yes)
			(effects
				(font
					(size 1.27 1.27)
				)
				(justify mirror)
			)
		)
		(property "Value" "4K7R2F-GP"
			(at -1.7907 -1.1176 0)
			(unlocked yes)
			(layer "B.Fab")
			(hide yes)
			(effects
				(font
					(size 1.016 1.016)
					(thickness 0.1524)
				)
				(justify mirror)
			)
		)
		(property "Device Type" "R402H16"
			(at -1.7907 -2.6416 0)
			(unlocked yes)
			(layer "B.Fab")
			(hide yes)
			(effects
				(font
					(size 1.016 1.016)
					(thickness 0.1524)
				)
				(justify mirror)
			)
		)
		(duplicate_pad_numbers_are_jumpers no)
		(fp_rect
			(start 0.381 0.8382)
			(end -0.381 -0.8382)
			(stroke
				(width 0)
				(type default)
			)
			(fill no)
			(layer "B.CrtYd")
		)
		(fp_rect
			(start 0.381 0.8382)
			(end -0.381 -0.8382)
			(stroke
				(width 0)
				(type default)
			)
			(fill no)
			(layer "B.Fab")
		)
		(pad "1" smd custom
			(at 0 -0.4318 180)
			(size 0.127 0.127)
			(layers "B.Cu" "B.Mask" "B.Paste")
			(net "P3V3")
			(options
				(clearance outline)
				(anchor circle)
			)
			(primitives
				(gr_poly
					(pts
						(arc
							(start -0.2032 0.2794)
							(mid -0.239121 0.264521)
							(end -0.254 0.2286)
						)
						(arc
							(start -0.254 -0.2286)
							(mid -0.239121 -0.264521)
							(end -0.2032 -0.2794)
						)
						(arc
							(start 0.2032 -0.2794)
							(mid 0.239121 -0.264521)
							(end 0.254 -0.2286)
						)
						(arc
							(start 0.254 0.2286)
							(mid 0.239121 0.264521)
							(end 0.2032 0.2794)
						)
					)
					(width 0)
					(fill yes)
				)
			)
		)
		(pad "2" smd custom
			(at 0 0.4318 180)
			(size 0.127 0.127)
			(layers "B.Cu" "B.Mask" "B.Paste")
			(net "CLKBUFF_BYPASS_OR_PLL")
			(options
				(clearance outline)
				(anchor circle)
			)
			(primitives
				(gr_poly
					(pts
						(arc
							(start -0.2032 0.2794)
							(mid -0.239121 0.264521)
							(end -0.254 0.2286)
						)
						(arc
							(start -0.254 -0.2286)
							(mid -0.239121 -0.264521)
							(end -0.2032 -0.2794)
						)
						(arc
							(start 0.2032 -0.2794)
							(mid 0.239121 -0.264521)
							(end 0.254 -0.2286)
						)
						(arc
							(start 0.254 0.2286)
							(mid 0.239121 0.264521)
							(end 0.2032 0.2794)
						)
					)
					(width 0)
					(fill yes)
				)
			)
		)
	)
	(footprint ""
		(layer "B.Cu")
		(at 182.977028 -30.39999 -90)
		(property "Reference" "PR213"
			(at 0 0 90)
			(layer "B.SilkS")
			(hide yes)
			(effects
				(font
					(size 1.27 1.27)
				)
				(justify mirror)
			)
		)
		(property "Value" "249R2F-GP"
			(at -1.7907 -1.1176 270)
			(unlocked yes)
			(layer "B.Fab")
			(hide yes)
			(effects
				(font
					(size 1.016 1.016)
					(thickness 0.1524)
				)
				(justify mirror)
			)
		)
		(property "Device Type" "R402H16"
			(at -1.7907 -2.6416 270)
			(unlocked yes)
			(layer "B.Fab")
			(hide yes)
			(effects
				(font
					(size 1.016 1.016)
					(thickness 0.1524)
				)
				(justify mirror)
			)
		)
		(duplicate_pad_numbers_are_jumpers no)
		(fp_rect
			(start 0.381 0.8382)
			(end -0.381 -0.8382)
			(stroke
				(width 0)
				(type default)
			)
			(fill no)
			(layer "B.CrtYd")
		)
		(fp_rect
			(start 0.381 0.8382)
			(end -0.381 -0.8382)
			(stroke
				(width 0)
				(type default)
			)
			(fill no)
			(layer "B.Fab")
		)
		(pad "1" smd custom
			(at 0 -0.4318 90)
			(size 0.127 0.127)
			(layers "B.Cu" "B.Mask" "B.Paste")
			(net "VR_PVDDR_A_FB")
			(options
				(clearance outline)
				(anchor circle)
			)
			(primitives
				(gr_poly
					(pts
						(arc
							(start -0.2032 0.2794)
							(mid -0.239121 0.264521)
							(end -0.254 0.2286)
						)
						(arc
							(start -0.254 -0.2286)
							(mid -0.239121 -0.264521)
							(end -0.2032 -0.2794)
						)
						(arc
							(start 0.2032 -0.2794)
							(mid 0.239121 -0.264521)
							(end 0.254 -0.2286)
						)
						(arc
							(start 0.254 0.2286)
							(mid 0.239121 0.264521)
							(end 0.2032 0.2794)
						)
					)
					(width 0)
					(fill yes)
				)
			)
		)
		(pad "2" smd custom
			(at 0 0.4318 90)
			(size 0.127 0.127)
			(layers "B.Cu" "B.Mask" "B.Paste")
			(net "VSENSE_PVDDR_A_VSEN_FB")
			(options
				(clearance outline)
				(anchor circle)
			)
			(primitives
				(gr_poly
					(pts
						(arc
							(start -0.2032 0.2794)
							(mid -0.239121 0.264521)
							(end -0.254 0.2286)
						)
						(arc
							(start -0.254 -0.2286)
							(mid -0.239121 -0.264521)
							(end -0.2032 -0.2794)
						)
						(arc
							(start 0.2032 -0.2794)
							(mid 0.239121 -0.264521)
							(end 0.254 -0.2286)
						)
						(arc
							(start 0.254 0.2286)
							(mid 0.239121 0.264521)
							(end 0.2032 0.2794)
						)
					)
					(width 0)
					(fill yes)
				)
			)
		)
	)
	(footprint ""
		(layer "B.Cu")
		(at 149.733 -45.466 90)
		(property "Reference" "C223"
			(at 0 0 90)
			(layer "B.SilkS")
			(hide yes)
			(effects
				(font
					(size 1.27 1.27)
				)
				(justify mirror)
			)
		)
		(property "Value" "SCD1U10V2KX-5GP"
			(at -1.1811 -2.7051 90)
			(unlocked yes)
			(layer "B.Fab")
			(hide yes)
			(effects
				(font
					(size 1.016 1.016)
					(thickness 0.1524)
				)
				(justify mirror)
			)
		)
		(property "Device Type" "C402H22"
			(at -1.1811 -4.2291 90)
			(unlocked yes)
			(layer "B.Fab")
			(hide yes)
			(effects
				(font
					(size 1.016 1.016)
					(thickness 0.1524)
				)
				(justify mirror)
			)
		)
		(duplicate_pad_numbers_are_jumpers no)
		(fp_rect
			(start 0.381 0.7366)
			(end -0.381 -0.7366)
			(stroke
				(width 0)
				(type default)
			)
			(fill no)
			(layer "B.CrtYd")
		)
		(fp_rect
			(start 0.381 0.7366)
			(end -0.381 -0.7366)
			(stroke
				(width 0)
				(type default)
			)
			(fill no)
			(layer "B.Fab")
		)
		(pad "1" smd custom
			(at 0 -0.4572 270)
			(size 0.1143 0.1143)
			(layers "B.Cu" "B.Mask" "B.Paste")
			(net "P1V2_FPGA_D")
			(options
				(clearance outline)
				(anchor circle)
			)
			(primitives
				(gr_poly
					(pts
						(arc
							(start -0.254 0.1778)
							(mid -0.239121 0.213721)
							(end -0.2032 0.2286)
						)
						(arc
							(start 0.2032 0.2286)
							(mid 0.239121 0.213721)
							(end 0.254 0.1778)
						)
						(arc
							(start 0.254 -0.1778)
							(mid 0.239121 -0.213721)
							(end 0.2032 -0.2286)
						)
						(arc
							(start -0.2032 -0.2286)
							(mid -0.239121 -0.213721)
							(end -0.254 -0.1778)
						)
					)
					(width 0)
					(fill yes)
				)
			)
		)
		(pad "2" smd custom
			(at 0 0.4572 270)
			(size 0.1143 0.1143)
			(layers "B.Cu" "B.Mask" "B.Paste")
			(net "GND")
			(options
				(clearance outline)
				(anchor circle)
			)
			(primitives
				(gr_poly
					(pts
						(arc
							(start -0.254 0.1778)
							(mid -0.239121 0.213721)
							(end -0.2032 0.2286)
						)
						(arc
							(start 0.2032 0.2286)
							(mid 0.239121 0.213721)
							(end 0.254 0.1778)
						)
						(arc
							(start 0.254 -0.1778)
							(mid 0.239121 -0.213721)
							(end 0.2032 -0.2286)
						)
						(arc
							(start -0.2032 -0.2286)
							(mid -0.239121 -0.213721)
							(end -0.254 -0.1778)
						)
					)
					(width 0)
					(fill yes)
				)
			)
		)
	)
	(footprint ""
		(layer "B.Cu")
		(at 184.4548 -26.3652)
		(property "Reference" "PR218"
			(at 0 0 0)
			(layer "B.SilkS")
			(hide yes)
			(effects
				(font
					(size 1.27 1.27)
				)
				(justify mirror)
			)
		)
		(property "Value" "10KR2F-2-GP"
			(at -1.7907 -1.1176 0)
			(unlocked yes)
			(layer "B.Fab")
			(hide yes)
			(effects
				(font
					(size 1.016 1.016)
					(thickness 0.1524)
				)
				(justify mirror)
			)
		)
		(property "Device Type" "R402H16"
			(at -1.7907 -2.6416 0)
			(unlocked yes)
			(layer "B.Fab")
			(hide yes)
			(effects
				(font
					(size 1.016 1.016)
					(thickness 0.1524)
				)
				(justify mirror)
			)
		)
		(duplicate_pad_numbers_are_jumpers no)
		(fp_rect
			(start 0.381 0.8382)
			(end -0.381 -0.8382)
			(stroke
				(width 0)
				(type default)
			)
			(fill no)
			(layer "B.CrtYd")
		)
		(fp_rect
			(start 0.381 0.8382)
			(end -0.381 -0.8382)
			(stroke
				(width 0)
				(type default)
			)
			(fill no)
			(layer "B.Fab")
		)
		(pad "1" smd custom
			(at 0 -0.4318 180)
			(size 0.127 0.127)
			(layers "B.Cu" "B.Mask" "B.Paste")
			(net "ISENSE_PVDDR_A_ISEN1")
			(options
				(clearance outline)
				(anchor circle)
			)
			(primitives
				(gr_poly
					(pts
						(arc
							(start -0.2032 0.2794)
							(mid -0.239121 0.264521)
							(end -0.254 0.2286)
						)
						(arc
							(start -0.254 -0.2286)
							(mid -0.239121 -0.264521)
							(end -0.2032 -0.2794)
						)
						(arc
							(start 0.2032 -0.2794)
							(mid 0.239121 -0.264521)
							(end 0.254 -0.2286)
						)
						(arc
							(start 0.254 0.2286)
							(mid 0.239121 0.264521)
							(end 0.2032 0.2794)
						)
					)
					(width 0)
					(fill yes)
				)
			)
		)
		(pad "2" smd custom
			(at 0 0.4318 180)
			(size 0.127 0.127)
			(layers "B.Cu" "B.Mask" "B.Paste")
			(net "VR_PVDDRA_R_IS")
			(options
				(clearance outline)
				(anchor circle)
			)
			(primitives
				(gr_poly
					(pts
						(arc
							(start -0.2032 0.2794)
							(mid -0.239121 0.264521)
							(end -0.254 0.2286)
						)
						(arc
							(start -0.254 -0.2286)
							(mid -0.239121 -0.264521)
							(end -0.2032 -0.2794)
						)
						(arc
							(start 0.2032 -0.2794)
							(mid 0.239121 -0.264521)
							(end 0.254 -0.2286)
						)
						(arc
							(start 0.254 0.2286)
							(mid 0.239121 0.264521)
							(end 0.2032 0.2794)
						)
					)
					(width 0)
					(fill yes)
				)
			)
		)
	)
	(footprint ""
		(layer "B.Cu")
		(at 197.7136 -58.5724 -90)
		(property "Reference" "PC177"
			(at 0 0 90)
			(layer "B.SilkS")
			(hide yes)
			(effects
				(font
					(size 1.27 1.27)
				)
				(justify mirror)
			)
		)
		(property "Value" "SC22U6D3V5MX-2GP"
			(at 0 -4.9022 270)
			(unlocked yes)
			(layer "B.Fab")
			(hide yes)
			(effects
				(font
					(size 1.016 1.016)
					(thickness 0.1524)
				)
				(justify mirror)
			)
		)
		(property "Device Type" "C805H58"
			(at 0 -6.8072 270)
			(unlocked yes)
			(layer "B.Fab")
			(hide yes)
			(effects
				(font
					(size 1.016 1.016)
					(thickness 0.1524)
				)
				(justify mirror)
			)
		)
		(duplicate_pad_numbers_are_jumpers no)
		(fp_line
			(start -0.6096 0)
			(end 0.6096 0)
			(stroke
				(width 0.3048)
				(type default)
			)
			(layer "B.SilkS")
		)
		(fp_poly
			(pts
				(xy 0.9017 1.4351) (xy -0.9017 1.4351) (xy -0.9017 -1.4351) (xy 0.9017 -1.4351)
			)
			(stroke
				(width 0)
				(type default)
			)
			(fill no)
			(layer "B.CrtYd")
		)
		(fp_poly
			(pts
				(xy -0.9017 1.4351) (xy -0.9017 -1.4351) (xy 0.9017 -1.4351) (xy 0.9017 1.4351)
			)
			(stroke
				(width 0)
				(type default)
			)
			(fill no)
			(layer "B.Fab")
		)
		(pad "1" smd rect
			(at 0 -0.8382 90)
			(size 1.5494 0.9398)
			(layers "B.Cu" "B.Mask" "B.Paste")
			(net "PV_VDDR")
		)
		(pad "2" smd rect
			(at 0 0.8382 90)
			(size 1.5494 0.9398)
			(layers "B.Cu" "B.Mask" "B.Paste")
			(net "GND")
		)
	)
	(footprint ""
		(layer "B.Cu")
		(at 15.875 -67.2592 90)
		(property "Reference" "C173"
			(at 0 0 90)
			(layer "B.SilkS")
			(hide yes)
			(effects
				(font
					(size 1.27 1.27)
				)
				(justify mirror)
			)
		)
		(property "Value" "SCD1U16V2KX-3GP"
			(at -1.8923 -1.2065 90)
			(unlocked yes)
			(layer "B.Fab")
			(hide yes)
			(effects
				(font
					(size 1.016 1.016)
					(thickness 0.1524)
				)
				(justify mirror)
			)
		)
		(property "Device Type" "C402H22"
			(at -1.8923 -2.7305 90)
			(unlocked yes)
			(layer "B.Fab")
			(hide yes)
			(effects
				(font
					(size 1.016 1.016)
					(thickness 0.1524)
				)
				(justify mirror)
			)
		)
		(duplicate_pad_numbers_are_jumpers no)
		(fp_rect
			(start 0.381 0.7366)
			(end -0.381 -0.7366)
			(stroke
				(width 0)
				(type default)
			)
			(fill no)
			(layer "B.CrtYd")
		)
		(fp_rect
			(start 0.381 0.7366)
			(end -0.381 -0.7366)
			(stroke
				(width 0)
				(type default)
			)
			(fill no)
			(layer "B.Fab")
		)
		(pad "1" smd custom
			(at 0 -0.4572 270)
			(size 0.1143 0.1143)
			(layers "B.Cu" "B.Mask" "B.Paste")
			(net "P3V3")
			(options
				(clearance outline)
				(anchor circle)
			)
			(primitives
				(gr_poly
					(pts
						(arc
							(start -0.254 0.1778)
							(mid -0.239121 0.213721)
							(end -0.2032 0.2286)
						)
						(arc
							(start 0.2032 0.2286)
							(mid 0.239121 0.213721)
							(end 0.254 0.1778)
						)
						(arc
							(start 0.254 -0.1778)
							(mid 0.239121 -0.213721)
							(end 0.2032 -0.2286)
						)
						(arc
							(start -0.2032 -0.2286)
							(mid -0.239121 -0.213721)
							(end -0.254 -0.1778)
						)
					)
					(width 0)
					(fill yes)
				)
			)
		)
		(pad "2" smd custom
			(at 0 0.4572 270)
			(size 0.1143 0.1143)
			(layers "B.Cu" "B.Mask" "B.Paste")
			(net "GND")
			(options
				(clearance outline)
				(anchor circle)
			)
			(primitives
				(gr_poly
					(pts
						(arc
							(start -0.254 0.1778)
							(mid -0.239121 0.213721)
							(end -0.2032 0.2286)
						)
						(arc
							(start 0.2032 0.2286)
							(mid 0.239121 0.213721)
							(end 0.254 0.1778)
						)
						(arc
							(start 0.254 -0.1778)
							(mid 0.239121 -0.213721)
							(end 0.2032 -0.2286)
						)
						(arc
							(start -0.2032 -0.2286)
							(mid -0.239121 -0.213721)
							(end -0.254 -0.1778)
						)
					)
					(width 0)
					(fill yes)
				)
			)
		)
	)
	(footprint ""
		(layer "B.Cu")
		(at 65.9638 -18.5674 90)
		(property "Reference" "PR183"
			(at 0 0 90)
			(layer "B.SilkS")
			(hide yes)
			(effects
				(font
					(size 1.27 1.27)
				)
				(justify mirror)
			)
		)
		(property "Value" "237KR2F-GP"
			(at -1.7907 -1.1176 90)
			(unlocked yes)
			(layer "B.Fab")
			(hide yes)
			(effects
				(font
					(size 1.016 1.016)
					(thickness 0.1524)
				)
				(justify mirror)
			)
		)
		(property "Device Type" "R402H16"
			(at -1.7907 -2.6416 90)
			(unlocked yes)
			(layer "B.Fab")
			(hide yes)
			(effects
				(font
					(size 1.016 1.016)
					(thickness 0.1524)
				)
				(justify mirror)
			)
		)
		(duplicate_pad_numbers_are_jumpers no)
		(fp_rect
			(start 0.381 0.8382)
			(end -0.381 -0.8382)
			(stroke
				(width 0)
				(type default)
			)
			(fill no)
			(layer "B.CrtYd")
		)
		(fp_rect
			(start 0.381 0.8382)
			(end -0.381 -0.8382)
			(stroke
				(width 0)
				(type default)
			)
			(fill no)
			(layer "B.Fab")
		)
		(pad "1" smd custom
			(at 0 -0.4318 270)
			(size 0.127 0.127)
			(layers "B.Cu" "B.Mask" "B.Paste")
			(net "VR_FB_R_P1V8_STBY")
			(options
				(clearance outline)
				(anchor circle)
			)
			(primitives
				(gr_poly
					(pts
						(arc
							(start -0.2032 0.2794)
							(mid -0.239121 0.264521)
							(end -0.254 0.2286)
						)
						(arc
							(start -0.254 -0.2286)
							(mid -0.239121 -0.264521)
							(end -0.2032 -0.2794)
						)
						(arc
							(start 0.2032 -0.2794)
							(mid 0.239121 -0.264521)
							(end 0.254 -0.2286)
						)
						(arc
							(start 0.254 0.2286)
							(mid 0.239121 0.264521)
							(end 0.2032 0.2794)
						)
					)
					(width 0)
					(fill yes)
				)
			)
		)
		(pad "2" smd custom
			(at 0 0.4318 270)
			(size 0.127 0.127)
			(layers "B.Cu" "B.Mask" "B.Paste")
			(net "VR_FB_P1V8_STBY")
			(options
				(clearance outline)
				(anchor circle)
			)
			(primitives
				(gr_poly
					(pts
						(arc
							(start -0.2032 0.2794)
							(mid -0.239121 0.264521)
							(end -0.254 0.2286)
						)
						(arc
							(start -0.254 -0.2286)
							(mid -0.239121 -0.264521)
							(end -0.2032 -0.2794)
						)
						(arc
							(start 0.2032 -0.2794)
							(mid 0.239121 -0.264521)
							(end 0.254 -0.2286)
						)
						(arc
							(start 0.254 0.2286)
							(mid 0.239121 0.264521)
							(end 0.2032 0.2794)
						)
					)
					(width 0)
					(fill yes)
				)
			)
		)
	)
	(footprint ""
		(layer "B.Cu")
		(at 103.251 -17.78 180)
		(property "Reference" "C336"
			(at 0 0 0)
			(layer "B.SilkS")
			(hide yes)
			(effects
				(font
					(size 1.27 1.27)
				)
				(justify mirror)
			)
		)
		(property "Value" "SCD1U10V2KX-5GP"
			(at -1.8923 -1.2065 180)
			(unlocked yes)
			(layer "B.Fab")
			(hide yes)
			(effects
				(font
					(size 1.016 1.016)
					(thickness 0.1524)
				)
				(justify mirror)
			)
		)
		(property "Device Type" "C402H22"
			(at -1.8923 -2.7305 180)
			(unlocked yes)
			(layer "B.Fab")
			(hide yes)
			(effects
				(font
					(size 1.016 1.016)
					(thickness 0.1524)
				)
				(justify mirror)
			)
		)
		(duplicate_pad_numbers_are_jumpers no)
		(fp_rect
			(start 0.381 0.7366)
			(end -0.381 -0.7366)
			(stroke
				(width 0)
				(type default)
			)
			(fill no)
			(layer "B.CrtYd")
		)
		(fp_rect
			(start 0.381 0.7366)
			(end -0.381 -0.7366)
			(stroke
				(width 0)
				(type default)
			)
			(fill no)
			(layer "B.Fab")
		)
		(pad "1" smd custom
			(at 0 -0.4572)
			(size 0.1143 0.1143)
			(layers "B.Cu" "B.Mask" "B.Paste")
			(net "P3V3")
			(options
				(clearance outline)
				(anchor circle)
			)
			(primitives
				(gr_poly
					(pts
						(arc
							(start -0.254 0.1778)
							(mid -0.239121 0.213721)
							(end -0.2032 0.2286)
						)
						(arc
							(start 0.2032 0.2286)
							(mid 0.239121 0.213721)
							(end 0.254 0.1778)
						)
						(arc
							(start 0.254 -0.1778)
							(mid 0.239121 -0.213721)
							(end 0.2032 -0.2286)
						)
						(arc
							(start -0.2032 -0.2286)
							(mid -0.239121 -0.213721)
							(end -0.254 -0.1778)
						)
					)
					(width 0)
					(fill yes)
				)
			)
		)
		(pad "2" smd custom
			(at 0 0.4572)
			(size 0.1143 0.1143)
			(layers "B.Cu" "B.Mask" "B.Paste")
			(net "GND")
			(options
				(clearance outline)
				(anchor circle)
			)
			(primitives
				(gr_poly
					(pts
						(arc
							(start -0.254 0.1778)
							(mid -0.239121 0.213721)
							(end -0.2032 0.2286)
						)
						(arc
							(start 0.2032 0.2286)
							(mid 0.239121 0.213721)
							(end 0.254 0.1778)
						)
						(arc
							(start 0.254 -0.1778)
							(mid 0.239121 -0.213721)
							(end 0.2032 -0.2286)
						)
						(arc
							(start -0.2032 -0.2286)
							(mid -0.239121 -0.213721)
							(end -0.254 -0.1778)
						)
					)
					(width 0)
					(fill yes)
				)
			)
		)
	)
	(footprint ""
		(layer "B.Cu")
		(at 154.6352 -12.828778 180)
		(property "Reference" "C363"
			(at 0 0 0)
			(layer "B.SilkS")
			(hide yes)
			(effects
				(font
					(size 1.27 1.27)
				)
				(justify mirror)
			)
		)
		(property "Value" "SC47U6D3V5MX-1-GP"
			(at 0 -4.9022 180)
			(unlocked yes)
			(layer "B.Fab")
			(hide yes)
			(effects
				(font
					(size 1.016 1.016)
					(thickness 0.1524)
				)
				(justify mirror)
			)
		)
		(property "Device Type" "C805H54"
			(at 0 -6.8072 180)
			(unlocked yes)
			(layer "B.Fab")
			(hide yes)
			(effects
				(font
					(size 1.016 1.016)
					(thickness 0.1524)
				)
				(justify mirror)
			)
		)
		(duplicate_pad_numbers_are_jumpers no)
		(fp_line
			(start -0.6096 0)
			(end 0.6096 0)
			(stroke
				(width 0.3048)
				(type default)
			)
			(layer "B.SilkS")
		)
		(fp_poly
			(pts
				(xy 0.9017 1.4351) (xy -0.9017 1.4351) (xy -0.9017 -1.4351) (xy 0.9017 -1.4351)
			)
			(stroke
				(width 0)
				(type default)
			)
			(fill no)
			(layer "B.CrtYd")
		)
		(fp_poly
			(pts
				(xy -0.9017 1.4351) (xy -0.9017 -1.4351) (xy 0.9017 -1.4351) (xy 0.9017 1.4351)
			)
			(stroke
				(width 0)
				(type default)
			)
			(fill no)
			(layer "B.Fab")
		)
		(pad "1" smd rect
			(at 0 -0.8382)
			(size 1.5494 0.9398)
			(layers "B.Cu" "B.Mask" "B.Paste")
			(net "PV_VDDR")
		)
		(pad "2" smd rect
			(at 0 0.8382)
			(size 1.5494 0.9398)
			(layers "B.Cu" "B.Mask" "B.Paste")
			(net "GND")
		)
	)
	(footprint ""
		(layer "B.Cu")
		(at 16.383 -48.133)
		(property "Reference" "C248"
			(at 0 0 0)
			(layer "B.SilkS")
			(hide yes)
			(effects
				(font
					(size 1.27 1.27)
				)
				(justify mirror)
			)
		)
		(property "Value" "SCD1U16V2KX-3GP"
			(at -1.8923 -1.2065 0)
			(unlocked yes)
			(layer "B.Fab")
			(hide yes)
			(effects
				(font
					(size 1.016 1.016)
					(thickness 0.1524)
				)
				(justify mirror)
			)
		)
		(property "Device Type" "C402H22"
			(at -1.8923 -2.7305 0)
			(unlocked yes)
			(layer "B.Fab")
			(hide yes)
			(effects
				(font
					(size 1.016 1.016)
					(thickness 0.1524)
				)
				(justify mirror)
			)
		)
		(duplicate_pad_numbers_are_jumpers no)
		(fp_rect
			(start 0.381 0.7366)
			(end -0.381 -0.7366)
			(stroke
				(width 0)
				(type default)
			)
			(fill no)
			(layer "B.CrtYd")
		)
		(fp_rect
			(start 0.381 0.7366)
			(end -0.381 -0.7366)
			(stroke
				(width 0)
				(type default)
			)
			(fill no)
			(layer "B.Fab")
		)
		(pad "1" smd custom
			(at 0 -0.4572 180)
			(size 0.1143 0.1143)
			(layers "B.Cu" "B.Mask" "B.Paste")
			(net "P3V3")
			(options
				(clearance outline)
				(anchor circle)
			)
			(primitives
				(gr_poly
					(pts
						(arc
							(start -0.254 0.1778)
							(mid -0.239121 0.213721)
							(end -0.2032 0.2286)
						)
						(arc
							(start 0.2032 0.2286)
							(mid 0.239121 0.213721)
							(end 0.254 0.1778)
						)
						(arc
							(start 0.254 -0.1778)
							(mid 0.239121 -0.213721)
							(end 0.2032 -0.2286)
						)
						(arc
							(start -0.2032 -0.2286)
							(mid -0.239121 -0.213721)
							(end -0.254 -0.1778)
						)
					)
					(width 0)
					(fill yes)
				)
			)
		)
		(pad "2" smd custom
			(at 0 0.4572 180)
			(size 0.1143 0.1143)
			(layers "B.Cu" "B.Mask" "B.Paste")
			(net "GND")
			(options
				(clearance outline)
				(anchor circle)
			)
			(primitives
				(gr_poly
					(pts
						(arc
							(start -0.254 0.1778)
							(mid -0.239121 0.213721)
							(end -0.2032 0.2286)
						)
						(arc
							(start 0.2032 0.2286)
							(mid 0.239121 0.213721)
							(end 0.254 0.1778)
						)
						(arc
							(start 0.254 -0.1778)
							(mid 0.239121 -0.213721)
							(end 0.2032 -0.2286)
						)
						(arc
							(start -0.2032 -0.2286)
							(mid -0.239121 -0.213721)
							(end -0.254 -0.1778)
						)
					)
					(width 0)
					(fill yes)
				)
			)
		)
	)
	(footprint ""
		(layer "B.Cu")
		(at 65.786 -13.589 180)
		(property "Reference" "C306"
			(at 0 0 0)
			(layer "B.SilkS")
			(hide yes)
			(effects
				(font
					(size 1.27 1.27)
				)
				(justify mirror)
			)
		)
		(property "Value" "SCD01U16V2KX-3GP"
			(at -1.8923 -1.2065 180)
			(unlocked yes)
			(layer "B.Fab")
			(hide yes)
			(effects
				(font
					(size 1.016 1.016)
					(thickness 0.1524)
				)
				(justify mirror)
			)
		)
		(property "Device Type" "C402H22"
			(at -1.8923 -2.7305 180)
			(unlocked yes)
			(layer "B.Fab")
			(hide yes)
			(effects
				(font
					(size 1.016 1.016)
					(thickness 0.1524)
				)
				(justify mirror)
			)
		)
		(duplicate_pad_numbers_are_jumpers no)
		(fp_rect
			(start 0.381 0.7366)
			(end -0.381 -0.7366)
			(stroke
				(width 0)
				(type default)
			)
			(fill no)
			(layer "B.CrtYd")
		)
		(fp_rect
			(start 0.381 0.7366)
			(end -0.381 -0.7366)
			(stroke
				(width 0)
				(type default)
			)
			(fill no)
			(layer "B.Fab")
		)
		(pad "1" smd custom
			(at 0 -0.4572)
			(size 0.1143 0.1143)
			(layers "B.Cu" "B.Mask" "B.Paste")
			(net "SATA2_TX_C_DN0")
			(options
				(clearance outline)
				(anchor circle)
			)
			(primitives
				(gr_poly
					(pts
						(arc
							(start -0.254 0.1778)
							(mid -0.239121 0.213721)
							(end -0.2032 0.2286)
						)
						(arc
							(start 0.2032 0.2286)
							(mid 0.239121 0.213721)
							(end 0.254 0.1778)
						)
						(arc
							(start 0.254 -0.1778)
							(mid 0.239121 -0.213721)
							(end 0.2032 -0.2286)
						)
						(arc
							(start -0.2032 -0.2286)
							(mid -0.239121 -0.213721)
							(end -0.254 -0.1778)
						)
					)
					(width 0)
					(fill yes)
				)
			)
		)
		(pad "2" smd custom
			(at 0 0.4572)
			(size 0.1143 0.1143)
			(layers "B.Cu" "B.Mask" "B.Paste")
			(net "SATA2_TX_DN0")
			(options
				(clearance outline)
				(anchor circle)
			)
			(primitives
				(gr_poly
					(pts
						(arc
							(start -0.254 0.1778)
							(mid -0.239121 0.213721)
							(end -0.2032 0.2286)
						)
						(arc
							(start 0.2032 0.2286)
							(mid 0.239121 0.213721)
							(end 0.254 0.1778)
						)
						(arc
							(start 0.254 -0.1778)
							(mid 0.239121 -0.213721)
							(end 0.2032 -0.2286)
						)
						(arc
							(start -0.2032 -0.2286)
							(mid -0.239121 -0.213721)
							(end -0.254 -0.1778)
						)
					)
					(width 0)
					(fill yes)
				)
			)
		)
	)
	(footprint ""
		(layer "B.Cu")
		(at 104.648 -42.7228 -90)
		(property "Reference" "TP24"
			(at 0 0 90)
			(layer "B.SilkS")
			(hide yes)
			(effects
				(font
					(size 1.27 1.27)
				)
				(justify mirror)
			)
		)
		(property "Value" "TPAD24"
			(at 0 -2.9972 270)
			(unlocked yes)
			(layer "B.Fab")
			(hide yes)
			(effects
				(font
					(size 1.016 1.016)
					(thickness 0.1524)
				)
				(justify mirror)
			)
		)
		(property "Device Type" "TPAD24"
			(at 0 -4.5212 270)
			(unlocked yes)
			(layer "B.Fab")
			(hide yes)
			(effects
				(font
					(size 1.016 1.016)
					(thickness 0.1524)
				)
				(justify mirror)
			)
		)
		(duplicate_pad_numbers_are_jumpers no)
		(fp_poly
			(pts
				(arc
					(start 0 -0.3048)
					(mid 0 0.3048)
					(end 0 -0.3048)
				)
			)
			(stroke
				(width 0)
				(type default)
			)
			(fill no)
			(layer "B.CrtYd")
		)
		(fp_poly
			(pts
				(arc
					(start 0 -0.6096)
					(mid 0 0.6096)
					(end 0 -0.6096)
				)
			)
			(stroke
				(width 0)
				(type default)
			)
			(fill no)
			(layer "B.Fab")
		)
		(pad "1" smd circle
			(at 0 0 90)
			(size 0.6096 0.6096)
			(layers "B.Cu" "B.Mask" "B.Paste")
			(net "TP_CPU_RSVD7")
		)
	)
	(footprint ""
		(layer "B.Cu")
		(at 52.6796 -21.8948)
		(property "Reference" "R439"
			(at 0 0 0)
			(layer "B.SilkS")
			(hide yes)
			(effects
				(font
					(size 1.27 1.27)
				)
				(justify mirror)
			)
		)
		(property "Value" "10KR2F-2-GP"
			(at -1.7907 -1.1176 0)
			(unlocked yes)
			(layer "B.Fab")
			(hide yes)
			(effects
				(font
					(size 1.016 1.016)
					(thickness 0.1524)
				)
				(justify mirror)
			)
		)
		(property "Device Type" "R402H16"
			(at -1.7907 -2.6416 0)
			(unlocked yes)
			(layer "B.Fab")
			(hide yes)
			(effects
				(font
					(size 1.016 1.016)
					(thickness 0.1524)
				)
				(justify mirror)
			)
		)
		(duplicate_pad_numbers_are_jumpers no)
		(fp_rect
			(start 0.381 0.8382)
			(end -0.381 -0.8382)
			(stroke
				(width 0)
				(type default)
			)
			(fill no)
			(layer "B.CrtYd")
		)
		(fp_rect
			(start 0.381 0.8382)
			(end -0.381 -0.8382)
			(stroke
				(width 0)
				(type default)
			)
			(fill no)
			(layer "B.Fab")
		)
		(pad "1" smd custom
			(at 0 -0.4318 180)
			(size 0.127 0.127)
			(layers "B.Cu" "B.Mask" "B.Paste")
			(net "P3V3")
			(options
				(clearance outline)
				(anchor circle)
			)
			(primitives
				(gr_poly
					(pts
						(arc
							(start -0.2032 0.2794)
							(mid -0.239121 0.264521)
							(end -0.254 0.2286)
						)
						(arc
							(start -0.254 -0.2286)
							(mid -0.239121 -0.264521)
							(end -0.2032 -0.2794)
						)
						(arc
							(start 0.2032 -0.2794)
							(mid 0.239121 -0.264521)
							(end 0.254 -0.2286)
						)
						(arc
							(start 0.254 0.2286)
							(mid 0.239121 0.264521)
							(end 0.2032 0.2794)
						)
					)
					(width 0)
					(fill yes)
				)
			)
		)
		(pad "2" smd custom
			(at 0 0.4318 180)
			(size 0.127 0.127)
			(layers "B.Cu" "B.Mask" "B.Paste")
			(net "CLKBUFF_SRC_DIV#")
			(options
				(clearance outline)
				(anchor circle)
			)
			(primitives
				(gr_poly
					(pts
						(arc
							(start -0.2032 0.2794)
							(mid -0.239121 0.264521)
							(end -0.254 0.2286)
						)
						(arc
							(start -0.254 -0.2286)
							(mid -0.239121 -0.264521)
							(end -0.2032 -0.2794)
						)
						(arc
							(start 0.2032 -0.2794)
							(mid 0.239121 -0.264521)
							(end 0.254 -0.2286)
						)
						(arc
							(start 0.254 0.2286)
							(mid 0.239121 0.264521)
							(end 0.2032 0.2794)
						)
					)
					(width 0)
					(fill yes)
				)
			)
		)
	)
	(footprint ""
		(layer "B.Cu")
		(at 87.503 -68.453 -90)
		(property "Reference" "PR31"
			(at 0 0 90)
			(layer "B.SilkS")
			(hide yes)
			(effects
				(font
					(size 1.27 1.27)
				)
				(justify mirror)
			)
		)
		(property "Value" "0R6J-3-GP"
			(at 0.0508 -4.8514 270)
			(unlocked yes)
			(layer "B.Fab")
			(hide yes)
			(effects
				(font
					(size 1.016 1.016)
					(thickness 0.1524)
				)
				(justify mirror)
			)
		)
		(property "Device Type" "R1206H28"
			(at 0 -6.3754 270)
			(unlocked yes)
			(layer "B.Fab")
			(hide yes)
			(effects
				(font
					(size 1.016 1.016)
					(thickness 0.1524)
				)
				(justify mirror)
			)
		)
		(duplicate_pad_numbers_are_jumpers no)
		(fp_line
			(start -0.7239 0.381)
			(end -0.7239 -0.381)
			(stroke
				(width 0.1524)
				(type default)
			)
			(layer "B.SilkS")
		)
		(fp_line
			(start 0.7239 0.381)
			(end -0.7239 0.381)
			(stroke
				(width 0.1524)
				(type default)
			)
			(layer "B.SilkS")
		)
		(fp_line
			(start -0.7239 -0.381)
			(end 0.7239 -0.381)
			(stroke
				(width 0.1524)
				(type default)
			)
			(layer "B.SilkS")
		)
		(fp_line
			(start 0.7239 -0.381)
			(end 0.7239 0.381)
			(stroke
				(width 0.1524)
				(type default)
			)
			(layer "B.SilkS")
		)
		(fp_poly
			(pts
				(xy 0.7239 0.381) (xy -0.7239 0.381) (xy -0.7239 -0.381) (xy 0.7239 -0.381)
			)
			(stroke
				(width 0)
				(type default)
			)
			(fill yes)
			(layer "B.SilkS")
		)
		(fp_rect
			(start 1.0541 1.9812)
			(end -1.0541 -1.9812)
			(stroke
				(width 0)
				(type default)
			)
			(fill no)
			(layer "B.CrtYd")
		)
		(fp_rect
			(start 1.0541 1.9812)
			(end -1.0541 -1.9812)
			(stroke
				(width 0)
				(type default)
			)
			(fill no)
			(layer "B.Fab")
		)
		(pad "1" smd rect
			(at 0 -1.3462 90)
			(size 1.8542 1.016)
			(layers "B.Cu" "B.Mask" "B.Paste")
			(net "VR_P1V1_PVIN")
		)
		(pad "2" smd rect
			(at 0 1.3462 90)
			(size 1.8542 1.016)
			(layers "B.Cu" "B.Mask" "B.Paste")
			(net "P3V3_STBY")
		)
	)
	(footprint ""
		(layer "B.Cu")
		(at 18.923 -45.466)
		(property "Reference" "Q17"
			(at 0 0 0)
			(layer "B.SilkS")
			(hide yes)
			(effects
				(font
					(size 1.27 1.27)
				)
				(justify mirror)
			)
		)
		(property "Value" "2N7002A-7-GP"
			(at 4.3561 -5.7912 0)
			(unlocked yes)
			(layer "B.Fab")
			(hide yes)
			(effects
				(font
					(size 1.016 1.016)
					(thickness 0.1524)
				)
				(justify mirror)
			)
		)
		(property "Device Type" "SOT23DGS2D4H48"
			(at 4.3561 -7.3152 0)
			(unlocked yes)
			(layer "B.Fab")
			(hide yes)
			(effects
				(font
					(size 1.016 1.016)
					(thickness 0.1524)
				)
				(justify mirror)
			)
		)
		(duplicate_pad_numbers_are_jumpers no)
		(fp_line
			(start -1.7145 -0.4445)
			(end 1.7145 -0.4445)
			(stroke
				(width 0.1524)
				(type default)
			)
			(layer "B.SilkS")
		)
		(fp_line
			(start -1.7145 0.4445)
			(end -1.7145 -0.4445)
			(stroke
				(width 0.1524)
				(type default)
			)
			(layer "B.SilkS")
		)
		(fp_line
			(start 1.7145 -0.4445)
			(end 1.7145 0.4445)
			(stroke
				(width 0.1524)
				(type default)
			)
			(layer "B.SilkS")
		)
		(fp_line
			(start 1.7145 0.4445)
			(end -1.7145 0.4445)
			(stroke
				(width 0.1524)
				(type default)
			)
			(layer "B.SilkS")
		)
		(fp_poly
			(pts
				(xy 1.4224 1.5621) (xy 1.4224 0.9017) (xy 1.7145 0.9017) (xy 1.7145 -0.9017) (xy 0.4699 -0.9017)
				(xy 0.4699 -1.5621) (xy -0.4699 -1.5621) (xy -0.4699 -0.9017) (xy -1.7145 -0.9017) (xy -1.7145 0.9017)
				(xy -1.4224 0.9017) (xy -1.4224 1.5621) (xy -0.4826 1.5621) (xy -0.4826 0.9017) (xy 0.4826 0.9017)
				(xy 0.4826 1.5621)
			)
			(stroke
				(width 0)
				(type default)
			)
			(fill no)
			(layer "B.CrtYd")
		)
		(fp_poly
			(pts
				(xy 1.4224 1.5621) (xy 1.4224 0.9017) (xy 1.7145 0.9017) (xy 1.7145 -0.9017) (xy 0.4699 -0.9017)
				(xy 0.4699 -1.5621) (xy -0.4699 -1.5621) (xy -0.4699 -0.9017) (xy -1.7145 -0.9017) (xy -1.7145 0.9017)
				(xy -1.4224 0.9017) (xy -1.4224 1.5621) (xy -0.4826 1.5621) (xy -0.4826 0.9017) (xy 0.4826 0.9017)
				(xy 0.4826 1.5621)
			)
			(stroke
				(width 0)
				(type default)
			)
			(fill no)
			(layer "B.Fab")
		)
		(pad "D" smd custom
			(at 0 -1.069086 180)
			(size 0.17145 0.17145)
			(layers "B.Cu" "B.Mask" "B.Paste")
			(net "P3V3_DISCHARGE_D")
			(options
				(clearance outline)
				(anchor circle)
			)
			(primitives
				(gr_poly
					(pts
						(arc
							(start -0.1397 -0.3683)
							(mid -0.283384 -0.308784)
							(end -0.3429 -0.1651)
						)
						(arc
							(start -0.3429 0.1651)
							(mid -0.283384 0.308784)
							(end -0.1397 0.3683)
						)
						(arc
							(start 0.1397 0.3683)
							(mid 0.283384 0.308784)
							(end 0.3429 0.1651)
						)
						(arc
							(start 0.3429 -0.1651)
							(mid 0.283384 -0.308784)
							(end 0.1397 -0.3683)
						)
					)
					(width 0)
					(fill yes)
				)
			)
		)
		(pad "G" smd custom
			(at 0.94996 1.069086 180)
			(size 0.17145 0.17145)
			(layers "B.Cu" "B.Mask" "B.Paste")
			(net "SW_P3V3_LV_G5")
			(options
				(clearance outline)
				(anchor circle)
			)
			(primitives
				(gr_poly
					(pts
						(arc
							(start -0.1397 -0.3683)
							(mid -0.283384 -0.308784)
							(end -0.3429 -0.1651)
						)
						(arc
							(start -0.3429 0.1651)
							(mid -0.283384 0.308784)
							(end -0.1397 0.3683)
						)
						(arc
							(start 0.1397 0.3683)
							(mid 0.283384 0.308784)
							(end 0.3429 0.1651)
						)
						(arc
							(start 0.3429 -0.1651)
							(mid 0.283384 -0.308784)
							(end 0.1397 -0.3683)
						)
					)
					(width 0)
					(fill yes)
				)
			)
		)
		(pad "S" smd custom
			(at -0.94996 1.069086 180)
			(size 0.17145 0.17145)
			(layers "B.Cu" "B.Mask" "B.Paste")
			(net "GND")
			(options
				(clearance outline)
				(anchor circle)
			)
			(primitives
				(gr_poly
					(pts
						(arc
							(start -0.1397 -0.3683)
							(mid -0.283384 -0.308784)
							(end -0.3429 -0.1651)
						)
						(arc
							(start -0.3429 0.1651)
							(mid -0.283384 0.308784)
							(end -0.1397 0.3683)
						)
						(arc
							(start 0.1397 0.3683)
							(mid 0.283384 0.308784)
							(end 0.3429 0.1651)
						)
						(arc
							(start 0.3429 -0.1651)
							(mid 0.283384 -0.308784)
							(end 0.1397 -0.3683)
						)
					)
					(width 0)
					(fill yes)
				)
			)
		)
	)
	(footprint ""
		(layer "B.Cu")
		(at 109.093 -66.675 -90)
		(property "Reference" "CN7"
			(at 0 0 90)
			(layer "B.SilkS")
			(hide yes)
			(effects
				(font
					(size 1.27 1.27)
				)
				(justify mirror)
			)
		)
		(property "Value" "HR-CON2-6-GP"
			(at 4.6355 -7.3787 270)
			(unlocked yes)
			(layer "B.Fab")
			(hide yes)
			(effects
				(font
					(size 1.016 1.016)
					(thickness 0.1524)
				)
				(justify mirror)
			)
		)
		(property "Device Type" "A1001WV-S-02PN6BT1TS2L"
			(at 4.6355 -8.9027 270)
			(unlocked yes)
			(layer "B.Fab")
			(hide yes)
			(effects
				(font
					(size 1.016 1.016)
					(thickness 0.1524)
				)
				(justify mirror)
			)
		)
		(duplicate_pad_numbers_are_jumpers no)
		(fp_poly
			(pts
				(xy -0.489458 -3.443986) (xy -1.124458 -4.078986) (xy 0.145542 -4.078986)
			)
			(stroke
				(width 0)
				(type default)
			)
			(fill yes)
			(layer "B.SilkS")
		)
		(fp_poly
			(pts
				(xy 0.999998 -1.547114) (xy 0.999998 1.0287) (xy -0.999998 1.0287) (xy -0.999998 -1.547114)
			)
			(stroke
				(width 0)
				(type default)
			)
			(fill yes)
			(layer "B.SilkS")
		)
		(fp_poly
			(pts
				(xy 2.5273 1.0287) (xy 2.5273 -2.5654) (xy 0.9398 -2.5654) (xy 0.9398 -3.4417) (xy -0.9398 -3.4417)
				(xy -0.9398 -2.5654) (xy -2.5273 -2.5654) (xy -2.5273 1.0287)
			)
			(stroke
				(width 0)
				(type default)
			)
			(fill no)
			(layer "B.CrtYd")
		)
		(fp_poly
			(pts
				(xy 2.5273 1.0287) (xy 2.5273 -2.5654) (xy 0.9398 -2.5654) (xy 0.9398 -3.4417) (xy -0.9398 -3.4417)
				(xy -0.9398 -2.5654) (xy -2.5273 -2.5654) (xy -2.5273 1.0287)
			)
			(stroke
				(width 0)
				(type default)
			)
			(fill no)
			(layer "B.Fab")
		)
		(pad "1" smd rect
			(at -0.500126 -2.525014 90)
			(size 0.6096 1.5494)
			(layers "B.Cu" "B.Mask" "B.Paste")
			(net "GND")
		)
		(pad "2" smd rect
			(at 0.500126 -2.525014 90)
			(size 0.6096 1.5494)
			(layers "B.Cu" "B.Mask" "B.Paste")
			(net "P3V0_BAT")
		)
		(pad "PTH1" smd rect
			(at -1.800098 0 90)
			(size 1.1938 1.8034)
			(layers "B.Cu" "B.Mask" "B.Paste")
			(net "GND")
		)
		(pad "PTH2" smd rect
			(at 1.800098 0 90)
			(size 1.1938 1.8034)
			(layers "B.Cu" "B.Mask" "B.Paste")
			(net "GND")
		)
	)
	(footprint ""
		(layer "B.Cu")
		(at 95.885 -33.782)
		(property "Reference" "C215"
			(at 0 0 0)
			(layer "B.SilkS")
			(hide yes)
			(effects
				(font
					(size 1.27 1.27)
				)
				(justify mirror)
			)
		)
		(property "Value" "SC1U10V2KX-1GP"
			(at -1.1811 -2.7051 0)
			(unlocked yes)
			(layer "B.Fab")
			(hide yes)
			(effects
				(font
					(size 1.016 1.016)
					(thickness 0.1524)
				)
				(justify mirror)
			)
		)
		(property "Device Type" "C402H22"
			(at -1.1811 -4.2291 0)
			(unlocked yes)
			(layer "B.Fab")
			(hide yes)
			(effects
				(font
					(size 1.016 1.016)
					(thickness 0.1524)
				)
				(justify mirror)
			)
		)
		(duplicate_pad_numbers_are_jumpers no)
		(fp_rect
			(start 0.381 0.7366)
			(end -0.381 -0.7366)
			(stroke
				(width 0)
				(type default)
			)
			(fill no)
			(layer "B.CrtYd")
		)
		(fp_rect
			(start 0.381 0.7366)
			(end -0.381 -0.7366)
			(stroke
				(width 0)
				(type default)
			)
			(fill no)
			(layer "B.Fab")
		)
		(pad "1" smd custom
			(at 0 -0.4572 180)
			(size 0.1143 0.1143)
			(layers "B.Cu" "B.Mask" "B.Paste")
			(net "P1V35")
			(options
				(clearance outline)
				(anchor circle)
			)
			(primitives
				(gr_poly
					(pts
						(arc
							(start -0.254 0.1778)
							(mid -0.239121 0.213721)
							(end -0.2032 0.2286)
						)
						(arc
							(start 0.2032 0.2286)
							(mid 0.239121 0.213721)
							(end 0.254 0.1778)
						)
						(arc
							(start 0.254 -0.1778)
							(mid 0.239121 -0.213721)
							(end 0.2032 -0.2286)
						)
						(arc
							(start -0.2032 -0.2286)
							(mid -0.239121 -0.213721)
							(end -0.254 -0.1778)
						)
					)
					(width 0)
					(fill yes)
				)
			)
		)
		(pad "2" smd custom
			(at 0 0.4572 180)
			(size 0.1143 0.1143)
			(layers "B.Cu" "B.Mask" "B.Paste")
			(net "GND")
			(options
				(clearance outline)
				(anchor circle)
			)
			(primitives
				(gr_poly
					(pts
						(arc
							(start -0.254 0.1778)
							(mid -0.239121 0.213721)
							(end -0.2032 0.2286)
						)
						(arc
							(start 0.2032 0.2286)
							(mid 0.239121 0.213721)
							(end 0.254 0.1778)
						)
						(arc
							(start 0.254 -0.1778)
							(mid 0.239121 -0.213721)
							(end 0.2032 -0.2286)
						)
						(arc
							(start -0.2032 -0.2286)
							(mid -0.239121 -0.213721)
							(end -0.254 -0.1778)
						)
					)
					(width 0)
					(fill yes)
				)
			)
		)
	)
	(footprint ""
		(layer "B.Cu")
		(at 104.902 -27.321002)
		(property "Reference" "C241"
			(at 0 0 0)
			(layer "B.SilkS")
			(hide yes)
			(effects
				(font
					(size 1.27 1.27)
				)
				(justify mirror)
			)
		)
		(property "Value" "SC1U10V2KX-1GP"
			(at -1.1811 -2.7051 0)
			(unlocked yes)
			(layer "B.Fab")
			(hide yes)
			(effects
				(font
					(size 1.016 1.016)
					(thickness 0.1524)
				)
				(justify mirror)
			)
		)
		(property "Device Type" "C402H22"
			(at -1.1811 -4.2291 0)
			(unlocked yes)
			(layer "B.Fab")
			(hide yes)
			(effects
				(font
					(size 1.016 1.016)
					(thickness 0.1524)
				)
				(justify mirror)
			)
		)
		(duplicate_pad_numbers_are_jumpers no)
		(fp_rect
			(start 0.381 0.7366)
			(end -0.381 -0.7366)
			(stroke
				(width 0)
				(type default)
			)
			(fill no)
			(layer "B.CrtYd")
		)
		(fp_rect
			(start 0.381 0.7366)
			(end -0.381 -0.7366)
			(stroke
				(width 0)
				(type default)
			)
			(fill no)
			(layer "B.Fab")
		)
		(pad "1" smd custom
			(at 0 -0.4572 180)
			(size 0.1143 0.1143)
			(layers "B.Cu" "B.Mask" "B.Paste")
			(net "PV_VDDR")
			(options
				(clearance outline)
				(anchor circle)
			)
			(primitives
				(gr_poly
					(pts
						(arc
							(start -0.254 0.1778)
							(mid -0.239121 0.213721)
							(end -0.2032 0.2286)
						)
						(arc
							(start 0.2032 0.2286)
							(mid 0.239121 0.213721)
							(end 0.254 0.1778)
						)
						(arc
							(start 0.254 -0.1778)
							(mid 0.239121 -0.213721)
							(end 0.2032 -0.2286)
						)
						(arc
							(start -0.2032 -0.2286)
							(mid -0.239121 -0.213721)
							(end -0.254 -0.1778)
						)
					)
					(width 0)
					(fill yes)
				)
			)
		)
		(pad "2" smd custom
			(at 0 0.4572 180)
			(size 0.1143 0.1143)
			(layers "B.Cu" "B.Mask" "B.Paste")
			(net "GND")
			(options
				(clearance outline)
				(anchor circle)
			)
			(primitives
				(gr_poly
					(pts
						(arc
							(start -0.254 0.1778)
							(mid -0.239121 0.213721)
							(end -0.2032 0.2286)
						)
						(arc
							(start 0.2032 0.2286)
							(mid 0.239121 0.213721)
							(end 0.254 0.1778)
						)
						(arc
							(start 0.254 -0.1778)
							(mid 0.239121 -0.213721)
							(end 0.2032 -0.2286)
						)
						(arc
							(start -0.2032 -0.2286)
							(mid -0.239121 -0.213721)
							(end -0.254 -0.1778)
						)
					)
					(width 0)
					(fill yes)
				)
			)
		)
	)
	(footprint ""
		(layer "B.Cu")
		(at 88.519 -24.765 -90)
		(property "Reference" "C259"
			(at 0 0 90)
			(layer "B.SilkS")
			(hide yes)
			(effects
				(font
					(size 1.27 1.27)
				)
				(justify mirror)
			)
		)
		(property "Value" "SC1U10V2KX-1GP"
			(at -1.1811 -2.7051 270)
			(unlocked yes)
			(layer "B.Fab")
			(hide yes)
			(effects
				(font
					(size 1.016 1.016)
					(thickness 0.1524)
				)
				(justify mirror)
			)
		)
		(property "Device Type" "C402H22"
			(at -1.1811 -4.2291 270)
			(unlocked yes)
			(layer "B.Fab")
			(hide yes)
			(effects
				(font
					(size 1.016 1.016)
					(thickness 0.1524)
				)
				(justify mirror)
			)
		)
		(duplicate_pad_numbers_are_jumpers no)
		(fp_rect
			(start 0.381 0.7366)
			(end -0.381 -0.7366)
			(stroke
				(width 0)
				(type default)
			)
			(fill no)
			(layer "B.CrtYd")
		)
		(fp_rect
			(start 0.381 0.7366)
			(end -0.381 -0.7366)
			(stroke
				(width 0)
				(type default)
			)
			(fill no)
			(layer "B.Fab")
		)
		(pad "1" smd custom
			(at 0 -0.4572 90)
			(size 0.1143 0.1143)
			(layers "B.Cu" "B.Mask" "B.Paste")
			(net "P1V0")
			(options
				(clearance outline)
				(anchor circle)
			)
			(primitives
				(gr_poly
					(pts
						(arc
							(start -0.254 0.1778)
							(mid -0.239121 0.213721)
							(end -0.2032 0.2286)
						)
						(arc
							(start 0.2032 0.2286)
							(mid 0.239121 0.213721)
							(end 0.254 0.1778)
						)
						(arc
							(start 0.254 -0.1778)
							(mid 0.239121 -0.213721)
							(end 0.2032 -0.2286)
						)
						(arc
							(start -0.2032 -0.2286)
							(mid -0.239121 -0.213721)
							(end -0.254 -0.1778)
						)
					)
					(width 0)
					(fill yes)
				)
			)
		)
		(pad "2" smd custom
			(at 0 0.4572 90)
			(size 0.1143 0.1143)
			(layers "B.Cu" "B.Mask" "B.Paste")
			(net "GND")
			(options
				(clearance outline)
				(anchor circle)
			)
			(primitives
				(gr_poly
					(pts
						(arc
							(start -0.254 0.1778)
							(mid -0.239121 0.213721)
							(end -0.2032 0.2286)
						)
						(arc
							(start 0.2032 0.2286)
							(mid 0.239121 0.213721)
							(end 0.254 0.1778)
						)
						(arc
							(start 0.254 -0.1778)
							(mid 0.239121 -0.213721)
							(end 0.2032 -0.2286)
						)
						(arc
							(start -0.2032 -0.2286)
							(mid -0.239121 -0.213721)
							(end -0.254 -0.1778)
						)
					)
					(width 0)
					(fill yes)
				)
			)
		)
	)
	(footprint ""
		(layer "B.Cu")
		(at 189.5856 -12.701778 90)
		(property "Reference" "R198"
			(at 0 0 90)
			(layer "B.SilkS")
			(hide yes)
			(effects
				(font
					(size 1.27 1.27)
				)
				(justify mirror)
			)
		)
		(property "Value" "4K7R2F-GP"
			(at -0.064008 -3.993896 90)
			(unlocked yes)
			(layer "B.Fab")
			(hide yes)
			(effects
				(font
					(size 1.016 1.016)
					(thickness 0.1524)
				)
				(justify mirror)
			)
		)
		(property "Device Type" "R402H16"
			(at -0.064008 -5.517896 90)
			(unlocked yes)
			(layer "B.Fab")
			(hide yes)
			(effects
				(font
					(size 1.016 1.016)
					(thickness 0.1524)
				)
				(justify mirror)
			)
		)
		(duplicate_pad_numbers_are_jumpers no)
		(fp_rect
			(start 0.381 0.8382)
			(end -0.381 -0.8382)
			(stroke
				(width 0)
				(type default)
			)
			(fill no)
			(layer "B.CrtYd")
		)
		(fp_rect
			(start 0.381 0.8382)
			(end -0.381 -0.8382)
			(stroke
				(width 0)
				(type default)
			)
			(fill no)
			(layer "B.Fab")
		)
		(pad "1" smd custom
			(at 0 -0.4318 270)
			(size 0.127 0.127)
			(layers "B.Cu" "B.Mask" "B.Paste")
			(net "P3V3_STBY")
			(options
				(clearance outline)
				(anchor circle)
			)
			(primitives
				(gr_poly
					(pts
						(arc
							(start -0.2032 0.2794)
							(mid -0.239121 0.264521)
							(end -0.254 0.2286)
						)
						(arc
							(start -0.254 -0.2286)
							(mid -0.239121 -0.264521)
							(end -0.2032 -0.2794)
						)
						(arc
							(start 0.2032 -0.2794)
							(mid 0.239121 -0.264521)
							(end 0.254 -0.2286)
						)
						(arc
							(start 0.254 0.2286)
							(mid 0.239121 0.264521)
							(end 0.2032 0.2794)
						)
					)
					(width 0)
					(fill yes)
				)
			)
		)
		(pad "2" smd custom
			(at 0 0.4318 270)
			(size 0.127 0.127)
			(layers "B.Cu" "B.Mask" "B.Paste")
			(net "CHB_0_SA1")
			(options
				(clearance outline)
				(anchor circle)
			)
			(primitives
				(gr_poly
					(pts
						(arc
							(start -0.2032 0.2794)
							(mid -0.239121 0.264521)
							(end -0.254 0.2286)
						)
						(arc
							(start -0.254 -0.2286)
							(mid -0.239121 -0.264521)
							(end -0.2032 -0.2794)
						)
						(arc
							(start 0.2032 -0.2794)
							(mid 0.239121 -0.264521)
							(end 0.254 -0.2286)
						)
						(arc
							(start 0.254 0.2286)
							(mid 0.239121 0.264521)
							(end 0.2032 0.2794)
						)
					)
					(width 0)
					(fill yes)
				)
			)
		)
	)
	(footprint ""
		(layer "B.Cu")
		(at 117.0432 -36.5506 90)
		(property "Reference" "PTC4"
			(at 0 0 90)
			(layer "B.SilkS")
			(hide yes)
			(effects
				(font
					(size 1.27 1.27)
				)
				(justify mirror)
			)
		)
		(property "Value" "SE470UF2VDM-GP"
			(at 0 -9.6012 90)
			(unlocked yes)
			(layer "B.Fab")
			(hide yes)
			(effects
				(font
					(size 1.016 1.016)
					(thickness 0.1524)
				)
				(justify mirror)
			)
		)
		(property "Device Type" "CT7343H83"
			(at 0 -11.1252 90)
			(unlocked yes)
			(layer "B.Fab")
			(hide yes)
			(effects
				(font
					(size 1.016 1.016)
					(thickness 0.1524)
				)
				(justify mirror)
			)
		)
		(duplicate_pad_numbers_are_jumpers no)
		(fp_line
			(start 2.206752 -4.2926)
			(end -2.155698 -4.2926)
			(stroke
				(width 0.508)
				(type default)
			)
			(layer "B.SilkS")
		)
		(fp_rect
			(start 2.1463 3.6449)
			(end -2.1463 -3.6449)
			(stroke
				(width 0)
				(type default)
			)
			(fill no)
			(layer "B.CrtYd")
		)
		(fp_poly
			(pts
				(xy 3.81 3.9116) (xy 3.81 -3.9116) (xy 2.54 -3.9116) (xy 2.4003 -3.9116) (xy 2.4003 -4.0386) (xy -2.4003 -4.0386)
				(xy -2.4003 -3.9116) (xy -2.54 -3.9116) (xy -2.5654 -3.9116) (xy -3.81 -3.9116) (xy -3.81 -1.6256)
				(xy -2.1463 -1.6256) (xy -2.1463 -3.6449) (xy 2.1463 -3.6449) (xy 2.1463 3.6449) (xy -2.1463 3.6449)
				(xy -2.1463 -1.6129) (xy -3.81 -1.6129) (xy -3.81 3.9116) (xy -2.4003 3.9116) (xy -2.4003 3.9243)
				(xy -2.4003 4.0386) (xy 2.4003 4.0386) (xy 2.4003 3.9116)
			)
			(stroke
				(width 0)
				(type default)
			)
			(fill no)
			(layer "B.CrtYd")
		)
		(fp_rect
			(start 3.81 3.9116)
			(end 2.4003 -3.9116)
			(stroke
				(width 0)
				(type default)
			)
			(fill no)
			(layer "B.Fab")
		)
		(fp_rect
			(start -2.4003 3.9116)
			(end -3.81 -3.9116)
			(stroke
				(width 0)
				(type default)
			)
			(fill no)
			(layer "B.Fab")
		)
		(fp_rect
			(start 2.4003 4.0386)
			(end -2.4003 -4.0386)
			(stroke
				(width 0)
				(type default)
			)
			(fill no)
			(layer "B.Fab")
		)
		(pad "1" smd rect
			(at 0 -2.9591 270)
			(size 2.413 1.905)
			(layers "B.Cu" "B.Mask" "B.Paste")
			(net "PVCCP")
		)
		(pad "2" smd rect
			(at 0 2.9591 270)
			(size 2.413 1.905)
			(layers "B.Cu" "B.Mask" "B.Paste")
			(net "GND")
		)
	)
	(footprint ""
		(layer "B.Cu")
		(at 33.147 -42.926 90)
		(property "Reference" "PR186"
			(at 0 0 90)
			(layer "B.SilkS")
			(hide yes)
			(effects
				(font
					(size 1.27 1.27)
				)
				(justify mirror)
			)
		)
		(property "Value" "4K22R2F-GP"
			(at -1.7907 -1.1176 90)
			(unlocked yes)
			(layer "B.Fab")
			(hide yes)
			(effects
				(font
					(size 1.016 1.016)
					(thickness 0.1524)
				)
				(justify mirror)
			)
		)
		(property "Device Type" "R402H16"
			(at -1.7907 -2.6416 90)
			(unlocked yes)
			(layer "B.Fab")
			(hide yes)
			(effects
				(font
					(size 1.016 1.016)
					(thickness 0.1524)
				)
				(justify mirror)
			)
		)
		(duplicate_pad_numbers_are_jumpers no)
		(fp_rect
			(start 0.381 0.8382)
			(end -0.381 -0.8382)
			(stroke
				(width 0)
				(type default)
			)
			(fill no)
			(layer "B.CrtYd")
		)
		(fp_rect
			(start 0.381 0.8382)
			(end -0.381 -0.8382)
			(stroke
				(width 0)
				(type default)
			)
			(fill no)
			(layer "B.Fab")
		)
		(pad "1" smd custom
			(at 0 -0.4318 270)
			(size 0.127 0.127)
			(layers "B.Cu" "B.Mask" "B.Paste")
			(net "P1V5_STBY_OUT")
			(options
				(clearance outline)
				(anchor circle)
			)
			(primitives
				(gr_poly
					(pts
						(arc
							(start -0.2032 0.2794)
							(mid -0.239121 0.264521)
							(end -0.254 0.2286)
						)
						(arc
							(start -0.254 -0.2286)
							(mid -0.239121 -0.264521)
							(end -0.2032 -0.2794)
						)
						(arc
							(start 0.2032 -0.2794)
							(mid 0.239121 -0.264521)
							(end 0.254 -0.2286)
						)
						(arc
							(start 0.254 0.2286)
							(mid 0.239121 0.264521)
							(end 0.2032 0.2794)
						)
					)
					(width 0)
					(fill yes)
				)
			)
		)
		(pad "2" smd custom
			(at 0 0.4318 270)
			(size 0.127 0.127)
			(layers "B.Cu" "B.Mask" "B.Paste")
			(net "P1V5_STBY_FB")
			(options
				(clearance outline)
				(anchor circle)
			)
			(primitives
				(gr_poly
					(pts
						(arc
							(start -0.2032 0.2794)
							(mid -0.239121 0.264521)
							(end -0.254 0.2286)
						)
						(arc
							(start -0.254 -0.2286)
							(mid -0.239121 -0.264521)
							(end -0.2032 -0.2794)
						)
						(arc
							(start 0.2032 -0.2794)
							(mid 0.239121 -0.264521)
							(end 0.254 -0.2286)
						)
						(arc
							(start 0.254 0.2286)
							(mid 0.239121 0.264521)
							(end 0.2032 0.2794)
						)
					)
					(width 0)
					(fill yes)
				)
			)
		)
	)
	(footprint ""
		(layer "B.Cu")
		(at 22.352 -64.77 180)
		(property "Reference" "PR26"
			(at 0 0 0)
			(layer "B.SilkS")
			(hide yes)
			(effects
				(font
					(size 1.27 1.27)
				)
				(justify mirror)
			)
		)
		(property "Value" "13K7R2F-GP"
			(at -1.7907 -1.1176 180)
			(unlocked yes)
			(layer "B.Fab")
			(hide yes)
			(effects
				(font
					(size 1.016 1.016)
					(thickness 0.1524)
				)
				(justify mirror)
			)
		)
		(property "Device Type" "R402H16"
			(at -1.7907 -2.6416 180)
			(unlocked yes)
			(layer "B.Fab")
			(hide yes)
			(effects
				(font
					(size 1.016 1.016)
					(thickness 0.1524)
				)
				(justify mirror)
			)
		)
		(duplicate_pad_numbers_are_jumpers no)
		(fp_rect
			(start 0.381 0.8382)
			(end -0.381 -0.8382)
			(stroke
				(width 0)
				(type default)
			)
			(fill no)
			(layer "B.CrtYd")
		)
		(fp_rect
			(start 0.381 0.8382)
			(end -0.381 -0.8382)
			(stroke
				(width 0)
				(type default)
			)
			(fill no)
			(layer "B.Fab")
		)
		(pad "1" smd custom
			(at 0 -0.4318)
			(size 0.127 0.127)
			(layers "B.Cu" "B.Mask" "B.Paste")
			(net "VR_PVNN_PROG2")
			(options
				(clearance outline)
				(anchor circle)
			)
			(primitives
				(gr_poly
					(pts
						(arc
							(start -0.2032 0.2794)
							(mid -0.239121 0.264521)
							(end -0.254 0.2286)
						)
						(arc
							(start -0.254 -0.2286)
							(mid -0.239121 -0.264521)
							(end -0.2032 -0.2794)
						)
						(arc
							(start 0.2032 -0.2794)
							(mid 0.239121 -0.264521)
							(end 0.254 -0.2286)
						)
						(arc
							(start 0.254 0.2286)
							(mid 0.239121 0.264521)
							(end 0.2032 0.2794)
						)
					)
					(width 0)
					(fill yes)
				)
			)
		)
		(pad "2" smd custom
			(at 0 0.4318)
			(size 0.127 0.127)
			(layers "B.Cu" "B.Mask" "B.Paste")
			(net "GND")
			(options
				(clearance outline)
				(anchor circle)
			)
			(primitives
				(gr_poly
					(pts
						(arc
							(start -0.2032 0.2794)
							(mid -0.239121 0.264521)
							(end -0.254 0.2286)
						)
						(arc
							(start -0.254 -0.2286)
							(mid -0.239121 -0.264521)
							(end -0.2032 -0.2794)
						)
						(arc
							(start 0.2032 -0.2794)
							(mid 0.239121 -0.264521)
							(end 0.254 -0.2286)
						)
						(arc
							(start 0.254 0.2286)
							(mid 0.239121 0.264521)
							(end 0.2032 0.2794)
						)
					)
					(width 0)
					(fill yes)
				)
			)
		)
	)
	(footprint ""
		(layer "B.Cu")
		(at 84.65058 -35.87496)
		(property "Reference" "TP60"
			(at 0 0 0)
			(layer "B.SilkS")
			(hide yes)
			(effects
				(font
					(size 1.27 1.27)
				)
				(justify mirror)
			)
		)
		(property "Value" "TPAD32-GP"
			(at 0 -3.166364 0)
			(unlocked yes)
			(layer "B.Fab")
			(hide yes)
			(effects
				(font
					(size 1.016 1.016)
					(thickness 0.1524)
				)
				(justify mirror)
			)
		)
		(property "Device Type" "TPAD32"
			(at 0 -4.690618 0)
			(unlocked yes)
			(layer "B.Fab")
			(hide yes)
			(effects
				(font
					(size 1.016 1.016)
					(thickness 0.1524)
				)
				(justify mirror)
			)
		)
		(duplicate_pad_numbers_are_jumpers no)
		(fp_poly
			(pts
				(arc
					(start 0.7112 0)
					(mid -0.7112 0)
					(end 0.7112 0)
				)
			)
			(stroke
				(width 0)
				(type default)
			)
			(fill no)
			(layer "B.CrtYd")
		)
		(fp_poly
			(pts
				(arc
					(start 0.7112 0)
					(mid -0.7112 0)
					(end 0.7112 0)
				)
			)
			(stroke
				(width 0)
				(type default)
			)
			(fill no)
			(layer "B.Fab")
		)
		(pad "1" smd circle
			(at 0 0 180)
			(size 0.8128 0.8128)
			(layers "B.Cu" "B.Mask" "B.Paste")
			(net "XDP_SOC_CPU_TDI")
		)
	)
	(footprint ""
		(layer "B.Cu")
		(at 201.2442 -49.7332 90)
		(property "Reference" "PTC2"
			(at 0 0 90)
			(layer "B.SilkS")
			(hide yes)
			(effects
				(font
					(size 1.27 1.27)
				)
				(justify mirror)
			)
		)
		(property "Value" "SE470UF2VDM-GP"
			(at 3.220466 1.242822 90)
			(unlocked yes)
			(layer "B.Fab")
			(hide yes)
			(effects
				(font
					(size 1.016 1.016)
					(thickness 0.1524)
				)
				(justify mirror)
			)
		)
		(property "Device Type" "CT7343H83"
			(at 3.220466 -0.281178 90)
			(unlocked yes)
			(layer "B.Fab")
			(hide yes)
			(effects
				(font
					(size 1.016 1.016)
					(thickness 0.1524)
				)
				(justify mirror)
			)
		)
		(duplicate_pad_numbers_are_jumpers no)
		(fp_line
			(start 2.206752 -4.2926)
			(end -2.155698 -4.2926)
			(stroke
				(width 0.508)
				(type default)
			)
			(layer "B.SilkS")
		)
		(fp_rect
			(start 2.1463 3.6449)
			(end -2.1463 -3.6449)
			(stroke
				(width 0)
				(type default)
			)
			(fill no)
			(layer "B.CrtYd")
		)
		(fp_poly
			(pts
				(xy 3.81 3.9116) (xy 3.81 -3.9116) (xy 2.54 -3.9116) (xy 2.4003 -3.9116) (xy 2.4003 -4.0386) (xy -2.4003 -4.0386)
				(xy -2.4003 -3.9116) (xy -2.54 -3.9116) (xy -2.5654 -3.9116) (xy -3.81 -3.9116) (xy -3.81 -1.6256)
				(xy -2.1463 -1.6256) (xy -2.1463 -3.6449) (xy 2.1463 -3.6449) (xy 2.1463 3.6449) (xy -2.1463 3.6449)
				(xy -2.1463 -1.6129) (xy -3.81 -1.6129) (xy -3.81 3.9116) (xy -2.4003 3.9116) (xy -2.4003 3.9243)
				(xy -2.4003 4.0386) (xy 2.4003 4.0386) (xy 2.4003 3.9116)
			)
			(stroke
				(width 0)
				(type default)
			)
			(fill no)
			(layer "B.CrtYd")
		)
		(fp_rect
			(start 3.81 3.9116)
			(end 2.4003 -3.9116)
			(stroke
				(width 0)
				(type default)
			)
			(fill no)
			(layer "B.Fab")
		)
		(fp_rect
			(start -2.4003 3.9116)
			(end -3.81 -3.9116)
			(stroke
				(width 0)
				(type default)
			)
			(fill no)
			(layer "B.Fab")
		)
		(fp_rect
			(start 2.4003 4.0386)
			(end -2.4003 -4.0386)
			(stroke
				(width 0)
				(type default)
			)
			(fill no)
			(layer "B.Fab")
		)
		(pad "1" smd rect
			(at 0 -2.9591 270)
			(size 2.413 1.905)
			(layers "B.Cu" "B.Mask" "B.Paste")
			(net "PV_VDDR")
		)
		(pad "2" smd rect
			(at 0 2.9591 270)
			(size 2.413 1.905)
			(layers "B.Cu" "B.Mask" "B.Paste")
			(net "GND")
		)
	)
	(footprint ""
		(layer "B.Cu")
		(at 36.957 -26.924 -90)
		(property "Reference" "C309"
			(at 0 0 90)
			(layer "B.SilkS")
			(hide yes)
			(effects
				(font
					(size 1.27 1.27)
				)
				(justify mirror)
			)
		)
		(property "Value" "SCD1U10V2KX-5GP"
			(at -1.8923 -1.2065 270)
			(unlocked yes)
			(layer "B.Fab")
			(hide yes)
			(effects
				(font
					(size 1.016 1.016)
					(thickness 0.1524)
				)
				(justify mirror)
			)
		)
		(property "Device Type" "C402H22"
			(at -1.8923 -2.7305 270)
			(unlocked yes)
			(layer "B.Fab")
			(hide yes)
			(effects
				(font
					(size 1.016 1.016)
					(thickness 0.1524)
				)
				(justify mirror)
			)
		)
		(duplicate_pad_numbers_are_jumpers no)
		(fp_rect
			(start 0.381 0.7366)
			(end -0.381 -0.7366)
			(stroke
				(width 0)
				(type default)
			)
			(fill no)
			(layer "B.CrtYd")
		)
		(fp_rect
			(start 0.381 0.7366)
			(end -0.381 -0.7366)
			(stroke
				(width 0)
				(type default)
			)
			(fill no)
			(layer "B.Fab")
		)
		(pad "1" smd custom
			(at 0 -0.4572 90)
			(size 0.1143 0.1143)
			(layers "B.Cu" "B.Mask" "B.Paste")
			(net "P3V3_VDD_CLKBUFF")
			(options
				(clearance outline)
				(anchor circle)
			)
			(primitives
				(gr_poly
					(pts
						(arc
							(start -0.254 0.1778)
							(mid -0.239121 0.213721)
							(end -0.2032 0.2286)
						)
						(arc
							(start 0.2032 0.2286)
							(mid 0.239121 0.213721)
							(end 0.254 0.1778)
						)
						(arc
							(start 0.254 -0.1778)
							(mid 0.239121 -0.213721)
							(end 0.2032 -0.2286)
						)
						(arc
							(start -0.2032 -0.2286)
							(mid -0.239121 -0.213721)
							(end -0.254 -0.1778)
						)
					)
					(width 0)
					(fill yes)
				)
			)
		)
		(pad "2" smd custom
			(at 0 0.4572 90)
			(size 0.1143 0.1143)
			(layers "B.Cu" "B.Mask" "B.Paste")
			(net "GND")
			(options
				(clearance outline)
				(anchor circle)
			)
			(primitives
				(gr_poly
					(pts
						(arc
							(start -0.254 0.1778)
							(mid -0.239121 0.213721)
							(end -0.2032 0.2286)
						)
						(arc
							(start 0.2032 0.2286)
							(mid 0.239121 0.213721)
							(end 0.254 0.1778)
						)
						(arc
							(start 0.254 -0.1778)
							(mid 0.239121 -0.213721)
							(end 0.2032 -0.2286)
						)
						(arc
							(start -0.2032 -0.2286)
							(mid -0.239121 -0.213721)
							(end -0.254 -0.1778)
						)
					)
					(width 0)
					(fill yes)
				)
			)
		)
	)
	(footprint ""
		(layer "B.Cu")
		(at 194.945 -31.877)
		(property "Reference" "PC102"
			(at 0 0 0)
			(layer "B.SilkS")
			(hide yes)
			(effects
				(font
					(size 1.27 1.27)
				)
				(justify mirror)
			)
		)
		(property "Value" "SC22U25V5MX-GP"
			(at 0 -4.9022 0)
			(unlocked yes)
			(layer "B.Fab")
			(hide yes)
			(effects
				(font
					(size 1.016 1.016)
					(thickness 0.1524)
				)
				(justify mirror)
			)
		)
		(property "Device Type" "C805H58"
			(at 0 -6.8072 0)
			(unlocked yes)
			(layer "B.Fab")
			(hide yes)
			(effects
				(font
					(size 1.016 1.016)
					(thickness 0.1524)
				)
				(justify mirror)
			)
		)
		(duplicate_pad_numbers_are_jumpers no)
		(fp_line
			(start -0.6096 0)
			(end 0.6096 0)
			(stroke
				(width 0.3048)
				(type default)
			)
			(layer "B.SilkS")
		)
		(fp_poly
			(pts
				(xy 0.9017 1.4351) (xy -0.9017 1.4351) (xy -0.9017 -1.4351) (xy 0.9017 -1.4351)
			)
			(stroke
				(width 0)
				(type default)
			)
			(fill no)
			(layer "B.CrtYd")
		)
		(fp_poly
			(pts
				(xy -0.9017 1.4351) (xy -0.9017 -1.4351) (xy 0.9017 -1.4351) (xy 0.9017 1.4351)
			)
			(stroke
				(width 0)
				(type default)
			)
			(fill no)
			(layer "B.Fab")
		)
		(pad "1" smd rect
			(at 0 -0.8382 180)
			(size 1.5494 0.9398)
			(layers "B.Cu" "B.Mask" "B.Paste")
			(net "VR_PVDDR_A_VIN")
		)
		(pad "2" smd rect
			(at 0 0.8382 180)
			(size 1.5494 0.9398)
			(layers "B.Cu" "B.Mask" "B.Paste")
			(net "GND")
		)
	)
	(footprint ""
		(layer "B.Cu")
		(at 102.489 -64.643 90)
		(property "Reference" "PG1"
			(at 0 0 90)
			(layer "B.SilkS")
			(hide yes)
			(effects
				(font
					(size 1.27 1.27)
				)
				(justify mirror)
			)
		)
		(property "Value" "COPPER-CLOSE-GP-U"
			(at -0.0762 -2.8702 90)
			(unlocked yes)
			(layer "B.Fab")
			(hide yes)
			(effects
				(font
					(size 1.016 1.016)
					(thickness 0.1524)
				)
				(justify mirror)
			)
		)
		(property "Device Type" "CON2C-U"
			(at -0.0762 -4.3942 90)
			(unlocked yes)
			(layer "B.Fab")
			(hide yes)
			(effects
				(font
					(size 1.016 1.016)
					(thickness 0.1524)
				)
				(justify mirror)
			)
		)
		(duplicate_pad_numbers_are_jumpers no)
		(fp_rect
			(start 0.9398 0.9652)
			(end -0.9398 -0.9652)
			(stroke
				(width 0)
				(type default)
			)
			(fill no)
			(layer "B.CrtYd")
		)
		(fp_rect
			(start 0.9398 0.9652)
			(end -0.9398 -0.9652)
			(stroke
				(width 0)
				(type default)
			)
			(fill no)
			(layer "B.Fab")
		)
		(pad "1" smd custom
			(at 0 -0.5334 270)
			(size 0.17145 0.17145)
			(layers "B.Cu" "B.Mask" "B.Paste")
			(net "AGND_P1V1")
			(options
				(clearance outline)
				(anchor circle)
			)
			(primitives
				(gr_poly
					(pts
						(xy -0.127 -0.3429) (xy -0.127 -0.1651) (xy -0.635 0.3429) (xy 0.635 0.3429) (xy 0.127 -0.1651)
						(xy 0.127 -0.3429)
					)
					(width 0)
					(fill yes)
				)
			)
		)
		(pad "2" smd custom
			(at 0 0.5334 270)
			(size 0.17145 0.17145)
			(layers "B.Cu" "B.Mask" "B.Paste")
			(net "GND")
			(options
				(clearance outline)
				(anchor circle)
			)
			(primitives
				(gr_poly
					(pts
						(xy -0.635 -0.3429) (xy -0.127 0.1651) (xy -0.127 0.3429) (xy 0.127 0.3429) (xy 0.127 0.1651)
						(xy 0.635 -0.3429)
					)
					(width 0)
					(fill yes)
				)
			)
		)
	)
	(footprint ""
		(layer "B.Cu")
		(at 134.366 -47.879 90)
		(property "Reference" "R399"
			(at 0 0 90)
			(layer "B.SilkS")
			(hide yes)
			(effects
				(font
					(size 1.27 1.27)
				)
				(justify mirror)
			)
		)
		(property "Value" "0R2J-2-GP"
			(at -1.7907 -1.1176 90)
			(unlocked yes)
			(layer "B.Fab")
			(hide yes)
			(effects
				(font
					(size 1.016 1.016)
					(thickness 0.1524)
				)
				(justify mirror)
			)
		)
		(property "Device Type" "R402H16"
			(at -1.7907 -2.6416 90)
			(unlocked yes)
			(layer "B.Fab")
			(hide yes)
			(effects
				(font
					(size 1.016 1.016)
					(thickness 0.1524)
				)
				(justify mirror)
			)
		)
		(duplicate_pad_numbers_are_jumpers no)
		(fp_rect
			(start 0.381 0.8382)
			(end -0.381 -0.8382)
			(stroke
				(width 0)
				(type default)
			)
			(fill no)
			(layer "B.CrtYd")
		)
		(fp_rect
			(start 0.381 0.8382)
			(end -0.381 -0.8382)
			(stroke
				(width 0)
				(type default)
			)
			(fill no)
			(layer "B.Fab")
		)
		(pad "1" smd custom
			(at 0 -0.4318 270)
			(size 0.127 0.127)
			(layers "B.Cu" "B.Mask" "B.Paste")
			(net "REV_CPU_FPGA_IO1")
			(options
				(clearance outline)
				(anchor circle)
			)
			(primitives
				(gr_poly
					(pts
						(arc
							(start -0.2032 0.2794)
							(mid -0.239121 0.264521)
							(end -0.254 0.2286)
						)
						(arc
							(start -0.254 -0.2286)
							(mid -0.239121 -0.264521)
							(end -0.2032 -0.2794)
						)
						(arc
							(start 0.2032 -0.2794)
							(mid 0.239121 -0.264521)
							(end 0.254 -0.2286)
						)
						(arc
							(start 0.254 0.2286)
							(mid 0.239121 0.264521)
							(end 0.2032 0.2794)
						)
					)
					(width 0)
					(fill yes)
				)
			)
		)
		(pad "2" smd custom
			(at 0 0.4318 270)
			(size 0.127 0.127)
			(layers "B.Cu" "B.Mask" "B.Paste")
			(net "REV_CPU_FPGA_R_IO1")
			(options
				(clearance outline)
				(anchor circle)
			)
			(primitives
				(gr_poly
					(pts
						(arc
							(start -0.2032 0.2794)
							(mid -0.239121 0.264521)
							(end -0.254 0.2286)
						)
						(arc
							(start -0.254 -0.2286)
							(mid -0.239121 -0.264521)
							(end -0.2032 -0.2794)
						)
						(arc
							(start 0.2032 -0.2794)
							(mid 0.239121 -0.264521)
							(end 0.254 -0.2286)
						)
						(arc
							(start 0.254 0.2286)
							(mid 0.239121 0.264521)
							(end 0.2032 0.2794)
						)
					)
					(width 0)
					(fill yes)
				)
			)
		)
	)
	(footprint ""
		(layer "B.Cu")
		(at 132.08 -59.944)
		(property "Reference" "R227"
			(at 0 0 0)
			(layer "B.SilkS")
			(hide yes)
			(effects
				(font
					(size 1.27 1.27)
				)
				(justify mirror)
			)
		)
		(property "Value" "4K7R2F-GP"
			(at -0.064008 -3.993896 0)
			(unlocked yes)
			(layer "B.Fab")
			(hide yes)
			(effects
				(font
					(size 1.016 1.016)
					(thickness 0.1524)
				)
				(justify mirror)
			)
		)
		(property "Device Type" "R402H16"
			(at -0.064008 -5.517896 0)
			(unlocked yes)
			(layer "B.Fab")
			(hide yes)
			(effects
				(font
					(size 1.016 1.016)
					(thickness 0.1524)
				)
				(justify mirror)
			)
		)
		(duplicate_pad_numbers_are_jumpers no)
		(fp_rect
			(start 0.381 0.8382)
			(end -0.381 -0.8382)
			(stroke
				(width 0)
				(type default)
			)
			(fill no)
			(layer "B.CrtYd")
		)
		(fp_rect
			(start 0.381 0.8382)
			(end -0.381 -0.8382)
			(stroke
				(width 0)
				(type default)
			)
			(fill no)
			(layer "B.Fab")
		)
		(pad "1" smd custom
			(at 0 -0.4318 180)
			(size 0.127 0.127)
			(layers "B.Cu" "B.Mask" "B.Paste")
			(net "P3V3_STBY")
			(options
				(clearance outline)
				(anchor circle)
			)
			(primitives
				(gr_poly
					(pts
						(arc
							(start -0.2032 0.2794)
							(mid -0.239121 0.264521)
							(end -0.254 0.2286)
						)
						(arc
							(start -0.254 -0.2286)
							(mid -0.239121 -0.264521)
							(end -0.2032 -0.2794)
						)
						(arc
							(start 0.2032 -0.2794)
							(mid 0.239121 -0.264521)
							(end 0.254 -0.2286)
						)
						(arc
							(start 0.254 0.2286)
							(mid 0.239121 0.264521)
							(end 0.2032 0.2794)
						)
					)
					(width 0)
					(fill yes)
				)
			)
		)
		(pad "2" smd custom
			(at 0 0.4318 180)
			(size 0.127 0.127)
			(layers "B.Cu" "B.Mask" "B.Paste")
			(net "CHA_0_SA1")
			(options
				(clearance outline)
				(anchor circle)
			)
			(primitives
				(gr_poly
					(pts
						(arc
							(start -0.2032 0.2794)
							(mid -0.239121 0.264521)
							(end -0.254 0.2286)
						)
						(arc
							(start -0.254 -0.2286)
							(mid -0.239121 -0.264521)
							(end -0.2032 -0.2794)
						)
						(arc
							(start 0.2032 -0.2794)
							(mid 0.239121 -0.264521)
							(end 0.254 -0.2286)
						)
						(arc
							(start 0.254 0.2286)
							(mid 0.239121 0.264521)
							(end 0.2032 0.2794)
						)
					)
					(width 0)
					(fill yes)
				)
			)
		)
	)
	(footprint ""
		(layer "B.Cu")
		(at 170.0784 -12.879578 180)
		(property "Reference" "C365"
			(at 0 0 0)
			(layer "B.SilkS")
			(hide yes)
			(effects
				(font
					(size 1.27 1.27)
				)
				(justify mirror)
			)
		)
		(property "Value" "SC47U6D3V5MX-1-GP"
			(at 0 -4.9022 180)
			(unlocked yes)
			(layer "B.Fab")
			(hide yes)
			(effects
				(font
					(size 1.016 1.016)
					(thickness 0.1524)
				)
				(justify mirror)
			)
		)
		(property "Device Type" "C805H54"
			(at 0 -6.8072 180)
			(unlocked yes)
			(layer "B.Fab")
			(hide yes)
			(effects
				(font
					(size 1.016 1.016)
					(thickness 0.1524)
				)
				(justify mirror)
			)
		)
		(duplicate_pad_numbers_are_jumpers no)
		(fp_line
			(start -0.6096 0)
			(end 0.6096 0)
			(stroke
				(width 0.3048)
				(type default)
			)
			(layer "B.SilkS")
		)
		(fp_poly
			(pts
				(xy 0.9017 1.4351) (xy -0.9017 1.4351) (xy -0.9017 -1.4351) (xy 0.9017 -1.4351)
			)
			(stroke
				(width 0)
				(type default)
			)
			(fill no)
			(layer "B.CrtYd")
		)
		(fp_poly
			(pts
				(xy -0.9017 1.4351) (xy -0.9017 -1.4351) (xy 0.9017 -1.4351) (xy 0.9017 1.4351)
			)
			(stroke
				(width 0)
				(type default)
			)
			(fill no)
			(layer "B.Fab")
		)
		(pad "1" smd rect
			(at 0 -0.8382)
			(size 1.5494 0.9398)
			(layers "B.Cu" "B.Mask" "B.Paste")
			(net "PV_VDDR")
		)
		(pad "2" smd rect
			(at 0 0.8382)
			(size 1.5494 0.9398)
			(layers "B.Cu" "B.Mask" "B.Paste")
			(net "GND")
		)
	)
	(footprint ""
		(layer "B.Cu")
		(at 80.264 -32.8168 90)
		(property "Reference" "R365"
			(at 0 0 90)
			(layer "B.SilkS")
			(hide yes)
			(effects
				(font
					(size 1.27 1.27)
				)
				(justify mirror)
			)
		)
		(property "Value" "0R2J-2-GP"
			(at -0.064008 -3.993896 90)
			(unlocked yes)
			(layer "B.Fab")
			(hide yes)
			(effects
				(font
					(size 1.016 1.016)
					(thickness 0.1524)
				)
				(justify mirror)
			)
		)
		(property "Device Type" "R402H16"
			(at -0.064008 -5.517896 90)
			(unlocked yes)
			(layer "B.Fab")
			(hide yes)
			(effects
				(font
					(size 1.016 1.016)
					(thickness 0.1524)
				)
				(justify mirror)
			)
		)
		(duplicate_pad_numbers_are_jumpers no)
		(fp_rect
			(start 0.381 0.8382)
			(end -0.381 -0.8382)
			(stroke
				(width 0)
				(type default)
			)
			(fill no)
			(layer "B.CrtYd")
		)
		(fp_rect
			(start 0.381 0.8382)
			(end -0.381 -0.8382)
			(stroke
				(width 0)
				(type default)
			)
			(fill no)
			(layer "B.Fab")
		)
		(pad "1" smd custom
			(at 0 -0.4318 270)
			(size 0.127 0.127)
			(layers "B.Cu" "B.Mask" "B.Paste")
			(net "GBE_SMBALRT#")
			(options
				(clearance outline)
				(anchor circle)
			)
			(primitives
				(gr_poly
					(pts
						(arc
							(start -0.2032 0.2794)
							(mid -0.239121 0.264521)
							(end -0.254 0.2286)
						)
						(arc
							(start -0.254 -0.2286)
							(mid -0.239121 -0.264521)
							(end -0.2032 -0.2794)
						)
						(arc
							(start 0.2032 -0.2794)
							(mid 0.239121 -0.264521)
							(end 0.254 -0.2286)
						)
						(arc
							(start 0.254 0.2286)
							(mid 0.239121 0.264521)
							(end 0.2032 0.2794)
						)
					)
					(width 0)
					(fill yes)
				)
			)
		)
		(pad "2" smd custom
			(at 0 0.4318 270)
			(size 0.127 0.127)
			(layers "B.Cu" "B.Mask" "B.Paste")
			(net "GND")
			(options
				(clearance outline)
				(anchor circle)
			)
			(primitives
				(gr_poly
					(pts
						(arc
							(start -0.2032 0.2794)
							(mid -0.239121 0.264521)
							(end -0.254 0.2286)
						)
						(arc
							(start -0.254 -0.2286)
							(mid -0.239121 -0.264521)
							(end -0.2032 -0.2794)
						)
						(arc
							(start 0.2032 -0.2794)
							(mid 0.239121 -0.264521)
							(end 0.254 -0.2286)
						)
						(arc
							(start 0.254 0.2286)
							(mid 0.239121 0.264521)
							(end 0.2032 0.2794)
						)
					)
					(width 0)
					(fill yes)
				)
			)
		)
	)
	(footprint ""
		(layer "B.Cu")
		(at 69.215 -61.722)
		(property "Reference" "C80"
			(at 0 0 0)
			(layer "B.SilkS")
			(hide yes)
			(effects
				(font
					(size 1.27 1.27)
				)
				(justify mirror)
			)
		)
		(property "Value" "SCD1U25V2KX-2-GP"
			(at -1.8923 -1.2065 0)
			(unlocked yes)
			(layer "B.Fab")
			(hide yes)
			(effects
				(font
					(size 1.016 1.016)
					(thickness 0.1524)
				)
				(justify mirror)
			)
		)
		(property "Device Type" "C402H22"
			(at -1.8923 -2.7305 0)
			(unlocked yes)
			(layer "B.Fab")
			(hide yes)
			(effects
				(font
					(size 1.016 1.016)
					(thickness 0.1524)
				)
				(justify mirror)
			)
		)
		(duplicate_pad_numbers_are_jumpers no)
		(fp_rect
			(start 0.381 0.7366)
			(end -0.381 -0.7366)
			(stroke
				(width 0)
				(type default)
			)
			(fill no)
			(layer "B.CrtYd")
		)
		(fp_rect
			(start 0.381 0.7366)
			(end -0.381 -0.7366)
			(stroke
				(width 0)
				(type default)
			)
			(fill no)
			(layer "B.Fab")
		)
		(pad "1" smd custom
			(at 0 -0.4572 180)
			(size 0.1143 0.1143)
			(layers "B.Cu" "B.Mask" "B.Paste")
			(net "P12V_SENSE")
			(options
				(clearance outline)
				(anchor circle)
			)
			(primitives
				(gr_poly
					(pts
						(arc
							(start -0.254 0.1778)
							(mid -0.239121 0.213721)
							(end -0.2032 0.2286)
						)
						(arc
							(start 0.2032 0.2286)
							(mid 0.239121 0.213721)
							(end 0.254 0.1778)
						)
						(arc
							(start 0.254 -0.1778)
							(mid 0.239121 -0.213721)
							(end 0.2032 -0.2286)
						)
						(arc
							(start -0.2032 -0.2286)
							(mid -0.239121 -0.213721)
							(end -0.254 -0.1778)
						)
					)
					(width 0)
					(fill yes)
				)
			)
		)
		(pad "2" smd custom
			(at 0 0.4572 180)
			(size 0.1143 0.1143)
			(layers "B.Cu" "B.Mask" "B.Paste")
			(net "GND")
			(options
				(clearance outline)
				(anchor circle)
			)
			(primitives
				(gr_poly
					(pts
						(arc
							(start -0.254 0.1778)
							(mid -0.239121 0.213721)
							(end -0.2032 0.2286)
						)
						(arc
							(start 0.2032 0.2286)
							(mid 0.239121 0.213721)
							(end 0.254 0.1778)
						)
						(arc
							(start 0.254 -0.1778)
							(mid 0.239121 -0.213721)
							(end 0.2032 -0.2286)
						)
						(arc
							(start -0.2032 -0.2286)
							(mid -0.239121 -0.213721)
							(end -0.254 -0.1778)
						)
					)
					(width 0)
					(fill yes)
				)
			)
		)
	)
	(footprint ""
		(layer "B.Cu")
		(at 46.99 -42.164)
		(property "Reference" "C36"
			(at 0 0 0)
			(layer "B.SilkS")
			(hide yes)
			(effects
				(font
					(size 1.27 1.27)
				)
				(justify mirror)
			)
		)
		(property "Value" "SC10U6D3V3MX-GP"
			(at 0 -2.8194 0)
			(unlocked yes)
			(layer "B.Fab")
			(hide yes)
			(effects
				(font
					(size 1.016 1.016)
					(thickness 0.1524)
				)
				(justify mirror)
			)
		)
		(property "Device Type" "C603H38"
			(at 0 -4.3434 0)
			(unlocked yes)
			(layer "B.Fab")
			(hide yes)
			(effects
				(font
					(size 1.016 1.016)
					(thickness 0.1524)
				)
				(justify mirror)
			)
		)
		(duplicate_pad_numbers_are_jumpers no)
		(fp_line
			(start 0.4064 0)
			(end -0.4064 0)
			(stroke
				(width 0.2286)
				(type default)
			)
			(layer "B.SilkS")
		)
		(fp_rect
			(start 0.635 1.1811)
			(end -0.635 -1.1811)
			(stroke
				(width 0)
				(type default)
			)
			(fill no)
			(layer "B.CrtYd")
		)
		(fp_rect
			(start 0.635 1.1811)
			(end -0.635 -1.1811)
			(stroke
				(width 0)
				(type default)
			)
			(fill no)
			(layer "B.Fab")
		)
		(pad "1" smd custom
			(at 0 -0.6604 180)
			(size 0.19685 0.19685)
			(layers "B.Cu" "B.Mask" "B.Paste")
			(net "P1V5_CLK_VDD_CORE")
			(options
				(clearance outline)
				(anchor circle)
			)
			(primitives
				(gr_poly
					(pts
						(arc
							(start 0.508 0.2921)
							(mid 0.478242 0.363942)
							(end 0.4064 0.3937)
						)
						(arc
							(start -0.4064 0.3937)
							(mid -0.478242 0.363942)
							(end -0.508 0.2921)
						)
						(arc
							(start -0.508 -0.2921)
							(mid -0.478242 -0.363942)
							(end -0.4064 -0.3937)
						)
						(arc
							(start 0.4064 -0.3937)
							(mid 0.478242 -0.363942)
							(end 0.508 -0.2921)
						)
					)
					(width 0)
					(fill yes)
				)
			)
		)
		(pad "2" smd custom
			(at 0 0.6604 180)
			(size 0.19685 0.19685)
			(layers "B.Cu" "B.Mask" "B.Paste")
			(net "GND")
			(options
				(clearance outline)
				(anchor circle)
			)
			(primitives
				(gr_poly
					(pts
						(arc
							(start 0.508 0.2921)
							(mid 0.478242 0.363942)
							(end 0.4064 0.3937)
						)
						(arc
							(start -0.4064 0.3937)
							(mid -0.478242 0.363942)
							(end -0.508 0.2921)
						)
						(arc
							(start -0.508 -0.2921)
							(mid -0.478242 -0.363942)
							(end -0.4064 -0.3937)
						)
						(arc
							(start 0.4064 -0.3937)
							(mid 0.478242 -0.363942)
							(end 0.508 -0.2921)
						)
					)
					(width 0)
					(fill yes)
				)
			)
		)
	)
	(footprint ""
		(layer "B.Cu")
		(at 74.168 -45.085 90)
		(property "Reference" "R70"
			(at 0 0 90)
			(layer "B.SilkS")
			(hide yes)
			(effects
				(font
					(size 1.27 1.27)
				)
				(justify mirror)
			)
		)
		(property "Value" "4K7R2F-GP"
			(at -0.064008 -3.993896 90)
			(unlocked yes)
			(layer "B.Fab")
			(hide yes)
			(effects
				(font
					(size 1.016 1.016)
					(thickness 0.1524)
				)
				(justify mirror)
			)
		)
		(property "Device Type" "R402H16"
			(at -0.064008 -5.517896 90)
			(unlocked yes)
			(layer "B.Fab")
			(hide yes)
			(effects
				(font
					(size 1.016 1.016)
					(thickness 0.1524)
				)
				(justify mirror)
			)
		)
		(duplicate_pad_numbers_are_jumpers no)
		(fp_rect
			(start 0.381 0.8382)
			(end -0.381 -0.8382)
			(stroke
				(width 0)
				(type default)
			)
			(fill no)
			(layer "B.CrtYd")
		)
		(fp_rect
			(start 0.381 0.8382)
			(end -0.381 -0.8382)
			(stroke
				(width 0)
				(type default)
			)
			(fill no)
			(layer "B.Fab")
		)
		(pad "1" smd custom
			(at 0 -0.4318 270)
			(size 0.127 0.127)
			(layers "B.Cu" "B.Mask" "B.Paste")
			(net "P3V3")
			(options
				(clearance outline)
				(anchor circle)
			)
			(primitives
				(gr_poly
					(pts
						(arc
							(start -0.2032 0.2794)
							(mid -0.239121 0.264521)
							(end -0.254 0.2286)
						)
						(arc
							(start -0.254 -0.2286)
							(mid -0.239121 -0.264521)
							(end -0.2032 -0.2794)
						)
						(arc
							(start 0.2032 -0.2794)
							(mid 0.239121 -0.264521)
							(end 0.254 -0.2286)
						)
						(arc
							(start 0.254 0.2286)
							(mid 0.239121 0.264521)
							(end 0.2032 0.2794)
						)
					)
					(width 0)
					(fill yes)
				)
			)
		)
		(pad "2" smd custom
			(at 0 0.4318 270)
			(size 0.127 0.127)
			(layers "B.Cu" "B.Mask" "B.Paste")
			(net "SMBUS_HOST_ALRT#")
			(options
				(clearance outline)
				(anchor circle)
			)
			(primitives
				(gr_poly
					(pts
						(arc
							(start -0.2032 0.2794)
							(mid -0.239121 0.264521)
							(end -0.254 0.2286)
						)
						(arc
							(start -0.254 -0.2286)
							(mid -0.239121 -0.264521)
							(end -0.2032 -0.2794)
						)
						(arc
							(start 0.2032 -0.2794)
							(mid 0.239121 -0.264521)
							(end 0.254 -0.2286)
						)
						(arc
							(start 0.254 0.2286)
							(mid 0.239121 0.264521)
							(end 0.2032 0.2794)
						)
					)
					(width 0)
					(fill yes)
				)
			)
		)
	)
	(footprint ""
		(layer "B.Cu")
		(at 15.621 -68.7324)
		(property "Reference" "R505"
			(at 0 0 0)
			(layer "B.SilkS")
			(hide yes)
			(effects
				(font
					(size 1.27 1.27)
				)
				(justify mirror)
			)
		)
		(property "Value" "4K7R2F-GP"
			(at -1.7907 -1.1176 0)
			(unlocked yes)
			(layer "B.Fab")
			(hide yes)
			(effects
				(font
					(size 1.016 1.016)
					(thickness 0.1524)
				)
				(justify mirror)
			)
		)
		(property "Device Type" "R402H16"
			(at -1.7907 -2.6416 0)
			(unlocked yes)
			(layer "B.Fab")
			(hide yes)
			(effects
				(font
					(size 1.016 1.016)
					(thickness 0.1524)
				)
				(justify mirror)
			)
		)
		(duplicate_pad_numbers_are_jumpers no)
		(fp_rect
			(start 0.381 0.8382)
			(end -0.381 -0.8382)
			(stroke
				(width 0)
				(type default)
			)
			(fill no)
			(layer "B.CrtYd")
		)
		(fp_rect
			(start 0.381 0.8382)
			(end -0.381 -0.8382)
			(stroke
				(width 0)
				(type default)
			)
			(fill no)
			(layer "B.Fab")
		)
		(pad "1" smd custom
			(at 0 -0.4318 180)
			(size 0.127 0.127)
			(layers "B.Cu" "B.Mask" "B.Paste")
			(net "LED_NGFF_DAS")
			(options
				(clearance outline)
				(anchor circle)
			)
			(primitives
				(gr_poly
					(pts
						(arc
							(start -0.2032 0.2794)
							(mid -0.239121 0.264521)
							(end -0.254 0.2286)
						)
						(arc
							(start -0.254 -0.2286)
							(mid -0.239121 -0.264521)
							(end -0.2032 -0.2794)
						)
						(arc
							(start 0.2032 -0.2794)
							(mid 0.239121 -0.264521)
							(end 0.254 -0.2286)
						)
						(arc
							(start 0.254 0.2286)
							(mid 0.239121 0.264521)
							(end 0.2032 0.2794)
						)
					)
					(width 0)
					(fill yes)
				)
			)
		)
		(pad "2" smd custom
			(at 0 0.4318 180)
			(size 0.127 0.127)
			(layers "B.Cu" "B.Mask" "B.Paste")
			(net "GND")
			(options
				(clearance outline)
				(anchor circle)
			)
			(primitives
				(gr_poly
					(pts
						(arc
							(start -0.2032 0.2794)
							(mid -0.239121 0.264521)
							(end -0.254 0.2286)
						)
						(arc
							(start -0.254 -0.2286)
							(mid -0.239121 -0.264521)
							(end -0.2032 -0.2794)
						)
						(arc
							(start 0.2032 -0.2794)
							(mid 0.239121 -0.264521)
							(end 0.254 -0.2286)
						)
						(arc
							(start 0.254 0.2286)
							(mid 0.239121 0.264521)
							(end 0.2032 0.2794)
						)
					)
					(width 0)
					(fill yes)
				)
			)
		)
	)
	(footprint ""
		(layer "B.Cu")
		(at 33.4772 -12.7)
		(property "Reference" "C269"
			(at 0 0 0)
			(layer "B.SilkS")
			(hide yes)
			(effects
				(font
					(size 1.27 1.27)
				)
				(justify mirror)
			)
		)
		(property "Value" "SCD1U16V2KX-3GP"
			(at -1.1811 -2.7051 0)
			(unlocked yes)
			(layer "B.Fab")
			(hide yes)
			(effects
				(font
					(size 1.016 1.016)
					(thickness 0.1524)
				)
				(justify mirror)
			)
		)
		(property "Device Type" "C402H22"
			(at -1.1811 -4.2291 0)
			(unlocked yes)
			(layer "B.Fab")
			(hide yes)
			(effects
				(font
					(size 1.016 1.016)
					(thickness 0.1524)
				)
				(justify mirror)
			)
		)
		(duplicate_pad_numbers_are_jumpers no)
		(fp_rect
			(start 0.381 0.7366)
			(end -0.381 -0.7366)
			(stroke
				(width 0)
				(type default)
			)
			(fill no)
			(layer "B.CrtYd")
		)
		(fp_rect
			(start 0.381 0.7366)
			(end -0.381 -0.7366)
			(stroke
				(width 0)
				(type default)
			)
			(fill no)
			(layer "B.Fab")
		)
		(pad "1" smd custom
			(at 0 -0.4572 180)
			(size 0.1143 0.1143)
			(layers "B.Cu" "B.Mask" "B.Paste")
			(net "P2E_CPU_SAS_C_TX_DN7")
			(options
				(clearance outline)
				(anchor circle)
			)
			(primitives
				(gr_poly
					(pts
						(arc
							(start -0.254 0.1778)
							(mid -0.239121 0.213721)
							(end -0.2032 0.2286)
						)
						(arc
							(start 0.2032 0.2286)
							(mid 0.239121 0.213721)
							(end 0.254 0.1778)
						)
						(arc
							(start 0.254 -0.1778)
							(mid 0.239121 -0.213721)
							(end 0.2032 -0.2286)
						)
						(arc
							(start -0.2032 -0.2286)
							(mid -0.239121 -0.213721)
							(end -0.254 -0.1778)
						)
					)
					(width 0)
					(fill yes)
				)
			)
		)
		(pad "2" smd custom
			(at 0 0.4572 180)
			(size 0.1143 0.1143)
			(layers "B.Cu" "B.Mask" "B.Paste")
			(net "P2E_CPU_SAS_TX_DN7")
			(options
				(clearance outline)
				(anchor circle)
			)
			(primitives
				(gr_poly
					(pts
						(arc
							(start -0.254 0.1778)
							(mid -0.239121 0.213721)
							(end -0.2032 0.2286)
						)
						(arc
							(start 0.2032 0.2286)
							(mid 0.239121 0.213721)
							(end 0.254 0.1778)
						)
						(arc
							(start 0.254 -0.1778)
							(mid 0.239121 -0.213721)
							(end 0.2032 -0.2286)
						)
						(arc
							(start -0.2032 -0.2286)
							(mid -0.239121 -0.213721)
							(end -0.254 -0.1778)
						)
					)
					(width 0)
					(fill yes)
				)
			)
		)
	)
	(footprint ""
		(layer "B.Cu")
		(at 200.787 -25.654 -90)
		(property "Reference" "PC84"
			(at 0 0 90)
			(layer "B.SilkS")
			(hide yes)
			(effects
				(font
					(size 1.27 1.27)
				)
				(justify mirror)
			)
		)
		(property "Value" "SC22U25V5MX-GP"
			(at 0 -4.9022 270)
			(unlocked yes)
			(layer "B.Fab")
			(hide yes)
			(effects
				(font
					(size 1.016 1.016)
					(thickness 0.1524)
				)
				(justify mirror)
			)
		)
		(property "Device Type" "C805H58"
			(at 0 -6.8072 270)
			(unlocked yes)
			(layer "B.Fab")
			(hide yes)
			(effects
				(font
					(size 1.016 1.016)
					(thickness 0.1524)
				)
				(justify mirror)
			)
		)
		(duplicate_pad_numbers_are_jumpers no)
		(fp_line
			(start -0.6096 0)
			(end 0.6096 0)
			(stroke
				(width 0.3048)
				(type default)
			)
			(layer "B.SilkS")
		)
		(fp_poly
			(pts
				(xy 0.9017 1.4351) (xy -0.9017 1.4351) (xy -0.9017 -1.4351) (xy 0.9017 -1.4351)
			)
			(stroke
				(width 0)
				(type default)
			)
			(fill no)
			(layer "B.CrtYd")
		)
		(fp_poly
			(pts
				(xy -0.9017 1.4351) (xy -0.9017 -1.4351) (xy 0.9017 -1.4351) (xy 0.9017 1.4351)
			)
			(stroke
				(width 0)
				(type default)
			)
			(fill no)
			(layer "B.Fab")
		)
		(pad "1" smd rect
			(at 0 -0.8382 90)
			(size 1.5494 0.9398)
			(layers "B.Cu" "B.Mask" "B.Paste")
			(net "PVDDR_VIN")
		)
		(pad "2" smd rect
			(at 0 0.8382 90)
			(size 1.5494 0.9398)
			(layers "B.Cu" "B.Mask" "B.Paste")
			(net "GND")
		)
	)
	(footprint ""
		(layer "B.Cu")
		(at 72.3138 -33.655 -90)
		(property "Reference" "R329"
			(at 0 0 90)
			(layer "B.SilkS")
			(hide yes)
			(effects
				(font
					(size 1.27 1.27)
				)
				(justify mirror)
			)
		)
		(property "Value" "0R2J-2-GP"
			(at -0.064008 -3.993896 270)
			(unlocked yes)
			(layer "B.Fab")
			(hide yes)
			(effects
				(font
					(size 1.016 1.016)
					(thickness 0.1524)
				)
				(justify mirror)
			)
		)
		(property "Device Type" "R402H16"
			(at -0.064008 -5.517896 270)
			(unlocked yes)
			(layer "B.Fab")
			(hide yes)
			(effects
				(font
					(size 1.016 1.016)
					(thickness 0.1524)
				)
				(justify mirror)
			)
		)
		(duplicate_pad_numbers_are_jumpers no)
		(fp_rect
			(start 0.381 0.8382)
			(end -0.381 -0.8382)
			(stroke
				(width 0)
				(type default)
			)
			(fill no)
			(layer "B.CrtYd")
		)
		(fp_rect
			(start 0.381 0.8382)
			(end -0.381 -0.8382)
			(stroke
				(width 0)
				(type default)
			)
			(fill no)
			(layer "B.Fab")
		)
		(pad "1" smd custom
			(at 0 -0.4318 90)
			(size 0.127 0.127)
			(layers "B.Cu" "B.Mask" "B.Paste")
			(net "SRTCRST_R#")
			(options
				(clearance outline)
				(anchor circle)
			)
			(primitives
				(gr_poly
					(pts
						(arc
							(start -0.2032 0.2794)
							(mid -0.239121 0.264521)
							(end -0.254 0.2286)
						)
						(arc
							(start -0.254 -0.2286)
							(mid -0.239121 -0.264521)
							(end -0.2032 -0.2794)
						)
						(arc
							(start 0.2032 -0.2794)
							(mid 0.239121 -0.264521)
							(end 0.254 -0.2286)
						)
						(arc
							(start 0.254 0.2286)
							(mid 0.239121 0.264521)
							(end 0.2032 0.2794)
						)
					)
					(width 0)
					(fill yes)
				)
			)
		)
		(pad "2" smd custom
			(at 0 0.4318 90)
			(size 0.127 0.127)
			(layers "B.Cu" "B.Mask" "B.Paste")
			(net "SRTCRST#")
			(options
				(clearance outline)
				(anchor circle)
			)
			(primitives
				(gr_poly
					(pts
						(arc
							(start -0.2032 0.2794)
							(mid -0.239121 0.264521)
							(end -0.254 0.2286)
						)
						(arc
							(start -0.254 -0.2286)
							(mid -0.239121 -0.264521)
							(end -0.2032 -0.2794)
						)
						(arc
							(start 0.2032 -0.2794)
							(mid 0.239121 -0.264521)
							(end 0.254 -0.2286)
						)
						(arc
							(start 0.254 0.2286)
							(mid 0.239121 0.264521)
							(end 0.2032 0.2794)
						)
					)
					(width 0)
					(fill yes)
				)
			)
		)
	)
	(footprint ""
		(layer "B.Cu")
		(at 197.993 -41.91 -90)
		(property "Reference" "R154"
			(at 0 0 90)
			(layer "B.SilkS")
			(hide yes)
			(effects
				(font
					(size 1.27 1.27)
				)
				(justify mirror)
			)
		)
		(property "Value" "300R2F-GP"
			(at -0.064008 -3.993896 270)
			(unlocked yes)
			(layer "B.Fab")
			(hide yes)
			(effects
				(font
					(size 1.016 1.016)
					(thickness 0.1524)
				)
				(justify mirror)
			)
		)
		(property "Device Type" "R402H16"
			(at -0.064008 -5.517896 270)
			(unlocked yes)
			(layer "B.Fab")
			(hide yes)
			(effects
				(font
					(size 1.016 1.016)
					(thickness 0.1524)
				)
				(justify mirror)
			)
		)
		(duplicate_pad_numbers_are_jumpers no)
		(fp_rect
			(start 0.381 0.8382)
			(end -0.381 -0.8382)
			(stroke
				(width 0)
				(type default)
			)
			(fill no)
			(layer "B.CrtYd")
		)
		(fp_rect
			(start 0.381 0.8382)
			(end -0.381 -0.8382)
			(stroke
				(width 0)
				(type default)
			)
			(fill no)
			(layer "B.Fab")
		)
		(pad "1" smd custom
			(at 0 -0.4318 90)
			(size 0.127 0.127)
			(layers "B.Cu" "B.Mask" "B.Paste")
			(net "PORT80_R_BIT5")
			(options
				(clearance outline)
				(anchor circle)
			)
			(primitives
				(gr_poly
					(pts
						(arc
							(start -0.2032 0.2794)
							(mid -0.239121 0.264521)
							(end -0.254 0.2286)
						)
						(arc
							(start -0.254 -0.2286)
							(mid -0.239121 -0.264521)
							(end -0.2032 -0.2794)
						)
						(arc
							(start 0.2032 -0.2794)
							(mid 0.239121 -0.264521)
							(end 0.254 -0.2286)
						)
						(arc
							(start 0.254 0.2286)
							(mid 0.239121 0.264521)
							(end 0.2032 0.2794)
						)
					)
					(width 0)
					(fill yes)
				)
			)
		)
		(pad "2" smd custom
			(at 0 0.4318 90)
			(size 0.127 0.127)
			(layers "B.Cu" "B.Mask" "B.Paste")
			(net "P3V3_STBY")
			(options
				(clearance outline)
				(anchor circle)
			)
			(primitives
				(gr_poly
					(pts
						(arc
							(start -0.2032 0.2794)
							(mid -0.239121 0.264521)
							(end -0.254 0.2286)
						)
						(arc
							(start -0.254 -0.2286)
							(mid -0.239121 -0.264521)
							(end -0.2032 -0.2794)
						)
						(arc
							(start 0.2032 -0.2794)
							(mid 0.239121 -0.264521)
							(end 0.254 -0.2286)
						)
						(arc
							(start 0.254 0.2286)
							(mid 0.239121 0.264521)
							(end 0.2032 0.2794)
						)
					)
					(width 0)
					(fill yes)
				)
			)
		)
	)
	(footprint ""
		(layer "B.Cu")
		(at 151.384 -59.309)
		(property "Reference" "C100"
			(at 0 0 0)
			(layer "B.SilkS")
			(hide yes)
			(effects
				(font
					(size 1.27 1.27)
				)
				(justify mirror)
			)
		)
		(property "Value" "SC10U6D3V3MX-GP"
			(at 0.0254 -2.0193 0)
			(unlocked yes)
			(layer "B.Fab")
			(hide yes)
			(effects
				(font
					(size 1.016 1.016)
					(thickness 0.1524)
				)
				(justify mirror)
			)
		)
		(property "Device Type" "C603H38"
			(at 0.0254 -3.5433 0)
			(unlocked yes)
			(layer "B.Fab")
			(hide yes)
			(effects
				(font
					(size 1.016 1.016)
					(thickness 0.1524)
				)
				(justify mirror)
			)
		)
		(duplicate_pad_numbers_are_jumpers no)
		(fp_line
			(start 0.4064 0)
			(end -0.4064 0)
			(stroke
				(width 0.2286)
				(type default)
			)
			(layer "B.SilkS")
		)
		(fp_rect
			(start 0.635 1.1811)
			(end -0.635 -1.1811)
			(stroke
				(width 0)
				(type default)
			)
			(fill no)
			(layer "B.CrtYd")
		)
		(fp_rect
			(start 0.635 1.1811)
			(end -0.635 -1.1811)
			(stroke
				(width 0)
				(type default)
			)
			(fill no)
			(layer "B.Fab")
		)
		(pad "1" smd custom
			(at 0 -0.6604 180)
			(size 0.19685 0.19685)
			(layers "B.Cu" "B.Mask" "B.Paste")
			(net "PV_VDDR")
			(options
				(clearance outline)
				(anchor circle)
			)
			(primitives
				(gr_poly
					(pts
						(arc
							(start 0.508 0.2921)
							(mid 0.478242 0.363942)
							(end 0.4064 0.3937)
						)
						(arc
							(start -0.4064 0.3937)
							(mid -0.478242 0.363942)
							(end -0.508 0.2921)
						)
						(arc
							(start -0.508 -0.2921)
							(mid -0.478242 -0.363942)
							(end -0.4064 -0.3937)
						)
						(arc
							(start 0.4064 -0.3937)
							(mid 0.478242 -0.363942)
							(end 0.508 -0.2921)
						)
					)
					(width 0)
					(fill yes)
				)
			)
		)
		(pad "2" smd custom
			(at 0 0.6604 180)
			(size 0.19685 0.19685)
			(layers "B.Cu" "B.Mask" "B.Paste")
			(net "GND")
			(options
				(clearance outline)
				(anchor circle)
			)
			(primitives
				(gr_poly
					(pts
						(arc
							(start 0.508 0.2921)
							(mid 0.478242 0.363942)
							(end 0.4064 0.3937)
						)
						(arc
							(start -0.4064 0.3937)
							(mid -0.478242 0.363942)
							(end -0.508 0.2921)
						)
						(arc
							(start -0.508 -0.2921)
							(mid -0.478242 -0.363942)
							(end -0.4064 -0.3937)
						)
						(arc
							(start 0.4064 -0.3937)
							(mid 0.478242 -0.363942)
							(end 0.508 -0.2921)
						)
					)
					(width 0)
					(fill yes)
				)
			)
		)
	)
	(footprint ""
		(layer "B.Cu")
		(at 82.423 -24.511)
		(property "Reference" "R304"
			(at 0 0 0)
			(layer "B.SilkS")
			(hide yes)
			(effects
				(font
					(size 1.27 1.27)
				)
				(justify mirror)
			)
		)
		(property "Value" "0R2J-2-GP"
			(at -0.064008 -3.993896 0)
			(unlocked yes)
			(layer "B.Fab")
			(hide yes)
			(effects
				(font
					(size 1.016 1.016)
					(thickness 0.1524)
				)
				(justify mirror)
			)
		)
		(property "Device Type" "R402H16"
			(at -0.064008 -5.517896 0)
			(unlocked yes)
			(layer "B.Fab")
			(hide yes)
			(effects
				(font
					(size 1.016 1.016)
					(thickness 0.1524)
				)
				(justify mirror)
			)
		)
		(duplicate_pad_numbers_are_jumpers no)
		(fp_rect
			(start 0.381 0.8382)
			(end -0.381 -0.8382)
			(stroke
				(width 0)
				(type default)
			)
			(fill no)
			(layer "B.CrtYd")
		)
		(fp_rect
			(start 0.381 0.8382)
			(end -0.381 -0.8382)
			(stroke
				(width 0)
				(type default)
			)
			(fill no)
			(layer "B.Fab")
		)
		(pad "1" smd custom
			(at 0 -0.4318 180)
			(size 0.127 0.127)
			(layers "B.Cu" "B.Mask" "B.Paste")
			(net "CPU_UART_RXD_R")
			(options
				(clearance outline)
				(anchor circle)
			)
			(primitives
				(gr_poly
					(pts
						(arc
							(start -0.2032 0.2794)
							(mid -0.239121 0.264521)
							(end -0.254 0.2286)
						)
						(arc
							(start -0.254 -0.2286)
							(mid -0.239121 -0.264521)
							(end -0.2032 -0.2794)
						)
						(arc
							(start 0.2032 -0.2794)
							(mid 0.239121 -0.264521)
							(end 0.254 -0.2286)
						)
						(arc
							(start 0.254 0.2286)
							(mid 0.239121 0.264521)
							(end 0.2032 0.2794)
						)
					)
					(width 0)
					(fill yes)
				)
			)
		)
		(pad "2" smd custom
			(at 0 0.4318 180)
			(size 0.127 0.127)
			(layers "B.Cu" "B.Mask" "B.Paste")
			(net "CPU_RXD")
			(options
				(clearance outline)
				(anchor circle)
			)
			(primitives
				(gr_poly
					(pts
						(arc
							(start -0.2032 0.2794)
							(mid -0.239121 0.264521)
							(end -0.254 0.2286)
						)
						(arc
							(start -0.254 -0.2286)
							(mid -0.239121 -0.264521)
							(end -0.2032 -0.2794)
						)
						(arc
							(start 0.2032 -0.2794)
							(mid 0.239121 -0.264521)
							(end 0.254 -0.2286)
						)
						(arc
							(start 0.254 0.2286)
							(mid 0.239121 0.264521)
							(end 0.2032 0.2794)
						)
					)
					(width 0)
					(fill yes)
				)
			)
		)
	)
	(footprint ""
		(layer "B.Cu")
		(at 74.041 -31.75 90)
		(property "Reference" "R119"
			(at 0 0 90)
			(layer "B.SilkS")
			(hide yes)
			(effects
				(font
					(size 1.27 1.27)
				)
				(justify mirror)
			)
		)
		(property "Value" "10KR2F-2-GP"
			(at -0.064008 -3.993896 90)
			(unlocked yes)
			(layer "B.Fab")
			(hide yes)
			(effects
				(font
					(size 1.016 1.016)
					(thickness 0.1524)
				)
				(justify mirror)
			)
		)
		(property "Device Type" "R402H16"
			(at -0.064008 -5.517896 90)
			(unlocked yes)
			(layer "B.Fab")
			(hide yes)
			(effects
				(font
					(size 1.016 1.016)
					(thickness 0.1524)
				)
				(justify mirror)
			)
		)
		(duplicate_pad_numbers_are_jumpers no)
		(fp_rect
			(start 0.381 0.8382)
			(end -0.381 -0.8382)
			(stroke
				(width 0)
				(type default)
			)
			(fill no)
			(layer "B.CrtYd")
		)
		(fp_rect
			(start 0.381 0.8382)
			(end -0.381 -0.8382)
			(stroke
				(width 0)
				(type default)
			)
			(fill no)
			(layer "B.Fab")
		)
		(pad "1" smd custom
			(at 0 -0.4318 270)
			(size 0.127 0.127)
			(layers "B.Cu" "B.Mask" "B.Paste")
			(net "P3V3_CPU")
			(options
				(clearance outline)
				(anchor circle)
			)
			(primitives
				(gr_poly
					(pts
						(arc
							(start -0.2032 0.2794)
							(mid -0.239121 0.264521)
							(end -0.254 0.2286)
						)
						(arc
							(start -0.254 -0.2286)
							(mid -0.239121 -0.264521)
							(end -0.2032 -0.2794)
						)
						(arc
							(start 0.2032 -0.2794)
							(mid 0.239121 -0.264521)
							(end 0.254 -0.2286)
						)
						(arc
							(start 0.254 0.2286)
							(mid 0.239121 0.264521)
							(end 0.2032 0.2794)
						)
					)
					(width 0)
					(fill yes)
				)
			)
		)
		(pad "2" smd custom
			(at 0 0.4318 270)
			(size 0.127 0.127)
			(layers "B.Cu" "B.Mask" "B.Paste")
			(net "GBE_MDIO_DATA0")
			(options
				(clearance outline)
				(anchor circle)
			)
			(primitives
				(gr_poly
					(pts
						(arc
							(start -0.2032 0.2794)
							(mid -0.239121 0.264521)
							(end -0.254 0.2286)
						)
						(arc
							(start -0.254 -0.2286)
							(mid -0.239121 -0.264521)
							(end -0.2032 -0.2794)
						)
						(arc
							(start 0.2032 -0.2794)
							(mid 0.239121 -0.264521)
							(end 0.254 -0.2286)
						)
						(arc
							(start 0.254 0.2286)
							(mid 0.239121 0.264521)
							(end 0.2032 0.2794)
						)
					)
					(width 0)
					(fill yes)
				)
			)
		)
	)
	(footprint ""
		(layer "B.Cu")
		(at 52.6796 -23.5712 180)
		(property "Reference" "R454"
			(at 0 0 0)
			(layer "B.SilkS")
			(hide yes)
			(effects
				(font
					(size 1.27 1.27)
				)
				(justify mirror)
			)
		)
		(property "Value" "432R2F-GP"
			(at -1.7907 -1.1176 180)
			(unlocked yes)
			(layer "B.Fab")
			(hide yes)
			(effects
				(font
					(size 1.016 1.016)
					(thickness 0.1524)
				)
				(justify mirror)
			)
		)
		(property "Device Type" "R402H16"
			(at -1.7907 -2.6416 180)
			(unlocked yes)
			(layer "B.Fab")
			(hide yes)
			(effects
				(font
					(size 1.016 1.016)
					(thickness 0.1524)
				)
				(justify mirror)
			)
		)
		(duplicate_pad_numbers_are_jumpers no)
		(fp_rect
			(start 0.381 0.8382)
			(end -0.381 -0.8382)
			(stroke
				(width 0)
				(type default)
			)
			(fill no)
			(layer "B.CrtYd")
		)
		(fp_rect
			(start 0.381 0.8382)
			(end -0.381 -0.8382)
			(stroke
				(width 0)
				(type default)
			)
			(fill no)
			(layer "B.Fab")
		)
		(pad "1" smd custom
			(at 0 -0.4318)
			(size 0.127 0.127)
			(layers "B.Cu" "B.Mask" "B.Paste")
			(net "CLKBUFF_IREF")
			(options
				(clearance outline)
				(anchor circle)
			)
			(primitives
				(gr_poly
					(pts
						(arc
							(start -0.2032 0.2794)
							(mid -0.239121 0.264521)
							(end -0.254 0.2286)
						)
						(arc
							(start -0.254 -0.2286)
							(mid -0.239121 -0.264521)
							(end -0.2032 -0.2794)
						)
						(arc
							(start 0.2032 -0.2794)
							(mid 0.239121 -0.264521)
							(end 0.254 -0.2286)
						)
						(arc
							(start 0.254 0.2286)
							(mid 0.239121 0.264521)
							(end 0.2032 0.2794)
						)
					)
					(width 0)
					(fill yes)
				)
			)
		)
		(pad "2" smd custom
			(at 0 0.4318)
			(size 0.127 0.127)
			(layers "B.Cu" "B.Mask" "B.Paste")
			(net "GND")
			(options
				(clearance outline)
				(anchor circle)
			)
			(primitives
				(gr_poly
					(pts
						(arc
							(start -0.2032 0.2794)
							(mid -0.239121 0.264521)
							(end -0.254 0.2286)
						)
						(arc
							(start -0.254 -0.2286)
							(mid -0.239121 -0.264521)
							(end -0.2032 -0.2794)
						)
						(arc
							(start 0.2032 -0.2794)
							(mid 0.239121 -0.264521)
							(end 0.254 -0.2286)
						)
						(arc
							(start 0.254 0.2286)
							(mid 0.239121 0.264521)
							(end 0.2032 0.2794)
						)
					)
					(width 0)
					(fill yes)
				)
			)
		)
	)
	(footprint ""
		(layer "B.Cu")
		(at 137.922 -45.466 90)
		(property "Reference" "C164"
			(at 0 0 90)
			(layer "B.SilkS")
			(hide yes)
			(effects
				(font
					(size 1.27 1.27)
				)
				(justify mirror)
			)
		)
		(property "Value" "SCD1U10V2KX-5GP"
			(at -1.1811 -2.7051 90)
			(unlocked yes)
			(layer "B.Fab")
			(hide yes)
			(effects
				(font
					(size 1.016 1.016)
					(thickness 0.1524)
				)
				(justify mirror)
			)
		)
		(property "Device Type" "C402H22"
			(at -1.1811 -4.2291 90)
			(unlocked yes)
			(layer "B.Fab")
			(hide yes)
			(effects
				(font
					(size 1.016 1.016)
					(thickness 0.1524)
				)
				(justify mirror)
			)
		)
		(duplicate_pad_numbers_are_jumpers no)
		(fp_rect
			(start 0.381 0.7366)
			(end -0.381 -0.7366)
			(stroke
				(width 0)
				(type default)
			)
			(fill no)
			(layer "B.CrtYd")
		)
		(fp_rect
			(start 0.381 0.7366)
			(end -0.381 -0.7366)
			(stroke
				(width 0)
				(type default)
			)
			(fill no)
			(layer "B.Fab")
		)
		(pad "1" smd custom
			(at 0 -0.4572 270)
			(size 0.1143 0.1143)
			(layers "B.Cu" "B.Mask" "B.Paste")
			(net "P1V2_FPGA_D")
			(options
				(clearance outline)
				(anchor circle)
			)
			(primitives
				(gr_poly
					(pts
						(arc
							(start -0.254 0.1778)
							(mid -0.239121 0.213721)
							(end -0.2032 0.2286)
						)
						(arc
							(start 0.2032 0.2286)
							(mid 0.239121 0.213721)
							(end 0.254 0.1778)
						)
						(arc
							(start 0.254 -0.1778)
							(mid 0.239121 -0.213721)
							(end 0.2032 -0.2286)
						)
						(arc
							(start -0.2032 -0.2286)
							(mid -0.239121 -0.213721)
							(end -0.254 -0.1778)
						)
					)
					(width 0)
					(fill yes)
				)
			)
		)
		(pad "2" smd custom
			(at 0 0.4572 270)
			(size 0.1143 0.1143)
			(layers "B.Cu" "B.Mask" "B.Paste")
			(net "GND")
			(options
				(clearance outline)
				(anchor circle)
			)
			(primitives
				(gr_poly
					(pts
						(arc
							(start -0.254 0.1778)
							(mid -0.239121 0.213721)
							(end -0.2032 0.2286)
						)
						(arc
							(start 0.2032 0.2286)
							(mid 0.239121 0.213721)
							(end 0.254 0.1778)
						)
						(arc
							(start 0.254 -0.1778)
							(mid 0.239121 -0.213721)
							(end 0.2032 -0.2286)
						)
						(arc
							(start -0.2032 -0.2286)
							(mid -0.239121 -0.213721)
							(end -0.254 -0.1778)
						)
					)
					(width 0)
					(fill yes)
				)
			)
		)
	)
	(footprint ""
		(layer "B.Cu")
		(at 103.251 -34.052002 90)
		(property "Reference" "C214"
			(at 0 0 90)
			(layer "B.SilkS")
			(hide yes)
			(effects
				(font
					(size 1.27 1.27)
				)
				(justify mirror)
			)
		)
		(property "Value" "SC2D2U10V2KX-GP"
			(at -1.1811 -2.7051 90)
			(unlocked yes)
			(layer "B.Fab")
			(hide yes)
			(effects
				(font
					(size 1.016 1.016)
					(thickness 0.1524)
				)
				(justify mirror)
			)
		)
		(property "Device Type" "C402H22"
			(at -1.1811 -4.2291 90)
			(unlocked yes)
			(layer "B.Fab")
			(hide yes)
			(effects
				(font
					(size 1.016 1.016)
					(thickness 0.1524)
				)
				(justify mirror)
			)
		)
		(duplicate_pad_numbers_are_jumpers no)
		(fp_rect
			(start 0.381 0.7366)
			(end -0.381 -0.7366)
			(stroke
				(width 0)
				(type default)
			)
			(fill no)
			(layer "B.CrtYd")
		)
		(fp_rect
			(start 0.381 0.7366)
			(end -0.381 -0.7366)
			(stroke
				(width 0)
				(type default)
			)
			(fill no)
			(layer "B.Fab")
		)
		(pad "1" smd custom
			(at 0 -0.4572 270)
			(size 0.1143 0.1143)
			(layers "B.Cu" "B.Mask" "B.Paste")
			(net "P1V0")
			(options
				(clearance outline)
				(anchor circle)
			)
			(primitives
				(gr_poly
					(pts
						(arc
							(start -0.254 0.1778)
							(mid -0.239121 0.213721)
							(end -0.2032 0.2286)
						)
						(arc
							(start 0.2032 0.2286)
							(mid 0.239121 0.213721)
							(end 0.254 0.1778)
						)
						(arc
							(start 0.254 -0.1778)
							(mid 0.239121 -0.213721)
							(end 0.2032 -0.2286)
						)
						(arc
							(start -0.2032 -0.2286)
							(mid -0.239121 -0.213721)
							(end -0.254 -0.1778)
						)
					)
					(width 0)
					(fill yes)
				)
			)
		)
		(pad "2" smd custom
			(at 0 0.4572 270)
			(size 0.1143 0.1143)
			(layers "B.Cu" "B.Mask" "B.Paste")
			(net "GND")
			(options
				(clearance outline)
				(anchor circle)
			)
			(primitives
				(gr_poly
					(pts
						(arc
							(start -0.254 0.1778)
							(mid -0.239121 0.213721)
							(end -0.2032 0.2286)
						)
						(arc
							(start 0.2032 0.2286)
							(mid 0.239121 0.213721)
							(end 0.254 0.1778)
						)
						(arc
							(start 0.254 -0.1778)
							(mid 0.239121 -0.213721)
							(end 0.2032 -0.2286)
						)
						(arc
							(start -0.2032 -0.2286)
							(mid -0.239121 -0.213721)
							(end -0.254 -0.1778)
						)
					)
					(width 0)
					(fill yes)
				)
			)
		)
	)
	(footprint ""
		(layer "B.Cu")
		(at 17.653 -56.388 -90)
		(property "Reference" "PC2"
			(at 0 0 90)
			(layer "B.SilkS")
			(hide yes)
			(effects
				(font
					(size 1.27 1.27)
				)
				(justify mirror)
			)
		)
		(property "Value" "SC470P50V2KX-3GP"
			(at -1.8923 -1.2065 270)
			(unlocked yes)
			(layer "B.Fab")
			(hide yes)
			(effects
				(font
					(size 1.016 1.016)
					(thickness 0.1524)
				)
				(justify mirror)
			)
		)
		(property "Device Type" "C402H22"
			(at -1.8923 -2.7305 270)
			(unlocked yes)
			(layer "B.Fab")
			(hide yes)
			(effects
				(font
					(size 1.016 1.016)
					(thickness 0.1524)
				)
				(justify mirror)
			)
		)
		(duplicate_pad_numbers_are_jumpers no)
		(fp_rect
			(start 0.381 0.7366)
			(end -0.381 -0.7366)
			(stroke
				(width 0)
				(type default)
			)
			(fill no)
			(layer "B.CrtYd")
		)
		(fp_rect
			(start 0.381 0.7366)
			(end -0.381 -0.7366)
			(stroke
				(width 0)
				(type default)
			)
			(fill no)
			(layer "B.Fab")
		)
		(pad "1" smd custom
			(at 0 -0.4572 90)
			(size 0.1143 0.1143)
			(layers "B.Cu" "B.Mask" "B.Paste")
			(net "VR_PVNN_FB_RC1")
			(options
				(clearance outline)
				(anchor circle)
			)
			(primitives
				(gr_poly
					(pts
						(arc
							(start -0.254 0.1778)
							(mid -0.239121 0.213721)
							(end -0.2032 0.2286)
						)
						(arc
							(start 0.2032 0.2286)
							(mid 0.239121 0.213721)
							(end 0.254 0.1778)
						)
						(arc
							(start 0.254 -0.1778)
							(mid 0.239121 -0.213721)
							(end 0.2032 -0.2286)
						)
						(arc
							(start -0.2032 -0.2286)
							(mid -0.239121 -0.213721)
							(end -0.254 -0.1778)
						)
					)
					(width 0)
					(fill yes)
				)
			)
		)
		(pad "2" smd custom
			(at 0 0.4572 90)
			(size 0.1143 0.1143)
			(layers "B.Cu" "B.Mask" "B.Paste")
			(net "VR_PVNN_VSEN_R")
			(options
				(clearance outline)
				(anchor circle)
			)
			(primitives
				(gr_poly
					(pts
						(arc
							(start -0.254 0.1778)
							(mid -0.239121 0.213721)
							(end -0.2032 0.2286)
						)
						(arc
							(start 0.2032 0.2286)
							(mid 0.239121 0.213721)
							(end 0.254 0.1778)
						)
						(arc
							(start 0.254 -0.1778)
							(mid 0.239121 -0.213721)
							(end 0.2032 -0.2286)
						)
						(arc
							(start -0.2032 -0.2286)
							(mid -0.239121 -0.213721)
							(end -0.254 -0.1778)
						)
					)
					(width 0)
					(fill yes)
				)
			)
		)
	)
	(footprint ""
		(layer "B.Cu")
		(at 90.2081 -34.2138 90)
		(property "Reference" "C211"
			(at 0 0 90)
			(layer "B.SilkS")
			(hide yes)
			(effects
				(font
					(size 1.27 1.27)
				)
				(justify mirror)
			)
		)
		(property "Value" "SC1U10V2KX-1GP"
			(at -1.1811 -2.7051 90)
			(unlocked yes)
			(layer "B.Fab")
			(hide yes)
			(effects
				(font
					(size 1.016 1.016)
					(thickness 0.1524)
				)
				(justify mirror)
			)
		)
		(property "Device Type" "C402H22"
			(at -1.1811 -4.2291 90)
			(unlocked yes)
			(layer "B.Fab")
			(hide yes)
			(effects
				(font
					(size 1.016 1.016)
					(thickness 0.1524)
				)
				(justify mirror)
			)
		)
		(duplicate_pad_numbers_are_jumpers no)
		(fp_rect
			(start 0.381 0.7366)
			(end -0.381 -0.7366)
			(stroke
				(width 0)
				(type default)
			)
			(fill no)
			(layer "B.CrtYd")
		)
		(fp_rect
			(start 0.381 0.7366)
			(end -0.381 -0.7366)
			(stroke
				(width 0)
				(type default)
			)
			(fill no)
			(layer "B.Fab")
		)
		(pad "1" smd custom
			(at 0 -0.4572 270)
			(size 0.1143 0.1143)
			(layers "B.Cu" "B.Mask" "B.Paste")
			(net "P1V0")
			(options
				(clearance outline)
				(anchor circle)
			)
			(primitives
				(gr_poly
					(pts
						(arc
							(start -0.254 0.1778)
							(mid -0.239121 0.213721)
							(end -0.2032 0.2286)
						)
						(arc
							(start 0.2032 0.2286)
							(mid 0.239121 0.213721)
							(end 0.254 0.1778)
						)
						(arc
							(start 0.254 -0.1778)
							(mid 0.239121 -0.213721)
							(end 0.2032 -0.2286)
						)
						(arc
							(start -0.2032 -0.2286)
							(mid -0.239121 -0.213721)
							(end -0.254 -0.1778)
						)
					)
					(width 0)
					(fill yes)
				)
			)
		)
		(pad "2" smd custom
			(at 0 0.4572 270)
			(size 0.1143 0.1143)
			(layers "B.Cu" "B.Mask" "B.Paste")
			(net "GND")
			(options
				(clearance outline)
				(anchor circle)
			)
			(primitives
				(gr_poly
					(pts
						(arc
							(start -0.254 0.1778)
							(mid -0.239121 0.213721)
							(end -0.2032 0.2286)
						)
						(arc
							(start 0.2032 0.2286)
							(mid 0.239121 0.213721)
							(end 0.254 0.1778)
						)
						(arc
							(start 0.254 -0.1778)
							(mid 0.239121 -0.213721)
							(end 0.2032 -0.2286)
						)
						(arc
							(start -0.2032 -0.2286)
							(mid -0.239121 -0.213721)
							(end -0.254 -0.1778)
						)
					)
					(width 0)
					(fill yes)
				)
			)
		)
	)
	(footprint ""
		(layer "B.Cu")
		(at 99.949 -21.9202)
		(property "Reference" "R380"
			(at 0 0 0)
			(layer "B.SilkS")
			(hide yes)
			(effects
				(font
					(size 1.27 1.27)
				)
				(justify mirror)
			)
		)
		(property "Value" "23D7R2F-GP"
			(at -0.064008 -3.993896 0)
			(unlocked yes)
			(layer "B.Fab")
			(hide yes)
			(effects
				(font
					(size 1.016 1.016)
					(thickness 0.1524)
				)
				(justify mirror)
			)
		)
		(property "Device Type" "R402H16"
			(at -0.064008 -5.517896 0)
			(unlocked yes)
			(layer "B.Fab")
			(hide yes)
			(effects
				(font
					(size 1.016 1.016)
					(thickness 0.1524)
				)
				(justify mirror)
			)
		)
		(duplicate_pad_numbers_are_jumpers no)
		(fp_rect
			(start 0.381 0.8382)
			(end -0.381 -0.8382)
			(stroke
				(width 0)
				(type default)
			)
			(fill no)
			(layer "B.CrtYd")
		)
		(fp_rect
			(start 0.381 0.8382)
			(end -0.381 -0.8382)
			(stroke
				(width 0)
				(type default)
			)
			(fill no)
			(layer "B.Fab")
		)
		(pad "1" smd custom
			(at 0 -0.4318 180)
			(size 0.127 0.127)
			(layers "B.Cu" "B.Mask" "B.Paste")
			(net "M_B_CMDPU")
			(options
				(clearance outline)
				(anchor circle)
			)
			(primitives
				(gr_poly
					(pts
						(arc
							(start -0.2032 0.2794)
							(mid -0.239121 0.264521)
							(end -0.254 0.2286)
						)
						(arc
							(start -0.254 -0.2286)
							(mid -0.239121 -0.264521)
							(end -0.2032 -0.2794)
						)
						(arc
							(start 0.2032 -0.2794)
							(mid 0.239121 -0.264521)
							(end 0.254 -0.2286)
						)
						(arc
							(start 0.254 0.2286)
							(mid 0.239121 0.264521)
							(end 0.2032 0.2794)
						)
					)
					(width 0)
					(fill yes)
				)
			)
		)
		(pad "2" smd custom
			(at 0 0.4318 180)
			(size 0.127 0.127)
			(layers "B.Cu" "B.Mask" "B.Paste")
			(net "GND")
			(options
				(clearance outline)
				(anchor circle)
			)
			(primitives
				(gr_poly
					(pts
						(arc
							(start -0.2032 0.2794)
							(mid -0.239121 0.264521)
							(end -0.254 0.2286)
						)
						(arc
							(start -0.254 -0.2286)
							(mid -0.239121 -0.264521)
							(end -0.2032 -0.2794)
						)
						(arc
							(start 0.2032 -0.2794)
							(mid 0.239121 -0.264521)
							(end 0.254 -0.2286)
						)
						(arc
							(start 0.254 0.2286)
							(mid 0.239121 0.264521)
							(end 0.2032 0.2794)
						)
					)
					(width 0)
					(fill yes)
				)
			)
		)
	)
	(footprint ""
		(layer "B.Cu")
		(at 60.198 -14.9352)
		(property "Reference" "C317"
			(at 0 0 0)
			(layer "B.SilkS")
			(hide yes)
			(effects
				(font
					(size 1.27 1.27)
				)
				(justify mirror)
			)
		)
		(property "Value" "SCD1U10V2KX-5GP"
			(at -1.8923 -1.2065 0)
			(unlocked yes)
			(layer "B.Fab")
			(hide yes)
			(effects
				(font
					(size 1.016 1.016)
					(thickness 0.1524)
				)
				(justify mirror)
			)
		)
		(property "Device Type" "C402H22"
			(at -1.8923 -2.7305 0)
			(unlocked yes)
			(layer "B.Fab")
			(hide yes)
			(effects
				(font
					(size 1.016 1.016)
					(thickness 0.1524)
				)
				(justify mirror)
			)
		)
		(duplicate_pad_numbers_are_jumpers no)
		(fp_rect
			(start 0.381 0.7366)
			(end -0.381 -0.7366)
			(stroke
				(width 0)
				(type default)
			)
			(fill no)
			(layer "B.CrtYd")
		)
		(fp_rect
			(start 0.381 0.7366)
			(end -0.381 -0.7366)
			(stroke
				(width 0)
				(type default)
			)
			(fill no)
			(layer "B.Fab")
		)
		(pad "1" smd custom
			(at 0 -0.4572 180)
			(size 0.1143 0.1143)
			(layers "B.Cu" "B.Mask" "B.Paste")
			(net "P3V3_STBY")
			(options
				(clearance outline)
				(anchor circle)
			)
			(primitives
				(gr_poly
					(pts
						(arc
							(start -0.254 0.1778)
							(mid -0.239121 0.213721)
							(end -0.2032 0.2286)
						)
						(arc
							(start 0.2032 0.2286)
							(mid 0.239121 0.213721)
							(end 0.254 0.1778)
						)
						(arc
							(start 0.254 -0.1778)
							(mid 0.239121 -0.213721)
							(end 0.2032 -0.2286)
						)
						(arc
							(start -0.2032 -0.2286)
							(mid -0.239121 -0.213721)
							(end -0.254 -0.1778)
						)
					)
					(width 0)
					(fill yes)
				)
			)
		)
		(pad "2" smd custom
			(at 0 0.4572 180)
			(size 0.1143 0.1143)
			(layers "B.Cu" "B.Mask" "B.Paste")
			(net "GND")
			(options
				(clearance outline)
				(anchor circle)
			)
			(primitives
				(gr_poly
					(pts
						(arc
							(start -0.254 0.1778)
							(mid -0.239121 0.213721)
							(end -0.2032 0.2286)
						)
						(arc
							(start 0.2032 0.2286)
							(mid 0.239121 0.213721)
							(end 0.254 0.1778)
						)
						(arc
							(start 0.254 -0.1778)
							(mid 0.239121 -0.213721)
							(end 0.2032 -0.2286)
						)
						(arc
							(start -0.2032 -0.2286)
							(mid -0.239121 -0.213721)
							(end -0.254 -0.1778)
						)
					)
					(width 0)
					(fill yes)
				)
			)
		)
	)
	(footprint ""
		(layer "B.Cu")
		(at 147.828 -59.309)
		(property "Reference" "C359"
			(at 0 0 0)
			(layer "B.SilkS")
			(hide yes)
			(effects
				(font
					(size 1.27 1.27)
				)
				(justify mirror)
			)
		)
		(property "Value" "SC47U6D3V5MX-1-GP"
			(at 0 -4.9022 0)
			(unlocked yes)
			(layer "B.Fab")
			(hide yes)
			(effects
				(font
					(size 1.016 1.016)
					(thickness 0.1524)
				)
				(justify mirror)
			)
		)
		(property "Device Type" "C805H54"
			(at 0 -6.8072 0)
			(unlocked yes)
			(layer "B.Fab")
			(hide yes)
			(effects
				(font
					(size 1.016 1.016)
					(thickness 0.1524)
				)
				(justify mirror)
			)
		)
		(duplicate_pad_numbers_are_jumpers no)
		(fp_line
			(start -0.6096 0)
			(end 0.6096 0)
			(stroke
				(width 0.3048)
				(type default)
			)
			(layer "B.SilkS")
		)
		(fp_poly
			(pts
				(xy 0.9017 1.4351) (xy -0.9017 1.4351) (xy -0.9017 -1.4351) (xy 0.9017 -1.4351)
			)
			(stroke
				(width 0)
				(type default)
			)
			(fill no)
			(layer "B.CrtYd")
		)
		(fp_poly
			(pts
				(xy -0.9017 1.4351) (xy -0.9017 -1.4351) (xy 0.9017 -1.4351) (xy 0.9017 1.4351)
			)
			(stroke
				(width 0)
				(type default)
			)
			(fill no)
			(layer "B.Fab")
		)
		(pad "1" smd rect
			(at 0 -0.8382 180)
			(size 1.5494 0.9398)
			(layers "B.Cu" "B.Mask" "B.Paste")
			(net "PV_VDDR")
		)
		(pad "2" smd rect
			(at 0 0.8382 180)
			(size 1.5494 0.9398)
			(layers "B.Cu" "B.Mask" "B.Paste")
			(net "GND")
		)
	)
	(footprint ""
		(layer "B.Cu")
		(at 203.708 -65.3542 90)
		(property "Reference" "PC154"
			(at 0 0 90)
			(layer "B.SilkS")
			(hide yes)
			(effects
				(font
					(size 1.27 1.27)
				)
				(justify mirror)
			)
		)
		(property "Value" "SC10U6D3V3MX-GP"
			(at 0.0254 -2.0193 90)
			(unlocked yes)
			(layer "B.Fab")
			(hide yes)
			(effects
				(font
					(size 1.016 1.016)
					(thickness 0.1524)
				)
				(justify mirror)
			)
		)
		(property "Device Type" "C603H38"
			(at 0.0254 -3.5433 90)
			(unlocked yes)
			(layer "B.Fab")
			(hide yes)
			(effects
				(font
					(size 1.016 1.016)
					(thickness 0.1524)
				)
				(justify mirror)
			)
		)
		(duplicate_pad_numbers_are_jumpers no)
		(fp_line
			(start 0.4064 0)
			(end -0.4064 0)
			(stroke
				(width 0.2286)
				(type default)
			)
			(layer "B.SilkS")
		)
		(fp_rect
			(start 0.635 1.1811)
			(end -0.635 -1.1811)
			(stroke
				(width 0)
				(type default)
			)
			(fill no)
			(layer "B.CrtYd")
		)
		(fp_rect
			(start 0.635 1.1811)
			(end -0.635 -1.1811)
			(stroke
				(width 0)
				(type default)
			)
			(fill no)
			(layer "B.Fab")
		)
		(pad "1" smd custom
			(at 0 -0.6604 270)
			(size 0.19685 0.19685)
			(layers "B.Cu" "B.Mask" "B.Paste")
			(net "PV_VDDR")
			(options
				(clearance outline)
				(anchor circle)
			)
			(primitives
				(gr_poly
					(pts
						(arc
							(start 0.508 0.2921)
							(mid 0.478242 0.363942)
							(end 0.4064 0.3937)
						)
						(arc
							(start -0.4064 0.3937)
							(mid -0.478242 0.363942)
							(end -0.508 0.2921)
						)
						(arc
							(start -0.508 -0.2921)
							(mid -0.478242 -0.363942)
							(end -0.4064 -0.3937)
						)
						(arc
							(start 0.4064 -0.3937)
							(mid 0.478242 -0.363942)
							(end 0.508 -0.2921)
						)
					)
					(width 0)
					(fill yes)
				)
			)
		)
		(pad "2" smd custom
			(at 0 0.6604 270)
			(size 0.19685 0.19685)
			(layers "B.Cu" "B.Mask" "B.Paste")
			(net "GND")
			(options
				(clearance outline)
				(anchor circle)
			)
			(primitives
				(gr_poly
					(pts
						(arc
							(start 0.508 0.2921)
							(mid 0.478242 0.363942)
							(end 0.4064 0.3937)
						)
						(arc
							(start -0.4064 0.3937)
							(mid -0.478242 0.363942)
							(end -0.508 0.2921)
						)
						(arc
							(start -0.508 -0.2921)
							(mid -0.478242 -0.363942)
							(end -0.4064 -0.3937)
						)
						(arc
							(start 0.4064 -0.3937)
							(mid 0.478242 -0.363942)
							(end 0.508 -0.2921)
						)
					)
					(width 0)
					(fill yes)
				)
			)
		)
	)
	(footprint ""
		(layer "B.Cu")
		(at 25.4 -44.196 -90)
		(property "Reference" "PC139"
			(at 0 0 90)
			(layer "B.SilkS")
			(hide yes)
			(effects
				(font
					(size 1.27 1.27)
				)
				(justify mirror)
			)
		)
		(property "Value" "SC10U6D3V5KX-4GP"
			(at 0 -4.9022 270)
			(unlocked yes)
			(layer "B.Fab")
			(hide yes)
			(effects
				(font
					(size 1.016 1.016)
					(thickness 0.1524)
				)
				(justify mirror)
			)
		)
		(property "Device Type" "C805H58"
			(at 0 -6.8072 270)
			(unlocked yes)
			(layer "B.Fab")
			(hide yes)
			(effects
				(font
					(size 1.016 1.016)
					(thickness 0.1524)
				)
				(justify mirror)
			)
		)
		(duplicate_pad_numbers_are_jumpers no)
		(fp_line
			(start -0.6096 0)
			(end 0.6096 0)
			(stroke
				(width 0.3048)
				(type default)
			)
			(layer "B.SilkS")
		)
		(fp_poly
			(pts
				(xy 0.9017 1.4351) (xy -0.9017 1.4351) (xy -0.9017 -1.4351) (xy 0.9017 -1.4351)
			)
			(stroke
				(width 0)
				(type default)
			)
			(fill no)
			(layer "B.CrtYd")
		)
		(fp_poly
			(pts
				(xy -0.9017 1.4351) (xy -0.9017 -1.4351) (xy 0.9017 -1.4351) (xy 0.9017 1.4351)
			)
			(stroke
				(width 0)
				(type default)
			)
			(fill no)
			(layer "B.Fab")
		)
		(pad "1" smd rect
			(at 0 -0.8382 90)
			(size 1.5494 0.9398)
			(layers "B.Cu" "B.Mask" "B.Paste")
			(net "P1V5_STBY_OUT")
		)
		(pad "2" smd rect
			(at 0 0.8382 90)
			(size 1.5494 0.9398)
			(layers "B.Cu" "B.Mask" "B.Paste")
			(net "GND")
		)
	)
	(footprint ""
		(layer "B.Cu")
		(at 55.3974 -49.9618 180)
		(property "Reference" "PR152"
			(at 0 0 0)
			(layer "B.SilkS")
			(hide yes)
			(effects
				(font
					(size 1.27 1.27)
				)
				(justify mirror)
			)
		)
		(property "Value" "0R2J-2-GP"
			(at -1.7907 -1.1176 180)
			(unlocked yes)
			(layer "B.Fab")
			(hide yes)
			(effects
				(font
					(size 1.016 1.016)
					(thickness 0.1524)
				)
				(justify mirror)
			)
		)
		(property "Device Type" "R402H16"
			(at -1.7907 -2.6416 180)
			(unlocked yes)
			(layer "B.Fab")
			(hide yes)
			(effects
				(font
					(size 1.016 1.016)
					(thickness 0.1524)
				)
				(justify mirror)
			)
		)
		(duplicate_pad_numbers_are_jumpers no)
		(fp_rect
			(start 0.381 0.8382)
			(end -0.381 -0.8382)
			(stroke
				(width 0)
				(type default)
			)
			(fill no)
			(layer "B.CrtYd")
		)
		(fp_rect
			(start 0.381 0.8382)
			(end -0.381 -0.8382)
			(stroke
				(width 0)
				(type default)
			)
			(fill no)
			(layer "B.Fab")
		)
		(pad "1" smd custom
			(at 0 -0.4318)
			(size 0.127 0.127)
			(layers "B.Cu" "B.Mask" "B.Paste")
			(net "P1V5_STBY_PG")
			(options
				(clearance outline)
				(anchor circle)
			)
			(primitives
				(gr_poly
					(pts
						(arc
							(start -0.2032 0.2794)
							(mid -0.239121 0.264521)
							(end -0.254 0.2286)
						)
						(arc
							(start -0.254 -0.2286)
							(mid -0.239121 -0.264521)
							(end -0.2032 -0.2794)
						)
						(arc
							(start 0.2032 -0.2794)
							(mid 0.239121 -0.264521)
							(end 0.254 -0.2286)
						)
						(arc
							(start 0.254 0.2286)
							(mid 0.239121 0.264521)
							(end 0.2032 0.2794)
						)
					)
					(width 0)
					(fill yes)
				)
			)
		)
		(pad "2" smd custom
			(at 0 0.4318)
			(size 0.127 0.127)
			(layers "B.Cu" "B.Mask" "B.Paste")
			(net "VR_EN_P1V0_STBY")
			(options
				(clearance outline)
				(anchor circle)
			)
			(primitives
				(gr_poly
					(pts
						(arc
							(start -0.2032 0.2794)
							(mid -0.239121 0.264521)
							(end -0.254 0.2286)
						)
						(arc
							(start -0.254 -0.2286)
							(mid -0.239121 -0.264521)
							(end -0.2032 -0.2794)
						)
						(arc
							(start 0.2032 -0.2794)
							(mid 0.239121 -0.264521)
							(end 0.254 -0.2286)
						)
						(arc
							(start 0.254 0.2286)
							(mid 0.239121 0.264521)
							(end 0.2032 0.2794)
						)
					)
					(width 0)
					(fill yes)
				)
			)
		)
	)
	(footprint ""
		(layer "B.Cu")
		(at 95.3262 -42.30243 -90)
		(property "Reference" "TP22"
			(at 0 0 90)
			(layer "B.SilkS")
			(hide yes)
			(effects
				(font
					(size 1.27 1.27)
				)
				(justify mirror)
			)
		)
		(property "Value" "TPAD24"
			(at 0 -2.9972 270)
			(unlocked yes)
			(layer "B.Fab")
			(hide yes)
			(effects
				(font
					(size 1.016 1.016)
					(thickness 0.1524)
				)
				(justify mirror)
			)
		)
		(property "Device Type" "TPAD24"
			(at 0 -4.5212 270)
			(unlocked yes)
			(layer "B.Fab")
			(hide yes)
			(effects
				(font
					(size 1.016 1.016)
					(thickness 0.1524)
				)
				(justify mirror)
			)
		)
		(duplicate_pad_numbers_are_jumpers no)
		(fp_poly
			(pts
				(arc
					(start 0 -0.3048)
					(mid 0 0.3048)
					(end 0 -0.3048)
				)
			)
			(stroke
				(width 0)
				(type default)
			)
			(fill no)
			(layer "B.CrtYd")
		)
		(fp_poly
			(pts
				(arc
					(start 0 -0.6096)
					(mid 0 0.6096)
					(end 0 -0.6096)
				)
			)
			(stroke
				(width 0)
				(type default)
			)
			(fill no)
			(layer "B.Fab")
		)
		(pad "1" smd circle
			(at 0 0 90)
			(size 0.6096 0.6096)
			(layers "B.Cu" "B.Mask" "B.Paste")
			(net "TP_CPU_RSVD0")
		)
	)
	(footprint ""
		(layer "B.Cu")
		(at 107.188 -27.321002)
		(property "Reference" "C238"
			(at 0 0 0)
			(layer "B.SilkS")
			(hide yes)
			(effects
				(font
					(size 1.27 1.27)
				)
				(justify mirror)
			)
		)
		(property "Value" "SC1U10V2KX-1GP"
			(at -1.1811 -2.7051 0)
			(unlocked yes)
			(layer "B.Fab")
			(hide yes)
			(effects
				(font
					(size 1.016 1.016)
					(thickness 0.1524)
				)
				(justify mirror)
			)
		)
		(property "Device Type" "C402H22"
			(at -1.1811 -4.2291 0)
			(unlocked yes)
			(layer "B.Fab")
			(hide yes)
			(effects
				(font
					(size 1.016 1.016)
					(thickness 0.1524)
				)
				(justify mirror)
			)
		)
		(duplicate_pad_numbers_are_jumpers no)
		(fp_rect
			(start 0.381 0.7366)
			(end -0.381 -0.7366)
			(stroke
				(width 0)
				(type default)
			)
			(fill no)
			(layer "B.CrtYd")
		)
		(fp_rect
			(start 0.381 0.7366)
			(end -0.381 -0.7366)
			(stroke
				(width 0)
				(type default)
			)
			(fill no)
			(layer "B.Fab")
		)
		(pad "1" smd custom
			(at 0 -0.4572 180)
			(size 0.1143 0.1143)
			(layers "B.Cu" "B.Mask" "B.Paste")
			(net "PV_VDDR")
			(options
				(clearance outline)
				(anchor circle)
			)
			(primitives
				(gr_poly
					(pts
						(arc
							(start -0.254 0.1778)
							(mid -0.239121 0.213721)
							(end -0.2032 0.2286)
						)
						(arc
							(start 0.2032 0.2286)
							(mid 0.239121 0.213721)
							(end 0.254 0.1778)
						)
						(arc
							(start 0.254 -0.1778)
							(mid 0.239121 -0.213721)
							(end 0.2032 -0.2286)
						)
						(arc
							(start -0.2032 -0.2286)
							(mid -0.239121 -0.213721)
							(end -0.254 -0.1778)
						)
					)
					(width 0)
					(fill yes)
				)
			)
		)
		(pad "2" smd custom
			(at 0 0.4572 180)
			(size 0.1143 0.1143)
			(layers "B.Cu" "B.Mask" "B.Paste")
			(net "GND")
			(options
				(clearance outline)
				(anchor circle)
			)
			(primitives
				(gr_poly
					(pts
						(arc
							(start -0.254 0.1778)
							(mid -0.239121 0.213721)
							(end -0.2032 0.2286)
						)
						(arc
							(start 0.2032 0.2286)
							(mid 0.239121 0.213721)
							(end 0.254 0.1778)
						)
						(arc
							(start 0.254 -0.1778)
							(mid 0.239121 -0.213721)
							(end 0.2032 -0.2286)
						)
						(arc
							(start -0.2032 -0.2286)
							(mid -0.239121 -0.213721)
							(end -0.254 -0.1778)
						)
					)
					(width 0)
					(fill yes)
				)
			)
		)
	)
	(footprint ""
		(layer "B.Cu")
		(at 89.1794 -40.4876 -90)
		(property "Reference" "R321"
			(at 0 0 90)
			(layer "B.SilkS")
			(hide yes)
			(effects
				(font
					(size 1.27 1.27)
				)
				(justify mirror)
			)
		)
		(property "Value" "2K2R2F-GP"
			(at -0.064008 -3.993896 270)
			(unlocked yes)
			(layer "B.Fab")
			(hide yes)
			(effects
				(font
					(size 1.016 1.016)
					(thickness 0.1524)
				)
				(justify mirror)
			)
		)
		(property "Device Type" "R402H16"
			(at -0.064008 -5.517896 270)
			(unlocked yes)
			(layer "B.Fab")
			(hide yes)
			(effects
				(font
					(size 1.016 1.016)
					(thickness 0.1524)
				)
				(justify mirror)
			)
		)
		(duplicate_pad_numbers_are_jumpers no)
		(fp_rect
			(start 0.381 0.8382)
			(end -0.381 -0.8382)
			(stroke
				(width 0)
				(type default)
			)
			(fill no)
			(layer "B.CrtYd")
		)
		(fp_rect
			(start 0.381 0.8382)
			(end -0.381 -0.8382)
			(stroke
				(width 0)
				(type default)
			)
			(fill no)
			(layer "B.Fab")
		)
		(pad "1" smd custom
			(at 0 -0.4318 90)
			(size 0.127 0.127)
			(layers "B.Cu" "B.Mask" "B.Paste")
			(net "P3V3")
			(options
				(clearance outline)
				(anchor circle)
			)
			(primitives
				(gr_poly
					(pts
						(arc
							(start -0.2032 0.2794)
							(mid -0.239121 0.264521)
							(end -0.254 0.2286)
						)
						(arc
							(start -0.254 -0.2286)
							(mid -0.239121 -0.264521)
							(end -0.2032 -0.2794)
						)
						(arc
							(start 0.2032 -0.2794)
							(mid 0.239121 -0.264521)
							(end 0.254 -0.2286)
						)
						(arc
							(start 0.254 0.2286)
							(mid 0.239121 0.264521)
							(end 0.2032 0.2794)
						)
					)
					(width 0)
					(fill yes)
				)
			)
		)
		(pad "2" smd custom
			(at 0 0.4318 90)
			(size 0.127 0.127)
			(layers "B.Cu" "B.Mask" "B.Paste")
			(net "LPC_CPU_CLKRUN#")
			(options
				(clearance outline)
				(anchor circle)
			)
			(primitives
				(gr_poly
					(pts
						(arc
							(start -0.2032 0.2794)
							(mid -0.239121 0.264521)
							(end -0.254 0.2286)
						)
						(arc
							(start -0.254 -0.2286)
							(mid -0.239121 -0.264521)
							(end -0.2032 -0.2794)
						)
						(arc
							(start 0.2032 -0.2794)
							(mid 0.239121 -0.264521)
							(end 0.254 -0.2286)
						)
						(arc
							(start 0.254 0.2286)
							(mid 0.239121 0.264521)
							(end 0.2032 0.2794)
						)
					)
					(width 0)
					(fill yes)
				)
			)
		)
	)
	(footprint ""
		(layer "B.Cu")
		(at 45.72 -54.102 -90)
		(property "Reference" "R102"
			(at 0 0 90)
			(layer "B.SilkS")
			(hide yes)
			(effects
				(font
					(size 1.27 1.27)
				)
				(justify mirror)
			)
		)
		(property "Value" "1KR2F-3-GP"
			(at -1.7907 -1.1176 270)
			(unlocked yes)
			(layer "B.Fab")
			(hide yes)
			(effects
				(font
					(size 1.016 1.016)
					(thickness 0.1524)
				)
				(justify mirror)
			)
		)
		(property "Device Type" "R402H16"
			(at -1.7907 -2.6416 270)
			(unlocked yes)
			(layer "B.Fab")
			(hide yes)
			(effects
				(font
					(size 1.016 1.016)
					(thickness 0.1524)
				)
				(justify mirror)
			)
		)
		(duplicate_pad_numbers_are_jumpers no)
		(fp_rect
			(start 0.381 0.8382)
			(end -0.381 -0.8382)
			(stroke
				(width 0)
				(type default)
			)
			(fill no)
			(layer "B.CrtYd")
		)
		(fp_rect
			(start 0.381 0.8382)
			(end -0.381 -0.8382)
			(stroke
				(width 0)
				(type default)
			)
			(fill no)
			(layer "B.Fab")
		)
		(pad "1" smd custom
			(at 0 -0.4318 90)
			(size 0.127 0.127)
			(layers "B.Cu" "B.Mask" "B.Paste")
			(net "CLKREQB")
			(options
				(clearance outline)
				(anchor circle)
			)
			(primitives
				(gr_poly
					(pts
						(arc
							(start -0.2032 0.2794)
							(mid -0.239121 0.264521)
							(end -0.254 0.2286)
						)
						(arc
							(start -0.254 -0.2286)
							(mid -0.239121 -0.264521)
							(end -0.2032 -0.2794)
						)
						(arc
							(start 0.2032 -0.2794)
							(mid 0.239121 -0.264521)
							(end 0.254 -0.2286)
						)
						(arc
							(start 0.254 0.2286)
							(mid 0.239121 0.264521)
							(end 0.2032 0.2794)
						)
					)
					(width 0)
					(fill yes)
				)
			)
		)
		(pad "2" smd custom
			(at 0 0.4318 90)
			(size 0.127 0.127)
			(layers "B.Cu" "B.Mask" "B.Paste")
			(net "GND")
			(options
				(clearance outline)
				(anchor circle)
			)
			(primitives
				(gr_poly
					(pts
						(arc
							(start -0.2032 0.2794)
							(mid -0.239121 0.264521)
							(end -0.254 0.2286)
						)
						(arc
							(start -0.254 -0.2286)
							(mid -0.239121 -0.264521)
							(end -0.2032 -0.2794)
						)
						(arc
							(start 0.2032 -0.2794)
							(mid 0.239121 -0.264521)
							(end 0.254 -0.2286)
						)
						(arc
							(start 0.254 0.2286)
							(mid 0.239121 0.264521)
							(end 0.2032 0.2794)
						)
					)
					(width 0)
					(fill yes)
				)
			)
		)
	)
	(footprint ""
		(layer "B.Cu")
		(at 81.026 -63.246 180)
		(property "Reference" "R288"
			(at 0 0 0)
			(layer "B.SilkS")
			(hide yes)
			(effects
				(font
					(size 1.27 1.27)
				)
				(justify mirror)
			)
		)
		(property "Value" "0R2J-2-GP"
			(at -0.064008 -3.993896 180)
			(unlocked yes)
			(layer "B.Fab")
			(hide yes)
			(effects
				(font
					(size 1.016 1.016)
					(thickness 0.1524)
				)
				(justify mirror)
			)
		)
		(property "Device Type" "R402H16"
			(at -0.064008 -5.517896 180)
			(unlocked yes)
			(layer "B.Fab")
			(hide yes)
			(effects
				(font
					(size 1.016 1.016)
					(thickness 0.1524)
				)
				(justify mirror)
			)
		)
		(duplicate_pad_numbers_are_jumpers no)
		(fp_rect
			(start 0.381 0.8382)
			(end -0.381 -0.8382)
			(stroke
				(width 0)
				(type default)
			)
			(fill no)
			(layer "B.CrtYd")
		)
		(fp_rect
			(start 0.381 0.8382)
			(end -0.381 -0.8382)
			(stroke
				(width 0)
				(type default)
			)
			(fill no)
			(layer "B.Fab")
		)
		(pad "1" smd custom
			(at 0 -0.4318)
			(size 0.127 0.127)
			(layers "B.Cu" "B.Mask" "B.Paste")
			(net "SVID_DATA_R")
			(options
				(clearance outline)
				(anchor circle)
			)
			(primitives
				(gr_poly
					(pts
						(arc
							(start -0.2032 0.2794)
							(mid -0.239121 0.264521)
							(end -0.254 0.2286)
						)
						(arc
							(start -0.254 -0.2286)
							(mid -0.239121 -0.264521)
							(end -0.2032 -0.2794)
						)
						(arc
							(start 0.2032 -0.2794)
							(mid 0.239121 -0.264521)
							(end 0.254 -0.2286)
						)
						(arc
							(start 0.254 0.2286)
							(mid 0.239121 0.264521)
							(end 0.2032 0.2794)
						)
					)
					(width 0)
					(fill yes)
				)
			)
		)
		(pad "2" smd custom
			(at 0 0.4318)
			(size 0.127 0.127)
			(layers "B.Cu" "B.Mask" "B.Paste")
			(net "SVID_CPU_DATA")
			(options
				(clearance outline)
				(anchor circle)
			)
			(primitives
				(gr_poly
					(pts
						(arc
							(start -0.2032 0.2794)
							(mid -0.239121 0.264521)
							(end -0.254 0.2286)
						)
						(arc
							(start -0.254 -0.2286)
							(mid -0.239121 -0.264521)
							(end -0.2032 -0.2794)
						)
						(arc
							(start 0.2032 -0.2794)
							(mid 0.239121 -0.264521)
							(end 0.254 -0.2286)
						)
						(arc
							(start 0.254 0.2286)
							(mid 0.239121 0.264521)
							(end 0.2032 0.2794)
						)
					)
					(width 0)
					(fill yes)
				)
			)
		)
	)
	(footprint ""
		(layer "B.Cu")
		(at 158.4452 -59.6646)
		(property "Reference" "C325"
			(at 0 0 0)
			(layer "B.SilkS")
			(hide yes)
			(effects
				(font
					(size 1.27 1.27)
				)
				(justify mirror)
			)
		)
		(property "Value" "SCD1U16V2KX-3GP"
			(at -1.8923 -1.2065 0)
			(unlocked yes)
			(layer "B.Fab")
			(hide yes)
			(effects
				(font
					(size 1.016 1.016)
					(thickness 0.1524)
				)
				(justify mirror)
			)
		)
		(property "Device Type" "C402H22"
			(at -1.8923 -2.7305 0)
			(unlocked yes)
			(layer "B.Fab")
			(hide yes)
			(effects
				(font
					(size 1.016 1.016)
					(thickness 0.1524)
				)
				(justify mirror)
			)
		)
		(duplicate_pad_numbers_are_jumpers no)
		(fp_rect
			(start 0.381 0.7366)
			(end -0.381 -0.7366)
			(stroke
				(width 0)
				(type default)
			)
			(fill no)
			(layer "B.CrtYd")
		)
		(fp_rect
			(start 0.381 0.7366)
			(end -0.381 -0.7366)
			(stroke
				(width 0)
				(type default)
			)
			(fill no)
			(layer "B.Fab")
		)
		(pad "1" smd custom
			(at 0 -0.4572 180)
			(size 0.1143 0.1143)
			(layers "B.Cu" "B.Mask" "B.Paste")
			(net "PV_VDDR")
			(options
				(clearance outline)
				(anchor circle)
			)
			(primitives
				(gr_poly
					(pts
						(arc
							(start -0.254 0.1778)
							(mid -0.239121 0.213721)
							(end -0.2032 0.2286)
						)
						(arc
							(start 0.2032 0.2286)
							(mid 0.239121 0.213721)
							(end 0.254 0.1778)
						)
						(arc
							(start 0.254 -0.1778)
							(mid 0.239121 -0.213721)
							(end 0.2032 -0.2286)
						)
						(arc
							(start -0.2032 -0.2286)
							(mid -0.239121 -0.213721)
							(end -0.254 -0.1778)
						)
					)
					(width 0)
					(fill yes)
				)
			)
		)
		(pad "2" smd custom
			(at 0 0.4572 180)
			(size 0.1143 0.1143)
			(layers "B.Cu" "B.Mask" "B.Paste")
			(net "GND")
			(options
				(clearance outline)
				(anchor circle)
			)
			(primitives
				(gr_poly
					(pts
						(arc
							(start -0.254 0.1778)
							(mid -0.239121 0.213721)
							(end -0.2032 0.2286)
						)
						(arc
							(start 0.2032 0.2286)
							(mid 0.239121 0.213721)
							(end 0.254 0.1778)
						)
						(arc
							(start 0.254 -0.1778)
							(mid 0.239121 -0.213721)
							(end 0.2032 -0.2286)
						)
						(arc
							(start -0.2032 -0.2286)
							(mid -0.239121 -0.213721)
							(end -0.254 -0.1778)
						)
					)
					(width 0)
					(fill yes)
				)
			)
		)
	)
	(footprint ""
		(layer "B.Cu")
		(at 40.64 -42.291 180)
		(property "Reference" "C27"
			(at 0 0 0)
			(layer "B.SilkS")
			(hide yes)
			(effects
				(font
					(size 1.27 1.27)
				)
				(justify mirror)
			)
		)
		(property "Value" "SCD1U10V2KX-5GP"
			(at -1.8923 -1.2065 180)
			(unlocked yes)
			(layer "B.Fab")
			(hide yes)
			(effects
				(font
					(size 1.016 1.016)
					(thickness 0.1524)
				)
				(justify mirror)
			)
		)
		(property "Device Type" "C402H22"
			(at -1.8923 -2.7305 180)
			(unlocked yes)
			(layer "B.Fab")
			(hide yes)
			(effects
				(font
					(size 1.016 1.016)
					(thickness 0.1524)
				)
				(justify mirror)
			)
		)
		(duplicate_pad_numbers_are_jumpers no)
		(fp_rect
			(start 0.381 0.7366)
			(end -0.381 -0.7366)
			(stroke
				(width 0)
				(type default)
			)
			(fill no)
			(layer "B.CrtYd")
		)
		(fp_rect
			(start 0.381 0.7366)
			(end -0.381 -0.7366)
			(stroke
				(width 0)
				(type default)
			)
			(fill no)
			(layer "B.Fab")
		)
		(pad "1" smd custom
			(at 0 -0.4572)
			(size 0.1143 0.1143)
			(layers "B.Cu" "B.Mask" "B.Paste")
			(net "P3V3")
			(options
				(clearance outline)
				(anchor circle)
			)
			(primitives
				(gr_poly
					(pts
						(arc
							(start -0.254 0.1778)
							(mid -0.239121 0.213721)
							(end -0.2032 0.2286)
						)
						(arc
							(start 0.2032 0.2286)
							(mid 0.239121 0.213721)
							(end 0.254 0.1778)
						)
						(arc
							(start 0.254 -0.1778)
							(mid 0.239121 -0.213721)
							(end 0.2032 -0.2286)
						)
						(arc
							(start -0.2032 -0.2286)
							(mid -0.239121 -0.213721)
							(end -0.254 -0.1778)
						)
					)
					(width 0)
					(fill yes)
				)
			)
		)
		(pad "2" smd custom
			(at 0 0.4572)
			(size 0.1143 0.1143)
			(layers "B.Cu" "B.Mask" "B.Paste")
			(net "GND")
			(options
				(clearance outline)
				(anchor circle)
			)
			(primitives
				(gr_poly
					(pts
						(arc
							(start -0.254 0.1778)
							(mid -0.239121 0.213721)
							(end -0.2032 0.2286)
						)
						(arc
							(start 0.2032 0.2286)
							(mid 0.239121 0.213721)
							(end 0.254 0.1778)
						)
						(arc
							(start 0.254 -0.1778)
							(mid 0.239121 -0.213721)
							(end 0.2032 -0.2286)
						)
						(arc
							(start -0.2032 -0.2286)
							(mid -0.239121 -0.213721)
							(end -0.254 -0.1778)
						)
					)
					(width 0)
					(fill yes)
				)
			)
		)
	)
	(footprint ""
		(layer "B.Cu")
		(at 81.026 -13.462)
		(property "Reference" "C274"
			(at 0 0 0)
			(layer "B.SilkS")
			(hide yes)
			(effects
				(font
					(size 1.27 1.27)
				)
				(justify mirror)
			)
		)
		(property "Value" "SCD1U16V2KX-3GP"
			(at -1.1811 -2.7051 0)
			(unlocked yes)
			(layer "B.Fab")
			(hide yes)
			(effects
				(font
					(size 1.016 1.016)
					(thickness 0.1524)
				)
				(justify mirror)
			)
		)
		(property "Device Type" "C402H22"
			(at -1.1811 -4.2291 0)
			(unlocked yes)
			(layer "B.Fab")
			(hide yes)
			(effects
				(font
					(size 1.016 1.016)
					(thickness 0.1524)
				)
				(justify mirror)
			)
		)
		(duplicate_pad_numbers_are_jumpers no)
		(fp_rect
			(start 0.381 0.7366)
			(end -0.381 -0.7366)
			(stroke
				(width 0)
				(type default)
			)
			(fill no)
			(layer "B.CrtYd")
		)
		(fp_rect
			(start 0.381 0.7366)
			(end -0.381 -0.7366)
			(stroke
				(width 0)
				(type default)
			)
			(fill no)
			(layer "B.Fab")
		)
		(pad "1" smd custom
			(at 0 -0.4572 180)
			(size 0.1143 0.1143)
			(layers "B.Cu" "B.Mask" "B.Paste")
			(net "P2E_CPU_SAS_C_TX_DP0")
			(options
				(clearance outline)
				(anchor circle)
			)
			(primitives
				(gr_poly
					(pts
						(arc
							(start -0.254 0.1778)
							(mid -0.239121 0.213721)
							(end -0.2032 0.2286)
						)
						(arc
							(start 0.2032 0.2286)
							(mid 0.239121 0.213721)
							(end 0.254 0.1778)
						)
						(arc
							(start 0.254 -0.1778)
							(mid 0.239121 -0.213721)
							(end 0.2032 -0.2286)
						)
						(arc
							(start -0.2032 -0.2286)
							(mid -0.239121 -0.213721)
							(end -0.254 -0.1778)
						)
					)
					(width 0)
					(fill yes)
				)
			)
		)
		(pad "2" smd custom
			(at 0 0.4572 180)
			(size 0.1143 0.1143)
			(layers "B.Cu" "B.Mask" "B.Paste")
			(net "P2E_CPU_SAS_TX_DP0")
			(options
				(clearance outline)
				(anchor circle)
			)
			(primitives
				(gr_poly
					(pts
						(arc
							(start -0.254 0.1778)
							(mid -0.239121 0.213721)
							(end -0.2032 0.2286)
						)
						(arc
							(start 0.2032 0.2286)
							(mid 0.239121 0.213721)
							(end 0.254 0.1778)
						)
						(arc
							(start 0.254 -0.1778)
							(mid 0.239121 -0.213721)
							(end 0.2032 -0.2286)
						)
						(arc
							(start -0.2032 -0.2286)
							(mid -0.239121 -0.213721)
							(end -0.254 -0.1778)
						)
					)
					(width 0)
					(fill yes)
				)
			)
		)
	)
	(footprint ""
		(layer "B.Cu")
		(at 48.133 -15.9004)
		(property "Reference" "R419"
			(at 0 0 0)
			(layer "B.SilkS")
			(hide yes)
			(effects
				(font
					(size 1.27 1.27)
				)
				(justify mirror)
			)
		)
		(property "Value" "33R2F-3-GP"
			(at -1.7907 -1.1176 0)
			(unlocked yes)
			(layer "B.Fab")
			(hide yes)
			(effects
				(font
					(size 1.016 1.016)
					(thickness 0.1524)
				)
				(justify mirror)
			)
		)
		(property "Device Type" "R402H16"
			(at -1.7907 -2.6416 0)
			(unlocked yes)
			(layer "B.Fab")
			(hide yes)
			(effects
				(font
					(size 1.016 1.016)
					(thickness 0.1524)
				)
				(justify mirror)
			)
		)
		(duplicate_pad_numbers_are_jumpers no)
		(fp_rect
			(start 0.381 0.8382)
			(end -0.381 -0.8382)
			(stroke
				(width 0)
				(type default)
			)
			(fill no)
			(layer "B.CrtYd")
		)
		(fp_rect
			(start 0.381 0.8382)
			(end -0.381 -0.8382)
			(stroke
				(width 0)
				(type default)
			)
			(fill no)
			(layer "B.Fab")
		)
		(pad "1" smd custom
			(at 0 -0.4318 180)
			(size 0.127 0.127)
			(layers "B.Cu" "B.Mask" "B.Paste")
			(net "CLK_100M_PCIE2_REFCLK_R_DP")
			(options
				(clearance outline)
				(anchor circle)
			)
			(primitives
				(gr_poly
					(pts
						(arc
							(start -0.2032 0.2794)
							(mid -0.239121 0.264521)
							(end -0.254 0.2286)
						)
						(arc
							(start -0.254 -0.2286)
							(mid -0.239121 -0.264521)
							(end -0.2032 -0.2794)
						)
						(arc
							(start 0.2032 -0.2794)
							(mid 0.239121 -0.264521)
							(end 0.254 -0.2286)
						)
						(arc
							(start 0.254 0.2286)
							(mid 0.239121 0.264521)
							(end 0.2032 0.2794)
						)
					)
					(width 0)
					(fill yes)
				)
			)
		)
		(pad "2" smd custom
			(at 0 0.4318 180)
			(size 0.127 0.127)
			(layers "B.Cu" "B.Mask" "B.Paste")
			(net "CLK_100M_PCIE2_REFCLK_DP")
			(options
				(clearance outline)
				(anchor circle)
			)
			(primitives
				(gr_poly
					(pts
						(arc
							(start -0.2032 0.2794)
							(mid -0.239121 0.264521)
							(end -0.254 0.2286)
						)
						(arc
							(start -0.254 -0.2286)
							(mid -0.239121 -0.264521)
							(end -0.2032 -0.2794)
						)
						(arc
							(start 0.2032 -0.2794)
							(mid 0.239121 -0.264521)
							(end 0.254 -0.2286)
						)
						(arc
							(start 0.254 0.2286)
							(mid 0.239121 0.264521)
							(end 0.2032 0.2794)
						)
					)
					(width 0)
					(fill yes)
				)
			)
		)
	)
	(footprint ""
		(layer "B.Cu")
		(at 36.449 -22.225)
		(property "Reference" "R424"
			(at 0 0 0)
			(layer "B.SilkS")
			(hide yes)
			(effects
				(font
					(size 1.27 1.27)
				)
				(justify mirror)
			)
		)
		(property "Value" "43D2R2F-GP"
			(at -1.7907 -1.1176 0)
			(unlocked yes)
			(layer "B.Fab")
			(hide yes)
			(effects
				(font
					(size 1.016 1.016)
					(thickness 0.1524)
				)
				(justify mirror)
			)
		)
		(property "Device Type" "R402H16"
			(at -1.7907 -2.6416 0)
			(unlocked yes)
			(layer "B.Fab")
			(hide yes)
			(effects
				(font
					(size 1.016 1.016)
					(thickness 0.1524)
				)
				(justify mirror)
			)
		)
		(duplicate_pad_numbers_are_jumpers no)
		(fp_rect
			(start 0.381 0.8382)
			(end -0.381 -0.8382)
			(stroke
				(width 0)
				(type default)
			)
			(fill no)
			(layer "B.CrtYd")
		)
		(fp_rect
			(start 0.381 0.8382)
			(end -0.381 -0.8382)
			(stroke
				(width 0)
				(type default)
			)
			(fill no)
			(layer "B.Fab")
		)
		(pad "1" smd custom
			(at 0 -0.4318 180)
			(size 0.127 0.127)
			(layers "B.Cu" "B.Mask" "B.Paste")
			(net "CLK_100M_CLKBUFF_NGFF_DN")
			(options
				(clearance outline)
				(anchor circle)
			)
			(primitives
				(gr_poly
					(pts
						(arc
							(start -0.2032 0.2794)
							(mid -0.239121 0.264521)
							(end -0.254 0.2286)
						)
						(arc
							(start -0.254 -0.2286)
							(mid -0.239121 -0.264521)
							(end -0.2032 -0.2794)
						)
						(arc
							(start 0.2032 -0.2794)
							(mid 0.239121 -0.264521)
							(end 0.254 -0.2286)
						)
						(arc
							(start 0.254 0.2286)
							(mid 0.239121 0.264521)
							(end 0.2032 0.2794)
						)
					)
					(width 0)
					(fill yes)
				)
			)
		)
		(pad "2" smd custom
			(at 0 0.4318 180)
			(size 0.127 0.127)
			(layers "B.Cu" "B.Mask" "B.Paste")
			(net "GND")
			(options
				(clearance outline)
				(anchor circle)
			)
			(primitives
				(gr_poly
					(pts
						(arc
							(start -0.2032 0.2794)
							(mid -0.239121 0.264521)
							(end -0.254 0.2286)
						)
						(arc
							(start -0.254 -0.2286)
							(mid -0.239121 -0.264521)
							(end -0.2032 -0.2794)
						)
						(arc
							(start 0.2032 -0.2794)
							(mid 0.239121 -0.264521)
							(end 0.254 -0.2286)
						)
						(arc
							(start 0.254 0.2286)
							(mid 0.239121 0.264521)
							(end 0.2032 0.2794)
						)
					)
					(width 0)
					(fill yes)
				)
			)
		)
	)
	(footprint ""
		(layer "B.Cu")
		(at 53.975 -43.434 180)
		(property "Reference" "C23"
			(at 0 0 0)
			(layer "B.SilkS")
			(hide yes)
			(effects
				(font
					(size 1.27 1.27)
				)
				(justify mirror)
			)
		)
		(property "Value" "SCD1U10V2KX-5GP"
			(at -1.8923 -1.2065 180)
			(unlocked yes)
			(layer "B.Fab")
			(hide yes)
			(effects
				(font
					(size 1.016 1.016)
					(thickness 0.1524)
				)
				(justify mirror)
			)
		)
		(property "Device Type" "C402H22"
			(at -1.8923 -2.7305 180)
			(unlocked yes)
			(layer "B.Fab")
			(hide yes)
			(effects
				(font
					(size 1.016 1.016)
					(thickness 0.1524)
				)
				(justify mirror)
			)
		)
		(duplicate_pad_numbers_are_jumpers no)
		(fp_rect
			(start 0.381 0.7366)
			(end -0.381 -0.7366)
			(stroke
				(width 0)
				(type default)
			)
			(fill no)
			(layer "B.CrtYd")
		)
		(fp_rect
			(start 0.381 0.7366)
			(end -0.381 -0.7366)
			(stroke
				(width 0)
				(type default)
			)
			(fill no)
			(layer "B.Fab")
		)
		(pad "1" smd custom
			(at 0 -0.4572)
			(size 0.1143 0.1143)
			(layers "B.Cu" "B.Mask" "B.Paste")
			(net "P3V3")
			(options
				(clearance outline)
				(anchor circle)
			)
			(primitives
				(gr_poly
					(pts
						(arc
							(start -0.254 0.1778)
							(mid -0.239121 0.213721)
							(end -0.2032 0.2286)
						)
						(arc
							(start 0.2032 0.2286)
							(mid 0.239121 0.213721)
							(end 0.254 0.1778)
						)
						(arc
							(start 0.254 -0.1778)
							(mid 0.239121 -0.213721)
							(end 0.2032 -0.2286)
						)
						(arc
							(start -0.2032 -0.2286)
							(mid -0.239121 -0.213721)
							(end -0.254 -0.1778)
						)
					)
					(width 0)
					(fill yes)
				)
			)
		)
		(pad "2" smd custom
			(at 0 0.4572)
			(size 0.1143 0.1143)
			(layers "B.Cu" "B.Mask" "B.Paste")
			(net "GND")
			(options
				(clearance outline)
				(anchor circle)
			)
			(primitives
				(gr_poly
					(pts
						(arc
							(start -0.254 0.1778)
							(mid -0.239121 0.213721)
							(end -0.2032 0.2286)
						)
						(arc
							(start 0.2032 0.2286)
							(mid 0.239121 0.213721)
							(end 0.254 0.1778)
						)
						(arc
							(start 0.254 -0.1778)
							(mid 0.239121 -0.213721)
							(end 0.2032 -0.2286)
						)
						(arc
							(start -0.2032 -0.2286)
							(mid -0.239121 -0.213721)
							(end -0.254 -0.1778)
						)
					)
					(width 0)
					(fill yes)
				)
			)
		)
	)
	(footprint ""
		(layer "B.Cu")
		(at 97.79 -38.735 90)
		(property "Reference" "C186"
			(at 0 0 90)
			(layer "B.SilkS")
			(hide yes)
			(effects
				(font
					(size 1.27 1.27)
				)
				(justify mirror)
			)
		)
		(property "Value" "SC1U10V2KX-1GP"
			(at -1.1811 -2.7051 90)
			(unlocked yes)
			(layer "B.Fab")
			(hide yes)
			(effects
				(font
					(size 1.016 1.016)
					(thickness 0.1524)
				)
				(justify mirror)
			)
		)
		(property "Device Type" "C402H22"
			(at -1.1811 -4.2291 90)
			(unlocked yes)
			(layer "B.Fab")
			(hide yes)
			(effects
				(font
					(size 1.016 1.016)
					(thickness 0.1524)
				)
				(justify mirror)
			)
		)
		(duplicate_pad_numbers_are_jumpers no)
		(fp_rect
			(start 0.381 0.7366)
			(end -0.381 -0.7366)
			(stroke
				(width 0)
				(type default)
			)
			(fill no)
			(layer "B.CrtYd")
		)
		(fp_rect
			(start 0.381 0.7366)
			(end -0.381 -0.7366)
			(stroke
				(width 0)
				(type default)
			)
			(fill no)
			(layer "B.Fab")
		)
		(pad "1" smd custom
			(at 0 -0.4572 270)
			(size 0.1143 0.1143)
			(layers "B.Cu" "B.Mask" "B.Paste")
			(net "P1V1")
			(options
				(clearance outline)
				(anchor circle)
			)
			(primitives
				(gr_poly
					(pts
						(arc
							(start -0.254 0.1778)
							(mid -0.239121 0.213721)
							(end -0.2032 0.2286)
						)
						(arc
							(start 0.2032 0.2286)
							(mid 0.239121 0.213721)
							(end 0.254 0.1778)
						)
						(arc
							(start 0.254 -0.1778)
							(mid 0.239121 -0.213721)
							(end 0.2032 -0.2286)
						)
						(arc
							(start -0.2032 -0.2286)
							(mid -0.239121 -0.213721)
							(end -0.254 -0.1778)
						)
					)
					(width 0)
					(fill yes)
				)
			)
		)
		(pad "2" smd custom
			(at 0 0.4572 270)
			(size 0.1143 0.1143)
			(layers "B.Cu" "B.Mask" "B.Paste")
			(net "GND")
			(options
				(clearance outline)
				(anchor circle)
			)
			(primitives
				(gr_poly
					(pts
						(arc
							(start -0.254 0.1778)
							(mid -0.239121 0.213721)
							(end -0.2032 0.2286)
						)
						(arc
							(start 0.2032 0.2286)
							(mid 0.239121 0.213721)
							(end 0.254 0.1778)
						)
						(arc
							(start 0.254 -0.1778)
							(mid 0.239121 -0.213721)
							(end 0.2032 -0.2286)
						)
						(arc
							(start -0.2032 -0.2286)
							(mid -0.239121 -0.213721)
							(end -0.254 -0.1778)
						)
					)
					(width 0)
					(fill yes)
				)
			)
		)
	)
	(footprint ""
		(layer "B.Cu")
		(at 98.933 -52.705 -90)
		(property "Reference" "R281"
			(at 0 0 90)
			(layer "B.SilkS")
			(hide yes)
			(effects
				(font
					(size 1.27 1.27)
				)
				(justify mirror)
			)
		)
		(property "Value" "100R2F-L1-GP-U"
			(at -0.064008 -3.993896 270)
			(unlocked yes)
			(layer "B.Fab")
			(hide yes)
			(effects
				(font
					(size 1.016 1.016)
					(thickness 0.1524)
				)
				(justify mirror)
			)
		)
		(property "Device Type" "R402H14"
			(at -0.064008 -5.517896 270)
			(unlocked yes)
			(layer "B.Fab")
			(hide yes)
			(effects
				(font
					(size 1.016 1.016)
					(thickness 0.1524)
				)
				(justify mirror)
			)
		)
		(duplicate_pad_numbers_are_jumpers no)
		(fp_rect
			(start 0.381 0.8382)
			(end -0.381 -0.8382)
			(stroke
				(width 0)
				(type default)
			)
			(fill no)
			(layer "B.CrtYd")
		)
		(fp_rect
			(start 0.381 0.8382)
			(end -0.381 -0.8382)
			(stroke
				(width 0)
				(type default)
			)
			(fill no)
			(layer "B.Fab")
		)
		(pad "1" smd custom
			(at 0 -0.4318 90)
			(size 0.127 0.127)
			(layers "B.Cu" "B.Mask" "B.Paste")
			(net "M_A_VREF")
			(options
				(clearance outline)
				(anchor circle)
			)
			(primitives
				(gr_poly
					(pts
						(arc
							(start -0.2032 0.2794)
							(mid -0.239121 0.264521)
							(end -0.254 0.2286)
						)
						(arc
							(start -0.254 -0.2286)
							(mid -0.239121 -0.264521)
							(end -0.2032 -0.2794)
						)
						(arc
							(start 0.2032 -0.2794)
							(mid 0.239121 -0.264521)
							(end 0.254 -0.2286)
						)
						(arc
							(start 0.254 0.2286)
							(mid 0.239121 0.264521)
							(end 0.2032 0.2794)
						)
					)
					(width 0)
					(fill yes)
				)
			)
		)
		(pad "2" smd custom
			(at 0 0.4318 90)
			(size 0.127 0.127)
			(layers "B.Cu" "B.Mask" "B.Paste")
			(net "GND")
			(options
				(clearance outline)
				(anchor circle)
			)
			(primitives
				(gr_poly
					(pts
						(arc
							(start -0.2032 0.2794)
							(mid -0.239121 0.264521)
							(end -0.254 0.2286)
						)
						(arc
							(start -0.254 -0.2286)
							(mid -0.239121 -0.264521)
							(end -0.2032 -0.2794)
						)
						(arc
							(start 0.2032 -0.2794)
							(mid 0.239121 -0.264521)
							(end 0.254 -0.2286)
						)
						(arc
							(start 0.254 0.2286)
							(mid 0.239121 0.264521)
							(end 0.2032 0.2794)
						)
					)
					(width 0)
					(fill yes)
				)
			)
		)
	)
	(footprint ""
		(layer "B.Cu")
		(at 42.6466 -27.5336 180)
		(property "Reference" "R327"
			(at 0 0 0)
			(layer "B.SilkS")
			(hide yes)
			(effects
				(font
					(size 1.27 1.27)
				)
				(justify mirror)
			)
		)
		(property "Value" "33R2F-3-GP"
			(at -0.064008 -3.993896 180)
			(unlocked yes)
			(layer "B.Fab")
			(hide yes)
			(effects
				(font
					(size 1.016 1.016)
					(thickness 0.1524)
				)
				(justify mirror)
			)
		)
		(property "Device Type" "R402H16"
			(at -0.064008 -5.517896 180)
			(unlocked yes)
			(layer "B.Fab")
			(hide yes)
			(effects
				(font
					(size 1.016 1.016)
					(thickness 0.1524)
				)
				(justify mirror)
			)
		)
		(duplicate_pad_numbers_are_jumpers no)
		(fp_rect
			(start 0.381 0.8382)
			(end -0.381 -0.8382)
			(stroke
				(width 0)
				(type default)
			)
			(fill no)
			(layer "B.CrtYd")
		)
		(fp_rect
			(start 0.381 0.8382)
			(end -0.381 -0.8382)
			(stroke
				(width 0)
				(type default)
			)
			(fill no)
			(layer "B.Fab")
		)
		(pad "1" smd custom
			(at 0 -0.4318)
			(size 0.127 0.127)
			(layers "B.Cu" "B.Mask" "B.Paste")
			(net "CLK_100M_CLKBUFF_PCIE_R_DP")
			(options
				(clearance outline)
				(anchor circle)
			)
			(primitives
				(gr_poly
					(pts
						(arc
							(start -0.2032 0.2794)
							(mid -0.239121 0.264521)
							(end -0.254 0.2286)
						)
						(arc
							(start -0.254 -0.2286)
							(mid -0.239121 -0.264521)
							(end -0.2032 -0.2794)
						)
						(arc
							(start 0.2032 -0.2794)
							(mid 0.239121 -0.264521)
							(end 0.254 -0.2286)
						)
						(arc
							(start 0.254 0.2286)
							(mid 0.239121 0.264521)
							(end 0.2032 0.2794)
						)
					)
					(width 0)
					(fill yes)
				)
			)
		)
		(pad "2" smd custom
			(at 0 0.4318)
			(size 0.127 0.127)
			(layers "B.Cu" "B.Mask" "B.Paste")
			(net "CLK_100M_CLKBUFF_PCIE_DP")
			(options
				(clearance outline)
				(anchor circle)
			)
			(primitives
				(gr_poly
					(pts
						(arc
							(start -0.2032 0.2794)
							(mid -0.239121 0.264521)
							(end -0.254 0.2286)
						)
						(arc
							(start -0.254 -0.2286)
							(mid -0.239121 -0.264521)
							(end -0.2032 -0.2794)
						)
						(arc
							(start 0.2032 -0.2794)
							(mid 0.239121 -0.264521)
							(end 0.254 -0.2286)
						)
						(arc
							(start 0.254 0.2286)
							(mid 0.239121 0.264521)
							(end 0.2032 0.2794)
						)
					)
					(width 0)
					(fill yes)
				)
			)
		)
	)
	(footprint ""
		(layer "B.Cu")
		(at 39.878 -51.943 180)
		(property "Reference" "C67"
			(at 0 0 0)
			(layer "B.SilkS")
			(hide yes)
			(effects
				(font
					(size 1.27 1.27)
				)
				(justify mirror)
			)
		)
		(property "Value" "SC10U6D3V3MX-GP"
			(at 0.0254 -2.0193 180)
			(unlocked yes)
			(layer "B.Fab")
			(hide yes)
			(effects
				(font
					(size 1.016 1.016)
					(thickness 0.1524)
				)
				(justify mirror)
			)
		)
		(property "Device Type" "C603H38"
			(at 0.0254 -3.5433 180)
			(unlocked yes)
			(layer "B.Fab")
			(hide yes)
			(effects
				(font
					(size 1.016 1.016)
					(thickness 0.1524)
				)
				(justify mirror)
			)
		)
		(duplicate_pad_numbers_are_jumpers no)
		(fp_line
			(start 0.4064 0)
			(end -0.4064 0)
			(stroke
				(width 0.2286)
				(type default)
			)
			(layer "B.SilkS")
		)
		(fp_rect
			(start 0.635 1.1811)
			(end -0.635 -1.1811)
			(stroke
				(width 0)
				(type default)
			)
			(fill no)
			(layer "B.CrtYd")
		)
		(fp_rect
			(start 0.635 1.1811)
			(end -0.635 -1.1811)
			(stroke
				(width 0)
				(type default)
			)
			(fill no)
			(layer "B.Fab")
		)
		(pad "1" smd custom
			(at 0 -0.6604)
			(size 0.19685 0.19685)
			(layers "B.Cu" "B.Mask" "B.Paste")
			(net "P3V3_CLK_PCI")
			(options
				(clearance outline)
				(anchor circle)
			)
			(primitives
				(gr_poly
					(pts
						(arc
							(start 0.508 0.2921)
							(mid 0.478242 0.363942)
							(end 0.4064 0.3937)
						)
						(arc
							(start -0.4064 0.3937)
							(mid -0.478242 0.363942)
							(end -0.508 0.2921)
						)
						(arc
							(start -0.508 -0.2921)
							(mid -0.478242 -0.363942)
							(end -0.4064 -0.3937)
						)
						(arc
							(start 0.4064 -0.3937)
							(mid 0.478242 -0.363942)
							(end 0.508 -0.2921)
						)
					)
					(width 0)
					(fill yes)
				)
			)
		)
		(pad "2" smd custom
			(at 0 0.6604)
			(size 0.19685 0.19685)
			(layers "B.Cu" "B.Mask" "B.Paste")
			(net "GND")
			(options
				(clearance outline)
				(anchor circle)
			)
			(primitives
				(gr_poly
					(pts
						(arc
							(start 0.508 0.2921)
							(mid 0.478242 0.363942)
							(end 0.4064 0.3937)
						)
						(arc
							(start -0.4064 0.3937)
							(mid -0.478242 0.363942)
							(end -0.508 0.2921)
						)
						(arc
							(start -0.508 -0.2921)
							(mid -0.478242 -0.363942)
							(end -0.4064 -0.3937)
						)
						(arc
							(start 0.4064 -0.3937)
							(mid 0.478242 -0.363942)
							(end 0.508 -0.2921)
						)
					)
					(width 0)
					(fill yes)
				)
			)
		)
	)
	(footprint ""
		(layer "B.Cu")
		(at 94.361 -52.197)
		(property "Reference" "L5"
			(at 0 0 0)
			(layer "B.SilkS")
			(hide yes)
			(effects
				(font
					(size 1.27 1.27)
				)
				(justify mirror)
			)
		)
		(property "Value" "BLM18PG121SN1D-GP"
			(at 0.0254 -2.8956 0)
			(unlocked yes)
			(layer "B.Fab")
			(hide yes)
			(effects
				(font
					(size 1.016 1.016)
					(thickness 0.1524)
				)
				(justify mirror)
			)
		)
		(property "Device Type" "L1608-UH38"
			(at 0.0254 -4.4196 0)
			(unlocked yes)
			(layer "B.Fab")
			(hide yes)
			(effects
				(font
					(size 1.016 1.016)
					(thickness 0.1524)
				)
				(justify mirror)
			)
		)
		(duplicate_pad_numbers_are_jumpers no)
		(fp_line
			(start 0.4064 0)
			(end -0.4064 0)
			(stroke
				(width 0.2032)
				(type default)
			)
			(layer "B.SilkS")
		)
		(fp_rect
			(start 0.635 1.1811)
			(end -0.635 -1.1811)
			(stroke
				(width 0)
				(type default)
			)
			(fill no)
			(layer "B.CrtYd")
		)
		(fp_rect
			(start 0.635 1.1811)
			(end -0.635 -1.1811)
			(stroke
				(width 0)
				(type default)
			)
			(fill no)
			(layer "B.Fab")
		)
		(pad "1" smd custom
			(at 0 -0.6604 180)
			(size 0.19685 0.19685)
			(layers "B.Cu" "B.Mask" "B.Paste")
			(net "P1V0")
			(options
				(clearance outline)
				(anchor circle)
			)
			(primitives
				(gr_poly
					(pts
						(arc
							(start 0.508 0.2921)
							(mid 0.478242 0.363942)
							(end 0.4064 0.3937)
						)
						(arc
							(start -0.4064 0.3937)
							(mid -0.478242 0.363942)
							(end -0.508 0.2921)
						)
						(arc
							(start -0.508 -0.2921)
							(mid -0.478242 -0.363942)
							(end -0.4064 -0.3937)
						)
						(arc
							(start 0.4064 -0.3937)
							(mid 0.478242 -0.363942)
							(end 0.508 -0.2921)
						)
					)
					(width 0)
					(fill yes)
				)
			)
		)
		(pad "2" smd custom
			(at 0 0.6604 180)
			(size 0.19685 0.19685)
			(layers "B.Cu" "B.Mask" "B.Paste")
			(net "VCCACKDDR0")
			(options
				(clearance outline)
				(anchor circle)
			)
			(primitives
				(gr_poly
					(pts
						(arc
							(start 0.508 0.2921)
							(mid 0.478242 0.363942)
							(end 0.4064 0.3937)
						)
						(arc
							(start -0.4064 0.3937)
							(mid -0.478242 0.363942)
							(end -0.508 0.2921)
						)
						(arc
							(start -0.508 -0.2921)
							(mid -0.478242 -0.363942)
							(end -0.4064 -0.3937)
						)
						(arc
							(start 0.4064 -0.3937)
							(mid 0.478242 -0.363942)
							(end 0.508 -0.2921)
						)
					)
					(width 0)
					(fill yes)
				)
			)
		)
	)
	(footprint ""
		(layer "B.Cu")
		(at 87.122 -30.099 180)
		(property "Reference" "R366"
			(at 0 0 0)
			(layer "B.SilkS")
			(hide yes)
			(effects
				(font
					(size 1.27 1.27)
				)
				(justify mirror)
			)
		)
		(property "Value" "100R3F-1-GP"
			(at 0.0254 -2.5146 180)
			(unlocked yes)
			(layer "B.Fab")
			(hide yes)
			(effects
				(font
					(size 1.016 1.016)
					(thickness 0.1524)
				)
				(justify mirror)
			)
		)
		(property "Device Type" "R603H22"
			(at 0.0254 -4.0386 180)
			(unlocked yes)
			(layer "B.Fab")
			(hide yes)
			(effects
				(font
					(size 1.016 1.016)
					(thickness 0.1524)
				)
				(justify mirror)
			)
		)
		(duplicate_pad_numbers_are_jumpers no)
		(fp_line
			(start 0.2032 0)
			(end 0.4191 0)
			(stroke
				(width 0.2032)
				(type default)
			)
			(layer "B.SilkS")
		)
		(fp_line
			(start -0.4318 0)
			(end -0.2032 0)
			(stroke
				(width 0.2032)
				(type default)
			)
			(layer "B.SilkS")
		)
		(fp_rect
			(start 0.635 1.1811)
			(end -0.635 -1.1811)
			(stroke
				(width 0)
				(type default)
			)
			(fill no)
			(layer "B.CrtYd")
		)
		(fp_rect
			(start 0.635 1.1811)
			(end -0.635 -1.1811)
			(stroke
				(width 0)
				(type default)
			)
			(fill no)
			(layer "B.Fab")
		)
		(pad "1" smd custom
			(at 0 -0.6604)
			(size 0.19685 0.19685)
			(layers "B.Cu" "B.Mask" "B.Paste")
			(net "SATA2_OBS_P")
			(options
				(clearance outline)
				(anchor circle)
			)
			(primitives
				(gr_poly
					(pts
						(arc
							(start 0.508 0.2921)
							(mid 0.478242 0.363942)
							(end 0.4064 0.3937)
						)
						(arc
							(start -0.4064 0.3937)
							(mid -0.478242 0.363942)
							(end -0.508 0.2921)
						)
						(arc
							(start -0.508 -0.2921)
							(mid -0.478242 -0.363942)
							(end -0.4064 -0.3937)
						)
						(arc
							(start 0.4064 -0.3937)
							(mid 0.478242 -0.363942)
							(end 0.508 -0.2921)
						)
					)
					(width 0)
					(fill yes)
				)
			)
		)
		(pad "2" smd custom
			(at 0 0.6604)
			(size 0.19685 0.19685)
			(layers "B.Cu" "B.Mask" "B.Paste")
			(net "SATA2_OBS_N")
			(options
				(clearance outline)
				(anchor circle)
			)
			(primitives
				(gr_poly
					(pts
						(arc
							(start 0.508 0.2921)
							(mid 0.478242 0.363942)
							(end 0.4064 0.3937)
						)
						(arc
							(start -0.4064 0.3937)
							(mid -0.478242 0.363942)
							(end -0.508 0.2921)
						)
						(arc
							(start -0.508 -0.2921)
							(mid -0.478242 -0.363942)
							(end -0.4064 -0.3937)
						)
						(arc
							(start 0.4064 -0.3937)
							(mid 0.478242 -0.363942)
							(end 0.508 -0.2921)
						)
					)
					(width 0)
					(fill yes)
				)
			)
		)
	)
	(footprint ""
		(layer "B.Cu")
		(at 188.468 -16.383)
		(property "Reference" "PC204"
			(at 0 0 0)
			(layer "B.SilkS")
			(hide yes)
			(effects
				(font
					(size 1.27 1.27)
				)
				(justify mirror)
			)
		)
		(property "Value" "SC10U6D3V3MX-GP"
			(at 0 -2.8194 0)
			(unlocked yes)
			(layer "B.Fab")
			(hide yes)
			(effects
				(font
					(size 1.016 1.016)
					(thickness 0.1524)
				)
				(justify mirror)
			)
		)
		(property "Device Type" "C603H38"
			(at 0 -4.3434 0)
			(unlocked yes)
			(layer "B.Fab")
			(hide yes)
			(effects
				(font
					(size 1.016 1.016)
					(thickness 0.1524)
				)
				(justify mirror)
			)
		)
		(duplicate_pad_numbers_are_jumpers no)
		(fp_line
			(start 0.4064 0)
			(end -0.4064 0)
			(stroke
				(width 0.2286)
				(type default)
			)
			(layer "B.SilkS")
		)
		(fp_rect
			(start 0.635 1.1811)
			(end -0.635 -1.1811)
			(stroke
				(width 0)
				(type default)
			)
			(fill no)
			(layer "B.CrtYd")
		)
		(fp_rect
			(start 0.635 1.1811)
			(end -0.635 -1.1811)
			(stroke
				(width 0)
				(type default)
			)
			(fill no)
			(layer "B.Fab")
		)
		(pad "1" smd custom
			(at 0 -0.6604 180)
			(size 0.19685 0.19685)
			(layers "B.Cu" "B.Mask" "B.Paste")
			(net "GND")
			(options
				(clearance outline)
				(anchor circle)
			)
			(primitives
				(gr_poly
					(pts
						(arc
							(start 0.508 0.2921)
							(mid 0.478242 0.363942)
							(end 0.4064 0.3937)
						)
						(arc
							(start -0.4064 0.3937)
							(mid -0.478242 0.363942)
							(end -0.508 0.2921)
						)
						(arc
							(start -0.508 -0.2921)
							(mid -0.478242 -0.363942)
							(end -0.4064 -0.3937)
						)
						(arc
							(start 0.4064 -0.3937)
							(mid 0.478242 -0.363942)
							(end 0.508 -0.2921)
						)
					)
					(width 0)
					(fill yes)
				)
			)
		)
		(pad "2" smd custom
			(at 0 0.6604 180)
			(size 0.19685 0.19685)
			(layers "B.Cu" "B.Mask" "B.Paste")
			(net "PV_VTT_DDR_B")
			(options
				(clearance outline)
				(anchor circle)
			)
			(primitives
				(gr_poly
					(pts
						(arc
							(start 0.508 0.2921)
							(mid 0.478242 0.363942)
							(end 0.4064 0.3937)
						)
						(arc
							(start -0.4064 0.3937)
							(mid -0.478242 0.363942)
							(end -0.508 0.2921)
						)
						(arc
							(start -0.508 -0.2921)
							(mid -0.478242 -0.363942)
							(end -0.4064 -0.3937)
						)
						(arc
							(start 0.4064 -0.3937)
							(mid 0.478242 -0.363942)
							(end 0.508 -0.2921)
						)
					)
					(width 0)
					(fill yes)
				)
			)
		)
	)
	(footprint ""
		(layer "B.Cu")
		(at 87.884 -22.479 -90)
		(property "Reference" "C254"
			(at 0 0 90)
			(layer "B.SilkS")
			(hide yes)
			(effects
				(font
					(size 1.27 1.27)
				)
				(justify mirror)
			)
		)
		(property "Value" "SC1U10V2KX-1GP"
			(at -1.1811 -2.7051 270)
			(unlocked yes)
			(layer "B.Fab")
			(hide yes)
			(effects
				(font
					(size 1.016 1.016)
					(thickness 0.1524)
				)
				(justify mirror)
			)
		)
		(property "Device Type" "C402H22"
			(at -1.1811 -4.2291 270)
			(unlocked yes)
			(layer "B.Fab")
			(hide yes)
			(effects
				(font
					(size 1.016 1.016)
					(thickness 0.1524)
				)
				(justify mirror)
			)
		)
		(duplicate_pad_numbers_are_jumpers no)
		(fp_rect
			(start 0.381 0.7366)
			(end -0.381 -0.7366)
			(stroke
				(width 0)
				(type default)
			)
			(fill no)
			(layer "B.CrtYd")
		)
		(fp_rect
			(start 0.381 0.7366)
			(end -0.381 -0.7366)
			(stroke
				(width 0)
				(type default)
			)
			(fill no)
			(layer "B.Fab")
		)
		(pad "1" smd custom
			(at 0 -0.4572 90)
			(size 0.1143 0.1143)
			(layers "B.Cu" "B.Mask" "B.Paste")
			(net "P1V0")
			(options
				(clearance outline)
				(anchor circle)
			)
			(primitives
				(gr_poly
					(pts
						(arc
							(start -0.254 0.1778)
							(mid -0.239121 0.213721)
							(end -0.2032 0.2286)
						)
						(arc
							(start 0.2032 0.2286)
							(mid 0.239121 0.213721)
							(end 0.254 0.1778)
						)
						(arc
							(start 0.254 -0.1778)
							(mid 0.239121 -0.213721)
							(end 0.2032 -0.2286)
						)
						(arc
							(start -0.2032 -0.2286)
							(mid -0.239121 -0.213721)
							(end -0.254 -0.1778)
						)
					)
					(width 0)
					(fill yes)
				)
			)
		)
		(pad "2" smd custom
			(at 0 0.4572 90)
			(size 0.1143 0.1143)
			(layers "B.Cu" "B.Mask" "B.Paste")
			(net "GND")
			(options
				(clearance outline)
				(anchor circle)
			)
			(primitives
				(gr_poly
					(pts
						(arc
							(start -0.254 0.1778)
							(mid -0.239121 0.213721)
							(end -0.2032 0.2286)
						)
						(arc
							(start 0.2032 0.2286)
							(mid 0.239121 0.213721)
							(end 0.254 0.1778)
						)
						(arc
							(start 0.254 -0.1778)
							(mid 0.239121 -0.213721)
							(end 0.2032 -0.2286)
						)
						(arc
							(start -0.2032 -0.2286)
							(mid -0.239121 -0.213721)
							(end -0.254 -0.1778)
						)
					)
					(width 0)
					(fill yes)
				)
			)
		)
	)
	(footprint ""
		(layer "B.Cu")
		(at 197.993 -41.148 -90)
		(property "Reference" "R153"
			(at 0 0 90)
			(layer "B.SilkS")
			(hide yes)
			(effects
				(font
					(size 1.27 1.27)
				)
				(justify mirror)
			)
		)
		(property "Value" "300R2F-GP"
			(at -0.064008 -3.993896 270)
			(unlocked yes)
			(layer "B.Fab")
			(hide yes)
			(effects
				(font
					(size 1.016 1.016)
					(thickness 0.1524)
				)
				(justify mirror)
			)
		)
		(property "Device Type" "R402H16"
			(at -0.064008 -5.517896 270)
			(unlocked yes)
			(layer "B.Fab")
			(hide yes)
			(effects
				(font
					(size 1.016 1.016)
					(thickness 0.1524)
				)
				(justify mirror)
			)
		)
		(duplicate_pad_numbers_are_jumpers no)
		(fp_rect
			(start 0.381 0.8382)
			(end -0.381 -0.8382)
			(stroke
				(width 0)
				(type default)
			)
			(fill no)
			(layer "B.CrtYd")
		)
		(fp_rect
			(start 0.381 0.8382)
			(end -0.381 -0.8382)
			(stroke
				(width 0)
				(type default)
			)
			(fill no)
			(layer "B.Fab")
		)
		(pad "1" smd custom
			(at 0 -0.4318 90)
			(size 0.127 0.127)
			(layers "B.Cu" "B.Mask" "B.Paste")
			(net "PORT80_R_BIT4")
			(options
				(clearance outline)
				(anchor circle)
			)
			(primitives
				(gr_poly
					(pts
						(arc
							(start -0.2032 0.2794)
							(mid -0.239121 0.264521)
							(end -0.254 0.2286)
						)
						(arc
							(start -0.254 -0.2286)
							(mid -0.239121 -0.264521)
							(end -0.2032 -0.2794)
						)
						(arc
							(start 0.2032 -0.2794)
							(mid 0.239121 -0.264521)
							(end 0.254 -0.2286)
						)
						(arc
							(start 0.254 0.2286)
							(mid 0.239121 0.264521)
							(end 0.2032 0.2794)
						)
					)
					(width 0)
					(fill yes)
				)
			)
		)
		(pad "2" smd custom
			(at 0 0.4318 90)
			(size 0.127 0.127)
			(layers "B.Cu" "B.Mask" "B.Paste")
			(net "P3V3_STBY")
			(options
				(clearance outline)
				(anchor circle)
			)
			(primitives
				(gr_poly
					(pts
						(arc
							(start -0.2032 0.2794)
							(mid -0.239121 0.264521)
							(end -0.254 0.2286)
						)
						(arc
							(start -0.254 -0.2286)
							(mid -0.239121 -0.264521)
							(end -0.2032 -0.2794)
						)
						(arc
							(start 0.2032 -0.2794)
							(mid 0.239121 -0.264521)
							(end 0.254 -0.2286)
						)
						(arc
							(start 0.254 0.2286)
							(mid 0.239121 0.264521)
							(end 0.2032 0.2794)
						)
					)
					(width 0)
					(fill yes)
				)
			)
		)
	)
	(footprint ""
		(layer "B.Cu")
		(at 100.584 -51.308 180)
		(property "Reference" "R258"
			(at 0 0 0)
			(layer "B.SilkS")
			(hide yes)
			(effects
				(font
					(size 1.27 1.27)
				)
				(justify mirror)
			)
		)
		(property "Value" "1KR2F-3-GP"
			(at -0.064008 -3.993896 180)
			(unlocked yes)
			(layer "B.Fab")
			(hide yes)
			(effects
				(font
					(size 1.016 1.016)
					(thickness 0.1524)
				)
				(justify mirror)
			)
		)
		(property "Device Type" "R402H16"
			(at -0.064008 -5.517896 180)
			(unlocked yes)
			(layer "B.Fab")
			(hide yes)
			(effects
				(font
					(size 1.016 1.016)
					(thickness 0.1524)
				)
				(justify mirror)
			)
		)
		(duplicate_pad_numbers_are_jumpers no)
		(fp_rect
			(start 0.381 0.8382)
			(end -0.381 -0.8382)
			(stroke
				(width 0)
				(type default)
			)
			(fill no)
			(layer "B.CrtYd")
		)
		(fp_rect
			(start 0.381 0.8382)
			(end -0.381 -0.8382)
			(stroke
				(width 0)
				(type default)
			)
			(fill no)
			(layer "B.Fab")
		)
		(pad "1" smd custom
			(at 0 -0.4318)
			(size 0.127 0.127)
			(layers "B.Cu" "B.Mask" "B.Paste")
			(net "PV_VDDR")
			(options
				(clearance outline)
				(anchor circle)
			)
			(primitives
				(gr_poly
					(pts
						(arc
							(start -0.2032 0.2794)
							(mid -0.239121 0.264521)
							(end -0.254 0.2286)
						)
						(arc
							(start -0.254 -0.2286)
							(mid -0.239121 -0.264521)
							(end -0.2032 -0.2794)
						)
						(arc
							(start 0.2032 -0.2794)
							(mid 0.239121 -0.264521)
							(end 0.254 -0.2286)
						)
						(arc
							(start 0.254 0.2286)
							(mid 0.239121 0.264521)
							(end 0.2032 0.2794)
						)
					)
					(width 0)
					(fill yes)
				)
			)
		)
		(pad "2" smd custom
			(at 0 0.4318)
			(size 0.127 0.127)
			(layers "B.Cu" "B.Mask" "B.Paste")
			(net "M_A_RESET#")
			(options
				(clearance outline)
				(anchor circle)
			)
			(primitives
				(gr_poly
					(pts
						(arc
							(start -0.2032 0.2794)
							(mid -0.239121 0.264521)
							(end -0.254 0.2286)
						)
						(arc
							(start -0.254 -0.2286)
							(mid -0.239121 -0.264521)
							(end -0.2032 -0.2794)
						)
						(arc
							(start 0.2032 -0.2794)
							(mid 0.239121 -0.264521)
							(end 0.254 -0.2286)
						)
						(arc
							(start 0.254 0.2286)
							(mid 0.239121 0.264521)
							(end 0.2032 0.2794)
						)
					)
					(width 0)
					(fill yes)
				)
			)
		)
	)
	(footprint ""
		(layer "B.Cu")
		(at 95.9358 -38.6842 -90)
		(property "Reference" "TP29"
			(at 0 0 90)
			(layer "B.SilkS")
			(hide yes)
			(effects
				(font
					(size 1.27 1.27)
				)
				(justify mirror)
			)
		)
		(property "Value" "TPAD24"
			(at 0 -2.9972 270)
			(unlocked yes)
			(layer "B.Fab")
			(hide yes)
			(effects
				(font
					(size 1.016 1.016)
					(thickness 0.1524)
				)
				(justify mirror)
			)
		)
		(property "Device Type" "TPAD24"
			(at 0 -4.5212 270)
			(unlocked yes)
			(layer "B.Fab")
			(hide yes)
			(effects
				(font
					(size 1.016 1.016)
					(thickness 0.1524)
				)
				(justify mirror)
			)
		)
		(duplicate_pad_numbers_are_jumpers no)
		(fp_poly
			(pts
				(arc
					(start 0 -0.3048)
					(mid 0 0.3048)
					(end 0 -0.3048)
				)
			)
			(stroke
				(width 0)
				(type default)
			)
			(fill no)
			(layer "B.CrtYd")
		)
		(fp_poly
			(pts
				(arc
					(start 0 -0.6096)
					(mid 0 0.6096)
					(end 0 -0.6096)
				)
			)
			(stroke
				(width 0)
				(type default)
			)
			(fill no)
			(layer "B.Fab")
		)
		(pad "1" smd circle
			(at 0 0 90)
			(size 0.6096 0.6096)
			(layers "B.Cu" "B.Mask" "B.Paste")
			(net "TP_CPU_RSVD9")
		)
	)
	(footprint ""
		(layer "B.Cu")
		(at 100.29698 -50.064162 -90)
		(property "Reference" "R287"
			(at 0 0 90)
			(layer "B.SilkS")
			(hide yes)
			(effects
				(font
					(size 1.27 1.27)
				)
				(justify mirror)
			)
		)
		(property "Value" "100R2F-L1-GP-U"
			(at -0.064008 -3.993896 270)
			(unlocked yes)
			(layer "B.Fab")
			(hide yes)
			(effects
				(font
					(size 1.016 1.016)
					(thickness 0.1524)
				)
				(justify mirror)
			)
		)
		(property "Device Type" "R402H14"
			(at -0.064008 -5.517896 270)
			(unlocked yes)
			(layer "B.Fab")
			(hide yes)
			(effects
				(font
					(size 1.016 1.016)
					(thickness 0.1524)
				)
				(justify mirror)
			)
		)
		(duplicate_pad_numbers_are_jumpers no)
		(fp_rect
			(start 0.381 0.8382)
			(end -0.381 -0.8382)
			(stroke
				(width 0)
				(type default)
			)
			(fill no)
			(layer "B.CrtYd")
		)
		(fp_rect
			(start 0.381 0.8382)
			(end -0.381 -0.8382)
			(stroke
				(width 0)
				(type default)
			)
			(fill no)
			(layer "B.Fab")
		)
		(pad "1" smd custom
			(at 0 -0.4318 90)
			(size 0.127 0.127)
			(layers "B.Cu" "B.Mask" "B.Paste")
			(net "PV_VDDR")
			(options
				(clearance outline)
				(anchor circle)
			)
			(primitives
				(gr_poly
					(pts
						(arc
							(start -0.2032 0.2794)
							(mid -0.239121 0.264521)
							(end -0.254 0.2286)
						)
						(arc
							(start -0.254 -0.2286)
							(mid -0.239121 -0.264521)
							(end -0.2032 -0.2794)
						)
						(arc
							(start 0.2032 -0.2794)
							(mid 0.239121 -0.264521)
							(end 0.254 -0.2286)
						)
						(arc
							(start 0.254 0.2286)
							(mid 0.239121 0.264521)
							(end 0.2032 0.2794)
						)
					)
					(width 0)
					(fill yes)
				)
			)
		)
		(pad "2" smd custom
			(at 0 0.4318 90)
			(size 0.127 0.127)
			(layers "B.Cu" "B.Mask" "B.Paste")
			(net "M_A_VREF")
			(options
				(clearance outline)
				(anchor circle)
			)
			(primitives
				(gr_poly
					(pts
						(arc
							(start -0.2032 0.2794)
							(mid -0.239121 0.264521)
							(end -0.254 0.2286)
						)
						(arc
							(start -0.254 -0.2286)
							(mid -0.239121 -0.264521)
							(end -0.2032 -0.2794)
						)
						(arc
							(start 0.2032 -0.2794)
							(mid 0.239121 -0.264521)
							(end 0.254 -0.2286)
						)
						(arc
							(start 0.254 0.2286)
							(mid 0.239121 0.264521)
							(end 0.2032 0.2794)
						)
					)
					(width 0)
					(fill yes)
				)
			)
		)
	)
	(footprint ""
		(layer "B.Cu")
		(at 30.734 -53.594 180)
		(property "Reference" "PR177"
			(at 0 0 0)
			(layer "B.SilkS")
			(hide yes)
			(effects
				(font
					(size 1.27 1.27)
				)
				(justify mirror)
			)
		)
		(property "Value" "10KR2F-2-GP"
			(at -1.7907 -1.1176 180)
			(unlocked yes)
			(layer "B.Fab")
			(hide yes)
			(effects
				(font
					(size 1.016 1.016)
					(thickness 0.1524)
				)
				(justify mirror)
			)
		)
		(property "Device Type" "R402H16"
			(at -1.7907 -2.6416 180)
			(unlocked yes)
			(layer "B.Fab")
			(hide yes)
			(effects
				(font
					(size 1.016 1.016)
					(thickness 0.1524)
				)
				(justify mirror)
			)
		)
		(duplicate_pad_numbers_are_jumpers no)
		(fp_rect
			(start 0.381 0.8382)
			(end -0.381 -0.8382)
			(stroke
				(width 0)
				(type default)
			)
			(fill no)
			(layer "B.CrtYd")
		)
		(fp_rect
			(start 0.381 0.8382)
			(end -0.381 -0.8382)
			(stroke
				(width 0)
				(type default)
			)
			(fill no)
			(layer "B.Fab")
		)
		(pad "1" smd custom
			(at 0 -0.4318)
			(size 0.127 0.127)
			(layers "B.Cu" "B.Mask" "B.Paste")
			(net "P1V5_STBY_PG")
			(options
				(clearance outline)
				(anchor circle)
			)
			(primitives
				(gr_poly
					(pts
						(arc
							(start -0.2032 0.2794)
							(mid -0.239121 0.264521)
							(end -0.254 0.2286)
						)
						(arc
							(start -0.254 -0.2286)
							(mid -0.239121 -0.264521)
							(end -0.2032 -0.2794)
						)
						(arc
							(start 0.2032 -0.2794)
							(mid 0.239121 -0.264521)
							(end 0.254 -0.2286)
						)
						(arc
							(start 0.254 0.2286)
							(mid 0.239121 0.264521)
							(end 0.2032 0.2794)
						)
					)
					(width 0)
					(fill yes)
				)
			)
		)
		(pad "2" smd custom
			(at 0 0.4318)
			(size 0.127 0.127)
			(layers "B.Cu" "B.Mask" "B.Paste")
			(net "P3V3_STBY")
			(options
				(clearance outline)
				(anchor circle)
			)
			(primitives
				(gr_poly
					(pts
						(arc
							(start -0.2032 0.2794)
							(mid -0.239121 0.264521)
							(end -0.254 0.2286)
						)
						(arc
							(start -0.254 -0.2286)
							(mid -0.239121 -0.264521)
							(end -0.2032 -0.2794)
						)
						(arc
							(start 0.2032 -0.2794)
							(mid 0.239121 -0.264521)
							(end 0.254 -0.2286)
						)
						(arc
							(start 0.254 0.2286)
							(mid 0.239121 0.264521)
							(end 0.2032 0.2794)
						)
					)
					(width 0)
					(fill yes)
				)
			)
		)
	)
	(footprint ""
		(layer "B.Cu")
		(at 161.6964 -12.447778 180)
		(property "Reference" "C333"
			(at 0 0 0)
			(layer "B.SilkS")
			(hide yes)
			(effects
				(font
					(size 1.27 1.27)
				)
				(justify mirror)
			)
		)
		(property "Value" "SCD1U16V2KX-3GP"
			(at -1.8923 -1.2065 180)
			(unlocked yes)
			(layer "B.Fab")
			(hide yes)
			(effects
				(font
					(size 1.016 1.016)
					(thickness 0.1524)
				)
				(justify mirror)
			)
		)
		(property "Device Type" "C402H22"
			(at -1.8923 -2.7305 180)
			(unlocked yes)
			(layer "B.Fab")
			(hide yes)
			(effects
				(font
					(size 1.016 1.016)
					(thickness 0.1524)
				)
				(justify mirror)
			)
		)
		(duplicate_pad_numbers_are_jumpers no)
		(fp_rect
			(start 0.381 0.7366)
			(end -0.381 -0.7366)
			(stroke
				(width 0)
				(type default)
			)
			(fill no)
			(layer "B.CrtYd")
		)
		(fp_rect
			(start 0.381 0.7366)
			(end -0.381 -0.7366)
			(stroke
				(width 0)
				(type default)
			)
			(fill no)
			(layer "B.Fab")
		)
		(pad "1" smd custom
			(at 0 -0.4572)
			(size 0.1143 0.1143)
			(layers "B.Cu" "B.Mask" "B.Paste")
			(net "PV_VDDR")
			(options
				(clearance outline)
				(anchor circle)
			)
			(primitives
				(gr_poly
					(pts
						(arc
							(start -0.254 0.1778)
							(mid -0.239121 0.213721)
							(end -0.2032 0.2286)
						)
						(arc
							(start 0.2032 0.2286)
							(mid 0.239121 0.213721)
							(end 0.254 0.1778)
						)
						(arc
							(start 0.254 -0.1778)
							(mid 0.239121 -0.213721)
							(end 0.2032 -0.2286)
						)
						(arc
							(start -0.2032 -0.2286)
							(mid -0.239121 -0.213721)
							(end -0.254 -0.1778)
						)
					)
					(width 0)
					(fill yes)
				)
			)
		)
		(pad "2" smd custom
			(at 0 0.4572)
			(size 0.1143 0.1143)
			(layers "B.Cu" "B.Mask" "B.Paste")
			(net "GND")
			(options
				(clearance outline)
				(anchor circle)
			)
			(primitives
				(gr_poly
					(pts
						(arc
							(start -0.254 0.1778)
							(mid -0.239121 0.213721)
							(end -0.2032 0.2286)
						)
						(arc
							(start 0.2032 0.2286)
							(mid 0.239121 0.213721)
							(end 0.254 0.1778)
						)
						(arc
							(start 0.254 -0.1778)
							(mid 0.239121 -0.213721)
							(end 0.2032 -0.2286)
						)
						(arc
							(start -0.2032 -0.2286)
							(mid -0.239121 -0.213721)
							(end -0.254 -0.1778)
						)
					)
					(width 0)
					(fill yes)
				)
			)
		)
	)
	(footprint ""
		(layer "B.Cu")
		(at 104.775 -52.832 90)
		(property "Reference" "C141"
			(at 0 0 90)
			(layer "B.SilkS")
			(hide yes)
			(effects
				(font
					(size 1.27 1.27)
				)
				(justify mirror)
			)
		)
		(property "Value" "SC33P50V2JN-3GP"
			(at -1.1811 -2.7051 90)
			(unlocked yes)
			(layer "B.Fab")
			(hide yes)
			(effects
				(font
					(size 1.016 1.016)
					(thickness 0.1524)
				)
				(justify mirror)
			)
		)
		(property "Device Type" "C402H22"
			(at -1.1811 -4.2291 90)
			(unlocked yes)
			(layer "B.Fab")
			(hide yes)
			(effects
				(font
					(size 1.016 1.016)
					(thickness 0.1524)
				)
				(justify mirror)
			)
		)
		(duplicate_pad_numbers_are_jumpers no)
		(fp_rect
			(start 0.381 0.7366)
			(end -0.381 -0.7366)
			(stroke
				(width 0)
				(type default)
			)
			(fill no)
			(layer "B.CrtYd")
		)
		(fp_rect
			(start 0.381 0.7366)
			(end -0.381 -0.7366)
			(stroke
				(width 0)
				(type default)
			)
			(fill no)
			(layer "B.Fab")
		)
		(pad "1" smd custom
			(at 0 -0.4572 270)
			(size 0.1143 0.1143)
			(layers "B.Cu" "B.Mask" "B.Paste")
			(net "PWRGD_DDR3_VCCA")
			(options
				(clearance outline)
				(anchor circle)
			)
			(primitives
				(gr_poly
					(pts
						(arc
							(start -0.254 0.1778)
							(mid -0.239121 0.213721)
							(end -0.2032 0.2286)
						)
						(arc
							(start 0.2032 0.2286)
							(mid 0.239121 0.213721)
							(end 0.254 0.1778)
						)
						(arc
							(start 0.254 -0.1778)
							(mid 0.239121 -0.213721)
							(end 0.2032 -0.2286)
						)
						(arc
							(start -0.2032 -0.2286)
							(mid -0.239121 -0.213721)
							(end -0.254 -0.1778)
						)
					)
					(width 0)
					(fill yes)
				)
			)
		)
		(pad "2" smd custom
			(at 0 0.4572 270)
			(size 0.1143 0.1143)
			(layers "B.Cu" "B.Mask" "B.Paste")
			(net "GND")
			(options
				(clearance outline)
				(anchor circle)
			)
			(primitives
				(gr_poly
					(pts
						(arc
							(start -0.254 0.1778)
							(mid -0.239121 0.213721)
							(end -0.2032 0.2286)
						)
						(arc
							(start 0.2032 0.2286)
							(mid 0.239121 0.213721)
							(end 0.254 0.1778)
						)
						(arc
							(start 0.254 -0.1778)
							(mid 0.239121 -0.213721)
							(end 0.2032 -0.2286)
						)
						(arc
							(start -0.2032 -0.2286)
							(mid -0.239121 -0.213721)
							(end -0.254 -0.1778)
						)
					)
					(width 0)
					(fill yes)
				)
			)
		)
	)
	(footprint ""
		(layer "B.Cu")
		(at 71.0946 -38.9128 90)
		(property "Reference" "C15"
			(at 0 0 90)
			(layer "B.SilkS")
			(hide yes)
			(effects
				(font
					(size 1.27 1.27)
				)
				(justify mirror)
			)
		)
		(property "Value" "SCD1U10V2KX-5GP"
			(at -1.1811 -2.7051 90)
			(unlocked yes)
			(layer "B.Fab")
			(hide yes)
			(effects
				(font
					(size 1.016 1.016)
					(thickness 0.1524)
				)
				(justify mirror)
			)
		)
		(property "Device Type" "C402H22"
			(at -1.1811 -4.2291 90)
			(unlocked yes)
			(layer "B.Fab")
			(hide yes)
			(effects
				(font
					(size 1.016 1.016)
					(thickness 0.1524)
				)
				(justify mirror)
			)
		)
		(duplicate_pad_numbers_are_jumpers no)
		(fp_rect
			(start 0.381 0.7366)
			(end -0.381 -0.7366)
			(stroke
				(width 0)
				(type default)
			)
			(fill no)
			(layer "B.CrtYd")
		)
		(fp_rect
			(start 0.381 0.7366)
			(end -0.381 -0.7366)
			(stroke
				(width 0)
				(type default)
			)
			(fill no)
			(layer "B.Fab")
		)
		(pad "1" smd custom
			(at 0 -0.4572 270)
			(size 0.1143 0.1143)
			(layers "B.Cu" "B.Mask" "B.Paste")
			(net "P3V3_STBY")
			(options
				(clearance outline)
				(anchor circle)
			)
			(primitives
				(gr_poly
					(pts
						(arc
							(start -0.254 0.1778)
							(mid -0.239121 0.213721)
							(end -0.2032 0.2286)
						)
						(arc
							(start 0.2032 0.2286)
							(mid 0.239121 0.213721)
							(end 0.254 0.1778)
						)
						(arc
							(start 0.254 -0.1778)
							(mid 0.239121 -0.213721)
							(end 0.2032 -0.2286)
						)
						(arc
							(start -0.2032 -0.2286)
							(mid -0.239121 -0.213721)
							(end -0.254 -0.1778)
						)
					)
					(width 0)
					(fill yes)
				)
			)
		)
		(pad "2" smd custom
			(at 0 0.4572 270)
			(size 0.1143 0.1143)
			(layers "B.Cu" "B.Mask" "B.Paste")
			(net "GND")
			(options
				(clearance outline)
				(anchor circle)
			)
			(primitives
				(gr_poly
					(pts
						(arc
							(start -0.254 0.1778)
							(mid -0.239121 0.213721)
							(end -0.2032 0.2286)
						)
						(arc
							(start 0.2032 0.2286)
							(mid 0.239121 0.213721)
							(end 0.254 0.1778)
						)
						(arc
							(start 0.254 -0.1778)
							(mid 0.239121 -0.213721)
							(end 0.2032 -0.2286)
						)
						(arc
							(start -0.2032 -0.2286)
							(mid -0.239121 -0.213721)
							(end -0.254 -0.1778)
						)
					)
					(width 0)
					(fill yes)
				)
			)
		)
	)
	(footprint ""
		(layer "B.Cu")
		(at 74.041 -30.226 90)
		(property "Reference" "R122"
			(at 0 0 90)
			(layer "B.SilkS")
			(hide yes)
			(effects
				(font
					(size 1.27 1.27)
				)
				(justify mirror)
			)
		)
		(property "Value" "10KR2F-2-GP"
			(at -0.064008 -3.993896 90)
			(unlocked yes)
			(layer "B.Fab")
			(hide yes)
			(effects
				(font
					(size 1.016 1.016)
					(thickness 0.1524)
				)
				(justify mirror)
			)
		)
		(property "Device Type" "R402H16"
			(at -0.064008 -5.517896 90)
			(unlocked yes)
			(layer "B.Fab")
			(hide yes)
			(effects
				(font
					(size 1.016 1.016)
					(thickness 0.1524)
				)
				(justify mirror)
			)
		)
		(duplicate_pad_numbers_are_jumpers no)
		(fp_rect
			(start 0.381 0.8382)
			(end -0.381 -0.8382)
			(stroke
				(width 0)
				(type default)
			)
			(fill no)
			(layer "B.CrtYd")
		)
		(fp_rect
			(start 0.381 0.8382)
			(end -0.381 -0.8382)
			(stroke
				(width 0)
				(type default)
			)
			(fill no)
			(layer "B.Fab")
		)
		(pad "1" smd custom
			(at 0 -0.4318 270)
			(size 0.127 0.127)
			(layers "B.Cu" "B.Mask" "B.Paste")
			(net "P3V3_CPU")
			(options
				(clearance outline)
				(anchor circle)
			)
			(primitives
				(gr_poly
					(pts
						(arc
							(start -0.2032 0.2794)
							(mid -0.239121 0.264521)
							(end -0.254 0.2286)
						)
						(arc
							(start -0.254 -0.2286)
							(mid -0.239121 -0.264521)
							(end -0.2032 -0.2794)
						)
						(arc
							(start 0.2032 -0.2794)
							(mid 0.239121 -0.264521)
							(end 0.254 -0.2286)
						)
						(arc
							(start 0.254 0.2286)
							(mid 0.239121 0.264521)
							(end 0.2032 0.2794)
						)
					)
					(width 0)
					(fill yes)
				)
			)
		)
		(pad "2" smd custom
			(at 0 0.4318 270)
			(size 0.127 0.127)
			(layers "B.Cu" "B.Mask" "B.Paste")
			(net "GBE_MDIO_CLK0")
			(options
				(clearance outline)
				(anchor circle)
			)
			(primitives
				(gr_poly
					(pts
						(arc
							(start -0.2032 0.2794)
							(mid -0.239121 0.264521)
							(end -0.254 0.2286)
						)
						(arc
							(start -0.254 -0.2286)
							(mid -0.239121 -0.264521)
							(end -0.2032 -0.2794)
						)
						(arc
							(start 0.2032 -0.2794)
							(mid 0.239121 -0.264521)
							(end 0.254 -0.2286)
						)
						(arc
							(start 0.254 0.2286)
							(mid 0.239121 0.264521)
							(end 0.2032 0.2794)
						)
					)
					(width 0)
					(fill yes)
				)
			)
		)
	)
	(footprint ""
		(layer "B.Cu")
		(at 41.4274 -28.7528 -90)
		(property "Reference" "R432"
			(at 0 0 90)
			(layer "B.SilkS")
			(hide yes)
			(effects
				(font
					(size 1.27 1.27)
				)
				(justify mirror)
			)
		)
		(property "Value" "43D2R2F-GP"
			(at -1.7907 -1.1176 270)
			(unlocked yes)
			(layer "B.Fab")
			(hide yes)
			(effects
				(font
					(size 1.016 1.016)
					(thickness 0.1524)
				)
				(justify mirror)
			)
		)
		(property "Device Type" "R402H16"
			(at -1.7907 -2.6416 270)
			(unlocked yes)
			(layer "B.Fab")
			(hide yes)
			(effects
				(font
					(size 1.016 1.016)
					(thickness 0.1524)
				)
				(justify mirror)
			)
		)
		(duplicate_pad_numbers_are_jumpers no)
		(fp_rect
			(start 0.381 0.8382)
			(end -0.381 -0.8382)
			(stroke
				(width 0)
				(type default)
			)
			(fill no)
			(layer "B.CrtYd")
		)
		(fp_rect
			(start 0.381 0.8382)
			(end -0.381 -0.8382)
			(stroke
				(width 0)
				(type default)
			)
			(fill no)
			(layer "B.Fab")
		)
		(pad "1" smd custom
			(at 0 -0.4318 90)
			(size 0.127 0.127)
			(layers "B.Cu" "B.Mask" "B.Paste")
			(net "CLK_100M_CLKBUFF_PCIE_DN")
			(options
				(clearance outline)
				(anchor circle)
			)
			(primitives
				(gr_poly
					(pts
						(arc
							(start -0.2032 0.2794)
							(mid -0.239121 0.264521)
							(end -0.254 0.2286)
						)
						(arc
							(start -0.254 -0.2286)
							(mid -0.239121 -0.264521)
							(end -0.2032 -0.2794)
						)
						(arc
							(start 0.2032 -0.2794)
							(mid 0.239121 -0.264521)
							(end 0.254 -0.2286)
						)
						(arc
							(start 0.254 0.2286)
							(mid 0.239121 0.264521)
							(end 0.2032 0.2794)
						)
					)
					(width 0)
					(fill yes)
				)
			)
		)
		(pad "2" smd custom
			(at 0 0.4318 90)
			(size 0.127 0.127)
			(layers "B.Cu" "B.Mask" "B.Paste")
			(net "GND")
			(options
				(clearance outline)
				(anchor circle)
			)
			(primitives
				(gr_poly
					(pts
						(arc
							(start -0.2032 0.2794)
							(mid -0.239121 0.264521)
							(end -0.254 0.2286)
						)
						(arc
							(start -0.254 -0.2286)
							(mid -0.239121 -0.264521)
							(end -0.2032 -0.2794)
						)
						(arc
							(start 0.2032 -0.2794)
							(mid 0.239121 -0.264521)
							(end 0.254 -0.2286)
						)
						(arc
							(start 0.254 0.2286)
							(mid 0.239121 0.264521)
							(end 0.2032 0.2794)
						)
					)
					(width 0)
					(fill yes)
				)
			)
		)
	)
	(footprint ""
		(layer "B.Cu")
		(at 110.4646 -37.592)
		(property "Reference" "C194"
			(at 0 0 0)
			(layer "B.SilkS")
			(hide yes)
			(effects
				(font
					(size 1.27 1.27)
				)
				(justify mirror)
			)
		)
		(property "Value" "SC1U10V2KX-1GP"
			(at -1.1811 -2.7051 0)
			(unlocked yes)
			(layer "B.Fab")
			(hide yes)
			(effects
				(font
					(size 1.016 1.016)
					(thickness 0.1524)
				)
				(justify mirror)
			)
		)
		(property "Device Type" "C402H22"
			(at -1.1811 -4.2291 0)
			(unlocked yes)
			(layer "B.Fab")
			(hide yes)
			(effects
				(font
					(size 1.016 1.016)
					(thickness 0.1524)
				)
				(justify mirror)
			)
		)
		(duplicate_pad_numbers_are_jumpers no)
		(fp_rect
			(start 0.381 0.7366)
			(end -0.381 -0.7366)
			(stroke
				(width 0)
				(type default)
			)
			(fill no)
			(layer "B.CrtYd")
		)
		(fp_rect
			(start 0.381 0.7366)
			(end -0.381 -0.7366)
			(stroke
				(width 0)
				(type default)
			)
			(fill no)
			(layer "B.Fab")
		)
		(pad "1" smd custom
			(at 0 -0.4572 180)
			(size 0.1143 0.1143)
			(layers "B.Cu" "B.Mask" "B.Paste")
			(net "PVCCP")
			(options
				(clearance outline)
				(anchor circle)
			)
			(primitives
				(gr_poly
					(pts
						(arc
							(start -0.254 0.1778)
							(mid -0.239121 0.213721)
							(end -0.2032 0.2286)
						)
						(arc
							(start 0.2032 0.2286)
							(mid 0.239121 0.213721)
							(end 0.254 0.1778)
						)
						(arc
							(start 0.254 -0.1778)
							(mid 0.239121 -0.213721)
							(end 0.2032 -0.2286)
						)
						(arc
							(start -0.2032 -0.2286)
							(mid -0.239121 -0.213721)
							(end -0.254 -0.1778)
						)
					)
					(width 0)
					(fill yes)
				)
			)
		)
		(pad "2" smd custom
			(at 0 0.4572 180)
			(size 0.1143 0.1143)
			(layers "B.Cu" "B.Mask" "B.Paste")
			(net "GND")
			(options
				(clearance outline)
				(anchor circle)
			)
			(primitives
				(gr_poly
					(pts
						(arc
							(start -0.254 0.1778)
							(mid -0.239121 0.213721)
							(end -0.2032 0.2286)
						)
						(arc
							(start 0.2032 0.2286)
							(mid 0.239121 0.213721)
							(end 0.254 0.1778)
						)
						(arc
							(start 0.254 -0.1778)
							(mid 0.239121 -0.213721)
							(end 0.2032 -0.2286)
						)
						(arc
							(start -0.2032 -0.2286)
							(mid -0.239121 -0.213721)
							(end -0.254 -0.1778)
						)
					)
					(width 0)
					(fill yes)
				)
			)
		)
	)
	(footprint ""
		(layer "B.Cu")
		(at 94.168468 -35.921696 180)
		(property "Reference" "C203"
			(at 0 0 0)
			(layer "B.SilkS")
			(hide yes)
			(effects
				(font
					(size 1.27 1.27)
				)
				(justify mirror)
			)
		)
		(property "Value" "SC1U10V2KX-1GP"
			(at -1.1811 -2.7051 180)
			(unlocked yes)
			(layer "B.Fab")
			(hide yes)
			(effects
				(font
					(size 1.016 1.016)
					(thickness 0.1524)
				)
				(justify mirror)
			)
		)
		(property "Device Type" "C402H22"
			(at -1.1811 -4.2291 180)
			(unlocked yes)
			(layer "B.Fab")
			(hide yes)
			(effects
				(font
					(size 1.016 1.016)
					(thickness 0.1524)
				)
				(justify mirror)
			)
		)
		(duplicate_pad_numbers_are_jumpers no)
		(fp_rect
			(start 0.381 0.7366)
			(end -0.381 -0.7366)
			(stroke
				(width 0)
				(type default)
			)
			(fill no)
			(layer "B.CrtYd")
		)
		(fp_rect
			(start 0.381 0.7366)
			(end -0.381 -0.7366)
			(stroke
				(width 0)
				(type default)
			)
			(fill no)
			(layer "B.Fab")
		)
		(pad "1" smd custom
			(at 0 -0.4572)
			(size 0.1143 0.1143)
			(layers "B.Cu" "B.Mask" "B.Paste")
			(net "P1V0_STBY")
			(options
				(clearance outline)
				(anchor circle)
			)
			(primitives
				(gr_poly
					(pts
						(arc
							(start -0.254 0.1778)
							(mid -0.239121 0.213721)
							(end -0.2032 0.2286)
						)
						(arc
							(start 0.2032 0.2286)
							(mid 0.239121 0.213721)
							(end 0.254 0.1778)
						)
						(arc
							(start 0.254 -0.1778)
							(mid 0.239121 -0.213721)
							(end 0.2032 -0.2286)
						)
						(arc
							(start -0.2032 -0.2286)
							(mid -0.239121 -0.213721)
							(end -0.254 -0.1778)
						)
					)
					(width 0)
					(fill yes)
				)
			)
		)
		(pad "2" smd custom
			(at 0 0.4572)
			(size 0.1143 0.1143)
			(layers "B.Cu" "B.Mask" "B.Paste")
			(net "GND")
			(options
				(clearance outline)
				(anchor circle)
			)
			(primitives
				(gr_poly
					(pts
						(arc
							(start -0.254 0.1778)
							(mid -0.239121 0.213721)
							(end -0.2032 0.2286)
						)
						(arc
							(start 0.2032 0.2286)
							(mid 0.239121 0.213721)
							(end 0.254 0.1778)
						)
						(arc
							(start 0.254 -0.1778)
							(mid 0.239121 -0.213721)
							(end 0.2032 -0.2286)
						)
						(arc
							(start -0.2032 -0.2286)
							(mid -0.239121 -0.213721)
							(end -0.254 -0.1778)
						)
					)
					(width 0)
					(fill yes)
				)
			)
		)
	)
	(footprint ""
		(layer "B.Cu")
		(at 74.676 -24.7904 90)
		(property "Reference" "R375"
			(at 0 0 90)
			(layer "B.SilkS")
			(hide yes)
			(effects
				(font
					(size 1.27 1.27)
				)
				(justify mirror)
			)
		)
		(property "Value" "10KR2F-2-GP"
			(at -0.064008 -3.993896 90)
			(unlocked yes)
			(layer "B.Fab")
			(hide yes)
			(effects
				(font
					(size 1.016 1.016)
					(thickness 0.1524)
				)
				(justify mirror)
			)
		)
		(property "Device Type" "R402H16"
			(at -0.064008 -5.517896 90)
			(unlocked yes)
			(layer "B.Fab")
			(hide yes)
			(effects
				(font
					(size 1.016 1.016)
					(thickness 0.1524)
				)
				(justify mirror)
			)
		)
		(duplicate_pad_numbers_are_jumpers no)
		(fp_rect
			(start 0.381 0.8382)
			(end -0.381 -0.8382)
			(stroke
				(width 0)
				(type default)
			)
			(fill no)
			(layer "B.CrtYd")
		)
		(fp_rect
			(start 0.381 0.8382)
			(end -0.381 -0.8382)
			(stroke
				(width 0)
				(type default)
			)
			(fill no)
			(layer "B.Fab")
		)
		(pad "1" smd custom
			(at 0 -0.4318 270)
			(size 0.127 0.127)
			(layers "B.Cu" "B.Mask" "B.Paste")
			(net "P3V3_CPU")
			(options
				(clearance outline)
				(anchor circle)
			)
			(primitives
				(gr_poly
					(pts
						(arc
							(start -0.2032 0.2794)
							(mid -0.239121 0.264521)
							(end -0.254 0.2286)
						)
						(arc
							(start -0.254 -0.2286)
							(mid -0.239121 -0.264521)
							(end -0.2032 -0.2794)
						)
						(arc
							(start 0.2032 -0.2794)
							(mid 0.239121 -0.264521)
							(end 0.254 -0.2286)
						)
						(arc
							(start 0.254 0.2286)
							(mid 0.239121 0.264521)
							(end 0.2032 0.2794)
						)
					)
					(width 0)
					(fill yes)
				)
			)
		)
		(pad "2" smd custom
			(at 0 0.4318 270)
			(size 0.127 0.127)
			(layers "B.Cu" "B.Mask" "B.Paste")
			(net "GBE_SMBCLK")
			(options
				(clearance outline)
				(anchor circle)
			)
			(primitives
				(gr_poly
					(pts
						(arc
							(start -0.2032 0.2794)
							(mid -0.239121 0.264521)
							(end -0.254 0.2286)
						)
						(arc
							(start -0.254 -0.2286)
							(mid -0.239121 -0.264521)
							(end -0.2032 -0.2794)
						)
						(arc
							(start 0.2032 -0.2794)
							(mid 0.239121 -0.264521)
							(end 0.254 -0.2286)
						)
						(arc
							(start 0.254 0.2286)
							(mid 0.239121 0.264521)
							(end 0.2032 0.2794)
						)
					)
					(width 0)
					(fill yes)
				)
			)
		)
	)
	(footprint ""
		(layer "B.Cu")
		(at 74.4728 -38.7858 180)
		(property "Reference" "R324"
			(at 0 0 0)
			(layer "B.SilkS")
			(hide yes)
			(effects
				(font
					(size 1.27 1.27)
				)
				(justify mirror)
			)
		)
		(property "Value" "0R2J-2-GP"
			(at -0.064008 -3.993896 180)
			(unlocked yes)
			(layer "B.Fab")
			(hide yes)
			(effects
				(font
					(size 1.016 1.016)
					(thickness 0.1524)
				)
				(justify mirror)
			)
		)
		(property "Device Type" "R402H16"
			(at -0.064008 -5.517896 180)
			(unlocked yes)
			(layer "B.Fab")
			(hide yes)
			(effects
				(font
					(size 1.016 1.016)
					(thickness 0.1524)
				)
				(justify mirror)
			)
		)
		(duplicate_pad_numbers_are_jumpers no)
		(fp_rect
			(start 0.381 0.8382)
			(end -0.381 -0.8382)
			(stroke
				(width 0)
				(type default)
			)
			(fill no)
			(layer "B.CrtYd")
		)
		(fp_rect
			(start 0.381 0.8382)
			(end -0.381 -0.8382)
			(stroke
				(width 0)
				(type default)
			)
			(fill no)
			(layer "B.Fab")
		)
		(pad "1" smd custom
			(at 0 -0.4318)
			(size 0.127 0.127)
			(layers "B.Cu" "B.Mask" "B.Paste")
			(net "CPU_RSVD10")
			(options
				(clearance outline)
				(anchor circle)
			)
			(primitives
				(gr_poly
					(pts
						(arc
							(start -0.2032 0.2794)
							(mid -0.239121 0.264521)
							(end -0.254 0.2286)
						)
						(arc
							(start -0.254 -0.2286)
							(mid -0.239121 -0.264521)
							(end -0.2032 -0.2794)
						)
						(arc
							(start 0.2032 -0.2794)
							(mid 0.239121 -0.264521)
							(end 0.254 -0.2286)
						)
						(arc
							(start 0.254 0.2286)
							(mid 0.239121 0.264521)
							(end 0.2032 0.2794)
						)
					)
					(width 0)
					(fill yes)
				)
			)
		)
		(pad "2" smd custom
			(at 0 0.4318)
			(size 0.127 0.127)
			(layers "B.Cu" "B.Mask" "B.Paste")
			(net "GND")
			(options
				(clearance outline)
				(anchor circle)
			)
			(primitives
				(gr_poly
					(pts
						(arc
							(start -0.2032 0.2794)
							(mid -0.239121 0.264521)
							(end -0.254 0.2286)
						)
						(arc
							(start -0.254 -0.2286)
							(mid -0.239121 -0.264521)
							(end -0.2032 -0.2794)
						)
						(arc
							(start 0.2032 -0.2794)
							(mid 0.239121 -0.264521)
							(end 0.254 -0.2286)
						)
						(arc
							(start 0.254 0.2286)
							(mid 0.239121 0.264521)
							(end 0.2032 0.2794)
						)
					)
					(width 0)
					(fill yes)
				)
			)
		)
	)
	(footprint ""
		(layer "B.Cu")
		(at 99.947984 -27.321002)
		(property "Reference" "C244"
			(at 0 0 0)
			(layer "B.SilkS")
			(hide yes)
			(effects
				(font
					(size 1.27 1.27)
				)
				(justify mirror)
			)
		)
		(property "Value" "SCD1U16V2KX-L-GP"
			(at -1.1811 -2.7051 0)
			(unlocked yes)
			(layer "B.Fab")
			(hide yes)
			(effects
				(font
					(size 1.016 1.016)
					(thickness 0.1524)
				)
				(justify mirror)
			)
		)
		(property "Device Type" "C402H22"
			(at -1.1811 -4.2291 0)
			(unlocked yes)
			(layer "B.Fab")
			(hide yes)
			(effects
				(font
					(size 1.016 1.016)
					(thickness 0.1524)
				)
				(justify mirror)
			)
		)
		(duplicate_pad_numbers_are_jumpers no)
		(fp_rect
			(start 0.381 0.7366)
			(end -0.381 -0.7366)
			(stroke
				(width 0)
				(type default)
			)
			(fill no)
			(layer "B.CrtYd")
		)
		(fp_rect
			(start 0.381 0.7366)
			(end -0.381 -0.7366)
			(stroke
				(width 0)
				(type default)
			)
			(fill no)
			(layer "B.Fab")
		)
		(pad "1" smd custom
			(at 0 -0.4572 180)
			(size 0.1143 0.1143)
			(layers "B.Cu" "B.Mask" "B.Paste")
			(net "M_B_VREF")
			(options
				(clearance outline)
				(anchor circle)
			)
			(primitives
				(gr_poly
					(pts
						(arc
							(start -0.254 0.1778)
							(mid -0.239121 0.213721)
							(end -0.2032 0.2286)
						)
						(arc
							(start 0.2032 0.2286)
							(mid 0.239121 0.213721)
							(end 0.254 0.1778)
						)
						(arc
							(start 0.254 -0.1778)
							(mid 0.239121 -0.213721)
							(end 0.2032 -0.2286)
						)
						(arc
							(start -0.2032 -0.2286)
							(mid -0.239121 -0.213721)
							(end -0.254 -0.1778)
						)
					)
					(width 0)
					(fill yes)
				)
			)
		)
		(pad "2" smd custom
			(at 0 0.4572 180)
			(size 0.1143 0.1143)
			(layers "B.Cu" "B.Mask" "B.Paste")
			(net "GND")
			(options
				(clearance outline)
				(anchor circle)
			)
			(primitives
				(gr_poly
					(pts
						(arc
							(start -0.254 0.1778)
							(mid -0.239121 0.213721)
							(end -0.2032 0.2286)
						)
						(arc
							(start 0.2032 0.2286)
							(mid 0.239121 0.213721)
							(end 0.254 0.1778)
						)
						(arc
							(start 0.254 -0.1778)
							(mid 0.239121 -0.213721)
							(end 0.2032 -0.2286)
						)
						(arc
							(start -0.2032 -0.2286)
							(mid -0.239121 -0.213721)
							(end -0.254 -0.1778)
						)
					)
					(width 0)
					(fill yes)
				)
			)
		)
	)
	(footprint ""
		(layer "B.Cu")
		(at 133.731 -31.115 -90)
		(property "Reference" "C138"
			(at 0 0 90)
			(layer "B.SilkS")
			(hide yes)
			(effects
				(font
					(size 1.27 1.27)
				)
				(justify mirror)
			)
		)
		(property "Value" "SCD1U10V2KX-5GP"
			(at -1.1811 -2.7051 270)
			(unlocked yes)
			(layer "B.Fab")
			(hide yes)
			(effects
				(font
					(size 1.016 1.016)
					(thickness 0.1524)
				)
				(justify mirror)
			)
		)
		(property "Device Type" "C402H22"
			(at -1.1811 -4.2291 270)
			(unlocked yes)
			(layer "B.Fab")
			(hide yes)
			(effects
				(font
					(size 1.016 1.016)
					(thickness 0.1524)
				)
				(justify mirror)
			)
		)
		(duplicate_pad_numbers_are_jumpers no)
		(fp_rect
			(start 0.381 0.7366)
			(end -0.381 -0.7366)
			(stroke
				(width 0)
				(type default)
			)
			(fill no)
			(layer "B.CrtYd")
		)
		(fp_rect
			(start 0.381 0.7366)
			(end -0.381 -0.7366)
			(stroke
				(width 0)
				(type default)
			)
			(fill no)
			(layer "B.Fab")
		)
		(pad "1" smd custom
			(at 0 -0.4572 90)
			(size 0.1143 0.1143)
			(layers "B.Cu" "B.Mask" "B.Paste")
			(net "P3V3_STBY")
			(options
				(clearance outline)
				(anchor circle)
			)
			(primitives
				(gr_poly
					(pts
						(arc
							(start -0.254 0.1778)
							(mid -0.239121 0.213721)
							(end -0.2032 0.2286)
						)
						(arc
							(start 0.2032 0.2286)
							(mid 0.239121 0.213721)
							(end 0.254 0.1778)
						)
						(arc
							(start 0.254 -0.1778)
							(mid 0.239121 -0.213721)
							(end 0.2032 -0.2286)
						)
						(arc
							(start -0.2032 -0.2286)
							(mid -0.239121 -0.213721)
							(end -0.254 -0.1778)
						)
					)
					(width 0)
					(fill yes)
				)
			)
		)
		(pad "2" smd custom
			(at 0 0.4572 90)
			(size 0.1143 0.1143)
			(layers "B.Cu" "B.Mask" "B.Paste")
			(net "GND")
			(options
				(clearance outline)
				(anchor circle)
			)
			(primitives
				(gr_poly
					(pts
						(arc
							(start -0.254 0.1778)
							(mid -0.239121 0.213721)
							(end -0.2032 0.2286)
						)
						(arc
							(start 0.2032 0.2286)
							(mid 0.239121 0.213721)
							(end 0.254 0.1778)
						)
						(arc
							(start 0.254 -0.1778)
							(mid 0.239121 -0.213721)
							(end 0.2032 -0.2286)
						)
						(arc
							(start -0.2032 -0.2286)
							(mid -0.239121 -0.213721)
							(end -0.254 -0.1778)
						)
					)
					(width 0)
					(fill yes)
				)
			)
		)
	)
	(footprint ""
		(layer "B.Cu")
		(at 131.318 -14.733778 180)
		(property "Reference" "C296"
			(at 0 0 0)
			(layer "B.SilkS")
			(hide yes)
			(effects
				(font
					(size 1.27 1.27)
				)
				(justify mirror)
			)
		)
		(property "Value" "SCD1U16V2KX-3GP"
			(at -1.1811 -2.7051 180)
			(unlocked yes)
			(layer "B.Fab")
			(hide yes)
			(effects
				(font
					(size 1.016 1.016)
					(thickness 0.1524)
				)
				(justify mirror)
			)
		)
		(property "Device Type" "C402H22"
			(at -1.1811 -4.2291 180)
			(unlocked yes)
			(layer "B.Fab")
			(hide yes)
			(effects
				(font
					(size 1.016 1.016)
					(thickness 0.1524)
				)
				(justify mirror)
			)
		)
		(duplicate_pad_numbers_are_jumpers no)
		(fp_rect
			(start 0.381 0.7366)
			(end -0.381 -0.7366)
			(stroke
				(width 0)
				(type default)
			)
			(fill no)
			(layer "B.CrtYd")
		)
		(fp_rect
			(start 0.381 0.7366)
			(end -0.381 -0.7366)
			(stroke
				(width 0)
				(type default)
			)
			(fill no)
			(layer "B.Fab")
		)
		(pad "1" smd custom
			(at 0 -0.4572)
			(size 0.1143 0.1143)
			(layers "B.Cu" "B.Mask" "B.Paste")
			(net "DDR3_M_B_VREF_DQ1")
			(options
				(clearance outline)
				(anchor circle)
			)
			(primitives
				(gr_poly
					(pts
						(arc
							(start -0.254 0.1778)
							(mid -0.239121 0.213721)
							(end -0.2032 0.2286)
						)
						(arc
							(start 0.2032 0.2286)
							(mid 0.239121 0.213721)
							(end 0.254 0.1778)
						)
						(arc
							(start 0.254 -0.1778)
							(mid 0.239121 -0.213721)
							(end 0.2032 -0.2286)
						)
						(arc
							(start -0.2032 -0.2286)
							(mid -0.239121 -0.213721)
							(end -0.254 -0.1778)
						)
					)
					(width 0)
					(fill yes)
				)
			)
		)
		(pad "2" smd custom
			(at 0 0.4572)
			(size 0.1143 0.1143)
			(layers "B.Cu" "B.Mask" "B.Paste")
			(net "GND")
			(options
				(clearance outline)
				(anchor circle)
			)
			(primitives
				(gr_poly
					(pts
						(arc
							(start -0.254 0.1778)
							(mid -0.239121 0.213721)
							(end -0.2032 0.2286)
						)
						(arc
							(start 0.2032 0.2286)
							(mid 0.239121 0.213721)
							(end 0.254 0.1778)
						)
						(arc
							(start 0.254 -0.1778)
							(mid 0.239121 -0.213721)
							(end 0.2032 -0.2286)
						)
						(arc
							(start -0.2032 -0.2286)
							(mid -0.239121 -0.213721)
							(end -0.254 -0.1778)
						)
					)
					(width 0)
					(fill yes)
				)
			)
		)
	)
	(footprint ""
		(layer "B.Cu")
		(at 38.735 -43.561 -90)
		(property "Reference" "R125"
			(at 0 0 90)
			(layer "B.SilkS")
			(hide yes)
			(effects
				(font
					(size 1.27 1.27)
				)
				(justify mirror)
			)
		)
		(property "Value" "0R2J-2-GP"
			(at -1.7907 -1.1176 270)
			(unlocked yes)
			(layer "B.Fab")
			(hide yes)
			(effects
				(font
					(size 1.016 1.016)
					(thickness 0.1524)
				)
				(justify mirror)
			)
		)
		(property "Device Type" "R402H16"
			(at -1.7907 -2.6416 270)
			(unlocked yes)
			(layer "B.Fab")
			(hide yes)
			(effects
				(font
					(size 1.016 1.016)
					(thickness 0.1524)
				)
				(justify mirror)
			)
		)
		(duplicate_pad_numbers_are_jumpers no)
		(fp_rect
			(start 0.381 0.8382)
			(end -0.381 -0.8382)
			(stroke
				(width 0)
				(type default)
			)
			(fill no)
			(layer "B.CrtYd")
		)
		(fp_rect
			(start 0.381 0.8382)
			(end -0.381 -0.8382)
			(stroke
				(width 0)
				(type default)
			)
			(fill no)
			(layer "B.Fab")
		)
		(pad "1" smd custom
			(at 0 -0.4318 90)
			(size 0.127 0.127)
			(layers "B.Cu" "B.Mask" "B.Paste")
			(net "XTAL_CLK_GEN_OUT_R")
			(options
				(clearance outline)
				(anchor circle)
			)
			(primitives
				(gr_poly
					(pts
						(arc
							(start -0.2032 0.2794)
							(mid -0.239121 0.264521)
							(end -0.254 0.2286)
						)
						(arc
							(start -0.254 -0.2286)
							(mid -0.239121 -0.264521)
							(end -0.2032 -0.2794)
						)
						(arc
							(start 0.2032 -0.2794)
							(mid 0.239121 -0.264521)
							(end 0.254 -0.2286)
						)
						(arc
							(start 0.254 0.2286)
							(mid 0.239121 0.264521)
							(end 0.2032 0.2794)
						)
					)
					(width 0)
					(fill yes)
				)
			)
		)
		(pad "2" smd custom
			(at 0 0.4318 90)
			(size 0.127 0.127)
			(layers "B.Cu" "B.Mask" "B.Paste")
			(net "XTAL_CLK_GEN_OUT")
			(options
				(clearance outline)
				(anchor circle)
			)
			(primitives
				(gr_poly
					(pts
						(arc
							(start -0.2032 0.2794)
							(mid -0.239121 0.264521)
							(end -0.254 0.2286)
						)
						(arc
							(start -0.254 -0.2286)
							(mid -0.239121 -0.264521)
							(end -0.2032 -0.2794)
						)
						(arc
							(start 0.2032 -0.2794)
							(mid 0.239121 -0.264521)
							(end 0.254 -0.2286)
						)
						(arc
							(start 0.254 0.2286)
							(mid 0.239121 0.264521)
							(end 0.2032 0.2794)
						)
					)
					(width 0)
					(fill yes)
				)
			)
		)
	)
	(footprint ""
		(layer "B.Cu")
		(at 84.836 -14.478)
		(property "Reference" "PC203"
			(at 0 0 0)
			(layer "B.SilkS")
			(hide yes)
			(effects
				(font
					(size 1.27 1.27)
				)
				(justify mirror)
			)
		)
		(property "Value" "SCD1U10V2KX-5GP"
			(at -1.1811 -2.7051 0)
			(unlocked yes)
			(layer "B.Fab")
			(hide yes)
			(effects
				(font
					(size 1.016 1.016)
					(thickness 0.1524)
				)
				(justify mirror)
			)
		)
		(property "Device Type" "C402H22"
			(at -1.1811 -4.2291 0)
			(unlocked yes)
			(layer "B.Fab")
			(hide yes)
			(effects
				(font
					(size 1.016 1.016)
					(thickness 0.1524)
				)
				(justify mirror)
			)
		)
		(duplicate_pad_numbers_are_jumpers no)
		(fp_rect
			(start 0.381 0.7366)
			(end -0.381 -0.7366)
			(stroke
				(width 0)
				(type default)
			)
			(fill no)
			(layer "B.CrtYd")
		)
		(fp_rect
			(start 0.381 0.7366)
			(end -0.381 -0.7366)
			(stroke
				(width 0)
				(type default)
			)
			(fill no)
			(layer "B.Fab")
		)
		(pad "1" smd custom
			(at 0 -0.4572 180)
			(size 0.1143 0.1143)
			(layers "B.Cu" "B.Mask" "B.Paste")
			(net "TPS74801_1V35_OUT")
			(options
				(clearance outline)
				(anchor circle)
			)
			(primitives
				(gr_poly
					(pts
						(arc
							(start -0.254 0.1778)
							(mid -0.239121 0.213721)
							(end -0.2032 0.2286)
						)
						(arc
							(start 0.2032 0.2286)
							(mid 0.239121 0.213721)
							(end 0.254 0.1778)
						)
						(arc
							(start 0.254 -0.1778)
							(mid 0.239121 -0.213721)
							(end 0.2032 -0.2286)
						)
						(arc
							(start -0.2032 -0.2286)
							(mid -0.239121 -0.213721)
							(end -0.254 -0.1778)
						)
					)
					(width 0)
					(fill yes)
				)
			)
		)
		(pad "2" smd custom
			(at 0 0.4572 180)
			(size 0.1143 0.1143)
			(layers "B.Cu" "B.Mask" "B.Paste")
			(net "GND")
			(options
				(clearance outline)
				(anchor circle)
			)
			(primitives
				(gr_poly
					(pts
						(arc
							(start -0.254 0.1778)
							(mid -0.239121 0.213721)
							(end -0.2032 0.2286)
						)
						(arc
							(start 0.2032 0.2286)
							(mid 0.239121 0.213721)
							(end 0.254 0.1778)
						)
						(arc
							(start 0.254 -0.1778)
							(mid 0.239121 -0.213721)
							(end 0.2032 -0.2286)
						)
						(arc
							(start -0.2032 -0.2286)
							(mid -0.239121 -0.213721)
							(end -0.254 -0.1778)
						)
					)
					(width 0)
					(fill yes)
				)
			)
		)
	)
	(footprint ""
		(layer "B.Cu")
		(at 74.93 -49.911 90)
		(property "Reference" "R310"
			(at 0 0 90)
			(layer "B.SilkS")
			(hide yes)
			(effects
				(font
					(size 1.27 1.27)
				)
				(justify mirror)
			)
		)
		(property "Value" "4K7R2F-GP"
			(at -0.064008 -3.993896 90)
			(unlocked yes)
			(layer "B.Fab")
			(hide yes)
			(effects
				(font
					(size 1.016 1.016)
					(thickness 0.1524)
				)
				(justify mirror)
			)
		)
		(property "Device Type" "R402H16"
			(at -0.064008 -5.517896 90)
			(unlocked yes)
			(layer "B.Fab")
			(hide yes)
			(effects
				(font
					(size 1.016 1.016)
					(thickness 0.1524)
				)
				(justify mirror)
			)
		)
		(duplicate_pad_numbers_are_jumpers no)
		(fp_rect
			(start 0.381 0.8382)
			(end -0.381 -0.8382)
			(stroke
				(width 0)
				(type default)
			)
			(fill no)
			(layer "B.CrtYd")
		)
		(fp_rect
			(start 0.381 0.8382)
			(end -0.381 -0.8382)
			(stroke
				(width 0)
				(type default)
			)
			(fill no)
			(layer "B.Fab")
		)
		(pad "1" smd custom
			(at 0 -0.4318 270)
			(size 0.127 0.127)
			(layers "B.Cu" "B.Mask" "B.Paste")
			(net "P3V3")
			(options
				(clearance outline)
				(anchor circle)
			)
			(primitives
				(gr_poly
					(pts
						(arc
							(start -0.2032 0.2794)
							(mid -0.239121 0.264521)
							(end -0.254 0.2286)
						)
						(arc
							(start -0.254 -0.2286)
							(mid -0.239121 -0.264521)
							(end -0.2032 -0.2794)
						)
						(arc
							(start 0.2032 -0.2794)
							(mid 0.239121 -0.264521)
							(end 0.254 -0.2286)
						)
						(arc
							(start 0.254 0.2286)
							(mid 0.239121 0.264521)
							(end 0.2032 0.2794)
						)
					)
					(width 0)
					(fill yes)
				)
			)
		)
		(pad "2" smd custom
			(at 0 0.4318 270)
			(size 0.127 0.127)
			(layers "B.Cu" "B.Mask" "B.Paste")
			(net "BIOS_POST_CMPLT#")
			(options
				(clearance outline)
				(anchor circle)
			)
			(primitives
				(gr_poly
					(pts
						(arc
							(start -0.2032 0.2794)
							(mid -0.239121 0.264521)
							(end -0.254 0.2286)
						)
						(arc
							(start -0.254 -0.2286)
							(mid -0.239121 -0.264521)
							(end -0.2032 -0.2794)
						)
						(arc
							(start 0.2032 -0.2794)
							(mid 0.239121 -0.264521)
							(end 0.254 -0.2286)
						)
						(arc
							(start 0.254 0.2286)
							(mid 0.239121 0.264521)
							(end 0.2032 0.2794)
						)
					)
					(width 0)
					(fill yes)
				)
			)
		)
	)
	(footprint ""
		(layer "B.Cu")
		(at 71.952866 -26.243534)
		(property "Reference" "TP45"
			(at 0 0 0)
			(layer "B.SilkS")
			(hide yes)
			(effects
				(font
					(size 1.27 1.27)
				)
				(justify mirror)
			)
		)
		(property "Value" "TPAD24"
			(at 0 -2.9972 0)
			(unlocked yes)
			(layer "B.Fab")
			(hide yes)
			(effects
				(font
					(size 1.016 1.016)
					(thickness 0.1524)
				)
				(justify mirror)
			)
		)
		(property "Device Type" "TPAD24"
			(at 0 -4.5212 0)
			(unlocked yes)
			(layer "B.Fab")
			(hide yes)
			(effects
				(font
					(size 1.016 1.016)
					(thickness 0.1524)
				)
				(justify mirror)
			)
		)
		(duplicate_pad_numbers_are_jumpers no)
		(fp_poly
			(pts
				(arc
					(start 0.3048 0)
					(mid -0.3048 0)
					(end 0.3048 0)
				)
			)
			(stroke
				(width 0)
				(type default)
			)
			(fill no)
			(layer "B.CrtYd")
		)
		(fp_poly
			(pts
				(arc
					(start 0.6096 0)
					(mid -0.6096 0)
					(end 0.6096 0)
				)
			)
			(stroke
				(width 0)
				(type default)
			)
			(fill no)
			(layer "B.Fab")
		)
		(pad "1" smd circle
			(at 0 0 180)
			(size 0.6096 0.6096)
			(layers "B.Cu" "B.Mask" "B.Paste")
			(net "GBE_SDP0")
		)
	)
	(footprint ""
		(layer "B.Cu")
		(at 138.303 -23.622 90)
		(property "Reference" "C162"
			(at 0 0 90)
			(layer "B.SilkS")
			(hide yes)
			(effects
				(font
					(size 1.27 1.27)
				)
				(justify mirror)
			)
		)
		(property "Value" "SCD1U10V2KX-5GP"
			(at -1.1811 -2.7051 90)
			(unlocked yes)
			(layer "B.Fab")
			(hide yes)
			(effects
				(font
					(size 1.016 1.016)
					(thickness 0.1524)
				)
				(justify mirror)
			)
		)
		(property "Device Type" "C402H22"
			(at -1.1811 -4.2291 90)
			(unlocked yes)
			(layer "B.Fab")
			(hide yes)
			(effects
				(font
					(size 1.016 1.016)
					(thickness 0.1524)
				)
				(justify mirror)
			)
		)
		(duplicate_pad_numbers_are_jumpers no)
		(fp_rect
			(start 0.381 0.7366)
			(end -0.381 -0.7366)
			(stroke
				(width 0)
				(type default)
			)
			(fill no)
			(layer "B.CrtYd")
		)
		(fp_rect
			(start 0.381 0.7366)
			(end -0.381 -0.7366)
			(stroke
				(width 0)
				(type default)
			)
			(fill no)
			(layer "B.Fab")
		)
		(pad "1" smd custom
			(at 0 -0.4572 270)
			(size 0.1143 0.1143)
			(layers "B.Cu" "B.Mask" "B.Paste")
			(net "P3V3_STBY")
			(options
				(clearance outline)
				(anchor circle)
			)
			(primitives
				(gr_poly
					(pts
						(arc
							(start -0.254 0.1778)
							(mid -0.239121 0.213721)
							(end -0.2032 0.2286)
						)
						(arc
							(start 0.2032 0.2286)
							(mid 0.239121 0.213721)
							(end 0.254 0.1778)
						)
						(arc
							(start 0.254 -0.1778)
							(mid 0.239121 -0.213721)
							(end 0.2032 -0.2286)
						)
						(arc
							(start -0.2032 -0.2286)
							(mid -0.239121 -0.213721)
							(end -0.254 -0.1778)
						)
					)
					(width 0)
					(fill yes)
				)
			)
		)
		(pad "2" smd custom
			(at 0 0.4572 270)
			(size 0.1143 0.1143)
			(layers "B.Cu" "B.Mask" "B.Paste")
			(net "GND")
			(options
				(clearance outline)
				(anchor circle)
			)
			(primitives
				(gr_poly
					(pts
						(arc
							(start -0.254 0.1778)
							(mid -0.239121 0.213721)
							(end -0.2032 0.2286)
						)
						(arc
							(start 0.2032 0.2286)
							(mid 0.239121 0.213721)
							(end 0.254 0.1778)
						)
						(arc
							(start 0.254 -0.1778)
							(mid 0.239121 -0.213721)
							(end 0.2032 -0.2286)
						)
						(arc
							(start -0.2032 -0.2286)
							(mid -0.239121 -0.213721)
							(end -0.254 -0.1778)
						)
					)
					(width 0)
					(fill yes)
				)
			)
		)
	)
	(footprint ""
		(layer "B.Cu")
		(at 16.002 -51.181 180)
		(property "Reference" "R501"
			(at 0 0 0)
			(layer "B.SilkS")
			(hide yes)
			(effects
				(font
					(size 1.27 1.27)
				)
				(justify mirror)
			)
		)
		(property "Value" "150R3F-GP"
			(at 0.0254 -2.0193 180)
			(unlocked yes)
			(layer "B.Fab")
			(hide yes)
			(effects
				(font
					(size 1.016 1.016)
					(thickness 0.1524)
				)
				(justify mirror)
			)
		)
		(property "Device Type" "R603H22"
			(at 0.0254 -3.5433 180)
			(unlocked yes)
			(layer "B.Fab")
			(hide yes)
			(effects
				(font
					(size 1.016 1.016)
					(thickness 0.1524)
				)
				(justify mirror)
			)
		)
		(duplicate_pad_numbers_are_jumpers no)
		(fp_line
			(start 0.2032 0)
			(end 0.4191 0)
			(stroke
				(width 0.2032)
				(type default)
			)
			(layer "B.SilkS")
		)
		(fp_line
			(start -0.4318 0)
			(end -0.2032 0)
			(stroke
				(width 0.2032)
				(type default)
			)
			(layer "B.SilkS")
		)
		(fp_rect
			(start 0.635 1.1811)
			(end -0.635 -1.1811)
			(stroke
				(width 0)
				(type default)
			)
			(fill no)
			(layer "B.CrtYd")
		)
		(fp_rect
			(start 0.635 1.1811)
			(end -0.635 -1.1811)
			(stroke
				(width 0)
				(type default)
			)
			(fill no)
			(layer "B.Fab")
		)
		(pad "1" smd custom
			(at 0 -0.6604)
			(size 0.19685 0.19685)
			(layers "B.Cu" "B.Mask" "B.Paste")
			(net "P3V3")
			(options
				(clearance outline)
				(anchor circle)
			)
			(primitives
				(gr_poly
					(pts
						(arc
							(start 0.508 0.2921)
							(mid 0.478242 0.363942)
							(end 0.4064 0.3937)
						)
						(arc
							(start -0.4064 0.3937)
							(mid -0.478242 0.363942)
							(end -0.508 0.2921)
						)
						(arc
							(start -0.508 -0.2921)
							(mid -0.478242 -0.363942)
							(end -0.4064 -0.3937)
						)
						(arc
							(start 0.4064 -0.3937)
							(mid 0.478242 -0.363942)
							(end 0.508 -0.2921)
						)
					)
					(width 0)
					(fill yes)
				)
			)
		)
		(pad "2" smd custom
			(at 0 0.6604)
			(size 0.19685 0.19685)
			(layers "B.Cu" "B.Mask" "B.Paste")
			(net "P3V3_DISCHARGE_D")
			(options
				(clearance outline)
				(anchor circle)
			)
			(primitives
				(gr_poly
					(pts
						(arc
							(start 0.508 0.2921)
							(mid 0.478242 0.363942)
							(end 0.4064 0.3937)
						)
						(arc
							(start -0.4064 0.3937)
							(mid -0.478242 0.363942)
							(end -0.508 0.2921)
						)
						(arc
							(start -0.508 -0.2921)
							(mid -0.478242 -0.363942)
							(end -0.4064 -0.3937)
						)
						(arc
							(start 0.4064 -0.3937)
							(mid 0.478242 -0.363942)
							(end 0.508 -0.2921)
						)
					)
					(width 0)
					(fill yes)
				)
			)
		)
	)
	(footprint ""
		(layer "B.Cu")
		(at 178.054 -42.545)
		(property "Reference" "R175"
			(at 0 0 0)
			(layer "B.SilkS")
			(hide yes)
			(effects
				(font
					(size 1.27 1.27)
				)
				(justify mirror)
			)
		)
		(property "Value" "0R2J-2-GP"
			(at -1.7907 -1.1176 0)
			(unlocked yes)
			(layer "B.Fab")
			(hide yes)
			(effects
				(font
					(size 1.016 1.016)
					(thickness 0.1524)
				)
				(justify mirror)
			)
		)
		(property "Device Type" "R402H16"
			(at -1.7907 -2.6416 0)
			(unlocked yes)
			(layer "B.Fab")
			(hide yes)
			(effects
				(font
					(size 1.016 1.016)
					(thickness 0.1524)
				)
				(justify mirror)
			)
		)
		(duplicate_pad_numbers_are_jumpers no)
		(fp_rect
			(start 0.381 0.8382)
			(end -0.381 -0.8382)
			(stroke
				(width 0)
				(type default)
			)
			(fill no)
			(layer "B.CrtYd")
		)
		(fp_rect
			(start 0.381 0.8382)
			(end -0.381 -0.8382)
			(stroke
				(width 0)
				(type default)
			)
			(fill no)
			(layer "B.Fab")
		)
		(pad "1" smd custom
			(at 0 -0.4318 180)
			(size 0.127 0.127)
			(layers "B.Cu" "B.Mask" "B.Paste")
			(net "SPI_SW_RST#")
			(options
				(clearance outline)
				(anchor circle)
			)
			(primitives
				(gr_poly
					(pts
						(arc
							(start -0.2032 0.2794)
							(mid -0.239121 0.264521)
							(end -0.254 0.2286)
						)
						(arc
							(start -0.254 -0.2286)
							(mid -0.239121 -0.264521)
							(end -0.2032 -0.2794)
						)
						(arc
							(start 0.2032 -0.2794)
							(mid 0.239121 -0.264521)
							(end 0.254 -0.2286)
						)
						(arc
							(start 0.254 0.2286)
							(mid 0.239121 0.264521)
							(end 0.2032 0.2794)
						)
					)
					(width 0)
					(fill yes)
				)
			)
		)
		(pad "2" smd custom
			(at 0 0.4318 180)
			(size 0.127 0.127)
			(layers "B.Cu" "B.Mask" "B.Paste")
			(net "CPU_RSMRST#")
			(options
				(clearance outline)
				(anchor circle)
			)
			(primitives
				(gr_poly
					(pts
						(arc
							(start -0.2032 0.2794)
							(mid -0.239121 0.264521)
							(end -0.254 0.2286)
						)
						(arc
							(start -0.254 -0.2286)
							(mid -0.239121 -0.264521)
							(end -0.2032 -0.2794)
						)
						(arc
							(start 0.2032 -0.2794)
							(mid 0.239121 -0.264521)
							(end 0.254 -0.2286)
						)
						(arc
							(start 0.254 0.2286)
							(mid 0.239121 0.264521)
							(end 0.2032 0.2794)
						)
					)
					(width 0)
					(fill yes)
				)
			)
		)
	)
	(footprint ""
		(layer "B.Cu")
		(at 193.548 -37.338 180)
		(property "Reference" "PR167"
			(at 0 0 0)
			(layer "B.SilkS")
			(hide yes)
			(effects
				(font
					(size 1.27 1.27)
				)
				(justify mirror)
			)
		)
		(property "Value" "3K3R3F-GP"
			(at 0.0254 -2.0193 180)
			(unlocked yes)
			(layer "B.Fab")
			(hide yes)
			(effects
				(font
					(size 1.016 1.016)
					(thickness 0.1524)
				)
				(justify mirror)
			)
		)
		(property "Device Type" "R603H22"
			(at 0.0254 -3.5433 180)
			(unlocked yes)
			(layer "B.Fab")
			(hide yes)
			(effects
				(font
					(size 1.016 1.016)
					(thickness 0.1524)
				)
				(justify mirror)
			)
		)
		(duplicate_pad_numbers_are_jumpers no)
		(fp_line
			(start 0.2032 0)
			(end 0.4191 0)
			(stroke
				(width 0.2032)
				(type default)
			)
			(layer "B.SilkS")
		)
		(fp_line
			(start -0.4318 0)
			(end -0.2032 0)
			(stroke
				(width 0.2032)
				(type default)
			)
			(layer "B.SilkS")
		)
		(fp_rect
			(start 0.635 1.1811)
			(end -0.635 -1.1811)
			(stroke
				(width 0)
				(type default)
			)
			(fill no)
			(layer "B.CrtYd")
		)
		(fp_rect
			(start 0.635 1.1811)
			(end -0.635 -1.1811)
			(stroke
				(width 0)
				(type default)
			)
			(fill no)
			(layer "B.Fab")
		)
		(pad "1" smd custom
			(at 0 -0.6604)
			(size 0.19685 0.19685)
			(layers "B.Cu" "B.Mask" "B.Paste")
			(net "P12V")
			(options
				(clearance outline)
				(anchor circle)
			)
			(primitives
				(gr_poly
					(pts
						(arc
							(start 0.508 0.2921)
							(mid 0.478242 0.363942)
							(end 0.4064 0.3937)
						)
						(arc
							(start -0.4064 0.3937)
							(mid -0.478242 0.363942)
							(end -0.508 0.2921)
						)
						(arc
							(start -0.508 -0.2921)
							(mid -0.478242 -0.363942)
							(end -0.4064 -0.3937)
						)
						(arc
							(start 0.4064 -0.3937)
							(mid 0.478242 -0.363942)
							(end 0.508 -0.2921)
						)
					)
					(width 0)
					(fill yes)
				)
			)
		)
		(pad "2" smd custom
			(at 0 0.6604)
			(size 0.19685 0.19685)
			(layers "B.Cu" "B.Mask" "B.Paste")
			(net "VDDR_Z")
			(options
				(clearance outline)
				(anchor circle)
			)
			(primitives
				(gr_poly
					(pts
						(arc
							(start 0.508 0.2921)
							(mid 0.478242 0.363942)
							(end 0.4064 0.3937)
						)
						(arc
							(start -0.4064 0.3937)
							(mid -0.478242 0.363942)
							(end -0.508 0.2921)
						)
						(arc
							(start -0.508 -0.2921)
							(mid -0.478242 -0.363942)
							(end -0.4064 -0.3937)
						)
						(arc
							(start 0.4064 -0.3937)
							(mid 0.478242 -0.363942)
							(end 0.508 -0.2921)
						)
					)
					(width 0)
					(fill yes)
				)
			)
		)
	)
	(footprint ""
		(layer "B.Cu")
		(at 201.2696 -31.496 90)
		(property "Reference" "LED5"
			(at 0 0 90)
			(layer "B.SilkS")
			(hide yes)
			(effects
				(font
					(size 1.27 1.27)
				)
				(justify mirror)
			)
		)
		(property "Value" "LED-YG-51-GP"
			(at 0.0381 -2.6162 90)
			(unlocked yes)
			(layer "B.Fab")
			(hide yes)
			(effects
				(font
					(size 1.016 1.016)
					(thickness 0.1524)
				)
				(justify mirror)
			)
		)
		(property "Device Type" "LED1608AKH40"
			(at 0.0381 -4.1402 90)
			(unlocked yes)
			(layer "B.Fab")
			(hide yes)
			(effects
				(font
					(size 1.016 1.016)
					(thickness 0.1524)
				)
				(justify mirror)
			)
		)
		(duplicate_pad_numbers_are_jumpers no)
		(fp_line
			(start 0.5334 1.3081)
			(end -0.5334 1.3081)
			(stroke
				(width 0.254)
				(type default)
			)
			(layer "B.SilkS")
		)
		(fp_rect
			(start 0.6604 1.1811)
			(end -0.6604 -1.1811)
			(stroke
				(width 0)
				(type default)
			)
			(fill no)
			(layer "B.CrtYd")
		)
		(fp_rect
			(start 0.6604 1.1811)
			(end -0.6604 -1.1811)
			(stroke
				(width 0)
				(type default)
			)
			(fill no)
			(layer "B.Fab")
		)
		(pad "A" smd rect
			(at 0 -0.652526 270)
			(size 1.0668 0.8128)
			(layers "B.Cu" "B.Mask" "B.Paste")
			(net "PORT80_R_BIT0")
		)
		(pad "K" smd rect
			(at 0 0.652526 270)
			(size 1.0668 0.8128)
			(layers "B.Cu" "B.Mask" "B.Paste")
			(net "PORT80_BIT0")
		)
	)
	(footprint ""
		(layer "B.Cu")
		(at 67.437 -17.78 90)
		(property "Reference" "PR180"
			(at 0 0 90)
			(layer "B.SilkS")
			(hide yes)
			(effects
				(font
					(size 1.27 1.27)
				)
				(justify mirror)
			)
		)
		(property "Value" "0R2J-2-GP"
			(at -1.7907 -1.1176 90)
			(unlocked yes)
			(layer "B.Fab")
			(hide yes)
			(effects
				(font
					(size 1.016 1.016)
					(thickness 0.1524)
				)
				(justify mirror)
			)
		)
		(property "Device Type" "R402H16"
			(at -1.7907 -2.6416 90)
			(unlocked yes)
			(layer "B.Fab")
			(hide yes)
			(effects
				(font
					(size 1.016 1.016)
					(thickness 0.1524)
				)
				(justify mirror)
			)
		)
		(duplicate_pad_numbers_are_jumpers no)
		(fp_rect
			(start 0.381 0.8382)
			(end -0.381 -0.8382)
			(stroke
				(width 0)
				(type default)
			)
			(fill no)
			(layer "B.CrtYd")
		)
		(fp_rect
			(start 0.381 0.8382)
			(end -0.381 -0.8382)
			(stroke
				(width 0)
				(type default)
			)
			(fill no)
			(layer "B.Fab")
		)
		(pad "1" smd custom
			(at 0 -0.4318 270)
			(size 0.127 0.127)
			(layers "B.Cu" "B.Mask" "B.Paste")
			(net "VR_FB_R_P1V8_STBY")
			(options
				(clearance outline)
				(anchor circle)
			)
			(primitives
				(gr_poly
					(pts
						(arc
							(start -0.2032 0.2794)
							(mid -0.239121 0.264521)
							(end -0.254 0.2286)
						)
						(arc
							(start -0.254 -0.2286)
							(mid -0.239121 -0.264521)
							(end -0.2032 -0.2794)
						)
						(arc
							(start 0.2032 -0.2794)
							(mid 0.239121 -0.264521)
							(end 0.254 -0.2286)
						)
						(arc
							(start 0.254 0.2286)
							(mid 0.239121 0.264521)
							(end 0.2032 0.2794)
						)
					)
					(width 0)
					(fill yes)
				)
			)
		)
		(pad "2" smd custom
			(at 0 0.4318 270)
			(size 0.127 0.127)
			(layers "B.Cu" "B.Mask" "B.Paste")
			(net "P1V8_STBY_VOUT")
			(options
				(clearance outline)
				(anchor circle)
			)
			(primitives
				(gr_poly
					(pts
						(arc
							(start -0.2032 0.2794)
							(mid -0.239121 0.264521)
							(end -0.254 0.2286)
						)
						(arc
							(start -0.254 -0.2286)
							(mid -0.239121 -0.264521)
							(end -0.2032 -0.2794)
						)
						(arc
							(start 0.2032 -0.2794)
							(mid 0.239121 -0.264521)
							(end 0.254 -0.2286)
						)
						(arc
							(start 0.254 0.2286)
							(mid 0.239121 0.264521)
							(end 0.2032 0.2794)
						)
					)
					(width 0)
					(fill yes)
				)
			)
		)
	)
	(footprint ""
		(layer "B.Cu")
		(at 77.343 -56.007)
		(property "Reference" "C71"
			(at 0 0 0)
			(layer "B.SilkS")
			(hide yes)
			(effects
				(font
					(size 1.27 1.27)
				)
				(justify mirror)
			)
		)
		(property "Value" "SCD1U16V2KX-3GP"
			(at -1.1811 -2.7051 0)
			(unlocked yes)
			(layer "B.Fab")
			(hide yes)
			(effects
				(font
					(size 1.016 1.016)
					(thickness 0.1524)
				)
				(justify mirror)
			)
		)
		(property "Device Type" "C402H22"
			(at -1.1811 -4.2291 0)
			(unlocked yes)
			(layer "B.Fab")
			(hide yes)
			(effects
				(font
					(size 1.016 1.016)
					(thickness 0.1524)
				)
				(justify mirror)
			)
		)
		(duplicate_pad_numbers_are_jumpers no)
		(fp_rect
			(start 0.381 0.7366)
			(end -0.381 -0.7366)
			(stroke
				(width 0)
				(type default)
			)
			(fill no)
			(layer "B.CrtYd")
		)
		(fp_rect
			(start 0.381 0.7366)
			(end -0.381 -0.7366)
			(stroke
				(width 0)
				(type default)
			)
			(fill no)
			(layer "B.Fab")
		)
		(pad "1" smd custom
			(at 0 -0.4572 180)
			(size 0.1143 0.1143)
			(layers "B.Cu" "B.Mask" "B.Paste")
			(net "P3V3_STBY")
			(options
				(clearance outline)
				(anchor circle)
			)
			(primitives
				(gr_poly
					(pts
						(arc
							(start -0.254 0.1778)
							(mid -0.239121 0.213721)
							(end -0.2032 0.2286)
						)
						(arc
							(start 0.2032 0.2286)
							(mid 0.239121 0.213721)
							(end 0.254 0.1778)
						)
						(arc
							(start 0.254 -0.1778)
							(mid 0.239121 -0.213721)
							(end 0.2032 -0.2286)
						)
						(arc
							(start -0.2032 -0.2286)
							(mid -0.239121 -0.213721)
							(end -0.254 -0.1778)
						)
					)
					(width 0)
					(fill yes)
				)
			)
		)
		(pad "2" smd custom
			(at 0 0.4572 180)
			(size 0.1143 0.1143)
			(layers "B.Cu" "B.Mask" "B.Paste")
			(net "GND")
			(options
				(clearance outline)
				(anchor circle)
			)
			(primitives
				(gr_poly
					(pts
						(arc
							(start -0.254 0.1778)
							(mid -0.239121 0.213721)
							(end -0.2032 0.2286)
						)
						(arc
							(start 0.2032 0.2286)
							(mid 0.239121 0.213721)
							(end 0.254 0.1778)
						)
						(arc
							(start 0.254 -0.1778)
							(mid 0.239121 -0.213721)
							(end 0.2032 -0.2286)
						)
						(arc
							(start -0.2032 -0.2286)
							(mid -0.239121 -0.213721)
							(end -0.254 -0.1778)
						)
					)
					(width 0)
					(fill yes)
				)
			)
		)
	)
	(footprint ""
		(layer "B.Cu")
		(at 130.429 -31.115 90)
		(property "Reference" "C140"
			(at 0 0 90)
			(layer "B.SilkS")
			(hide yes)
			(effects
				(font
					(size 1.27 1.27)
				)
				(justify mirror)
			)
		)
		(property "Value" "SCD1U10V2KX-5GP"
			(at -1.1811 -2.7051 90)
			(unlocked yes)
			(layer "B.Fab")
			(hide yes)
			(effects
				(font
					(size 1.016 1.016)
					(thickness 0.1524)
				)
				(justify mirror)
			)
		)
		(property "Device Type" "C402H22"
			(at -1.1811 -4.2291 90)
			(unlocked yes)
			(layer "B.Fab")
			(hide yes)
			(effects
				(font
					(size 1.016 1.016)
					(thickness 0.1524)
				)
				(justify mirror)
			)
		)
		(duplicate_pad_numbers_are_jumpers no)
		(fp_rect
			(start 0.381 0.7366)
			(end -0.381 -0.7366)
			(stroke
				(width 0)
				(type default)
			)
			(fill no)
			(layer "B.CrtYd")
		)
		(fp_rect
			(start 0.381 0.7366)
			(end -0.381 -0.7366)
			(stroke
				(width 0)
				(type default)
			)
			(fill no)
			(layer "B.Fab")
		)
		(pad "1" smd custom
			(at 0 -0.4572 270)
			(size 0.1143 0.1143)
			(layers "B.Cu" "B.Mask" "B.Paste")
			(net "P3V3_STBY")
			(options
				(clearance outline)
				(anchor circle)
			)
			(primitives
				(gr_poly
					(pts
						(arc
							(start -0.254 0.1778)
							(mid -0.239121 0.213721)
							(end -0.2032 0.2286)
						)
						(arc
							(start 0.2032 0.2286)
							(mid 0.239121 0.213721)
							(end 0.254 0.1778)
						)
						(arc
							(start 0.254 -0.1778)
							(mid 0.239121 -0.213721)
							(end 0.2032 -0.2286)
						)
						(arc
							(start -0.2032 -0.2286)
							(mid -0.239121 -0.213721)
							(end -0.254 -0.1778)
						)
					)
					(width 0)
					(fill yes)
				)
			)
		)
		(pad "2" smd custom
			(at 0 0.4572 270)
			(size 0.1143 0.1143)
			(layers "B.Cu" "B.Mask" "B.Paste")
			(net "GND")
			(options
				(clearance outline)
				(anchor circle)
			)
			(primitives
				(gr_poly
					(pts
						(arc
							(start -0.254 0.1778)
							(mid -0.239121 0.213721)
							(end -0.2032 0.2286)
						)
						(arc
							(start 0.2032 0.2286)
							(mid 0.239121 0.213721)
							(end 0.254 0.1778)
						)
						(arc
							(start 0.254 -0.1778)
							(mid 0.239121 -0.213721)
							(end 0.2032 -0.2286)
						)
						(arc
							(start -0.2032 -0.2286)
							(mid -0.239121 -0.213721)
							(end -0.254 -0.1778)
						)
					)
					(width 0)
					(fill yes)
				)
			)
		)
	)
	(footprint ""
		(layer "B.Cu")
		(at 89.535 -44.577 180)
		(property "Reference" "C160"
			(at 0 0 0)
			(layer "B.SilkS")
			(hide yes)
			(effects
				(font
					(size 1.27 1.27)
				)
				(justify mirror)
			)
		)
		(property "Value" "SC1U10V2KX-1GP"
			(at -1.1811 -2.7051 180)
			(unlocked yes)
			(layer "B.Fab")
			(hide yes)
			(effects
				(font
					(size 1.016 1.016)
					(thickness 0.1524)
				)
				(justify mirror)
			)
		)
		(property "Device Type" "C402H22"
			(at -1.1811 -4.2291 180)
			(unlocked yes)
			(layer "B.Fab")
			(hide yes)
			(effects
				(font
					(size 1.016 1.016)
					(thickness 0.1524)
				)
				(justify mirror)
			)
		)
		(duplicate_pad_numbers_are_jumpers no)
		(fp_rect
			(start 0.381 0.7366)
			(end -0.381 -0.7366)
			(stroke
				(width 0)
				(type default)
			)
			(fill no)
			(layer "B.CrtYd")
		)
		(fp_rect
			(start 0.381 0.7366)
			(end -0.381 -0.7366)
			(stroke
				(width 0)
				(type default)
			)
			(fill no)
			(layer "B.Fab")
		)
		(pad "1" smd custom
			(at 0 -0.4572)
			(size 0.1143 0.1143)
			(layers "B.Cu" "B.Mask" "B.Paste")
			(net "P1V8_STBY")
			(options
				(clearance outline)
				(anchor circle)
			)
			(primitives
				(gr_poly
					(pts
						(arc
							(start -0.254 0.1778)
							(mid -0.239121 0.213721)
							(end -0.2032 0.2286)
						)
						(arc
							(start 0.2032 0.2286)
							(mid 0.239121 0.213721)
							(end 0.254 0.1778)
						)
						(arc
							(start 0.254 -0.1778)
							(mid 0.239121 -0.213721)
							(end 0.2032 -0.2286)
						)
						(arc
							(start -0.2032 -0.2286)
							(mid -0.239121 -0.213721)
							(end -0.254 -0.1778)
						)
					)
					(width 0)
					(fill yes)
				)
			)
		)
		(pad "2" smd custom
			(at 0 0.4572)
			(size 0.1143 0.1143)
			(layers "B.Cu" "B.Mask" "B.Paste")
			(net "GND")
			(options
				(clearance outline)
				(anchor circle)
			)
			(primitives
				(gr_poly
					(pts
						(arc
							(start -0.254 0.1778)
							(mid -0.239121 0.213721)
							(end -0.2032 0.2286)
						)
						(arc
							(start 0.2032 0.2286)
							(mid 0.239121 0.213721)
							(end 0.254 0.1778)
						)
						(arc
							(start 0.254 -0.1778)
							(mid 0.239121 -0.213721)
							(end 0.2032 -0.2286)
						)
						(arc
							(start -0.2032 -0.2286)
							(mid -0.239121 -0.213721)
							(end -0.254 -0.1778)
						)
					)
					(width 0)
					(fill yes)
				)
			)
		)
	)
	(footprint ""
		(layer "B.Cu")
		(at 188.7728 -11.812778 -90)
		(property "Reference" "R196"
			(at 0 0 90)
			(layer "B.SilkS")
			(hide yes)
			(effects
				(font
					(size 1.27 1.27)
				)
				(justify mirror)
			)
		)
		(property "Value" "4K7R2F-GP"
			(at -0.064008 -3.993896 270)
			(unlocked yes)
			(layer "B.Fab")
			(hide yes)
			(effects
				(font
					(size 1.016 1.016)
					(thickness 0.1524)
				)
				(justify mirror)
			)
		)
		(property "Device Type" "R402H16"
			(at -0.064008 -5.517896 270)
			(unlocked yes)
			(layer "B.Fab")
			(hide yes)
			(effects
				(font
					(size 1.016 1.016)
					(thickness 0.1524)
				)
				(justify mirror)
			)
		)
		(duplicate_pad_numbers_are_jumpers no)
		(fp_rect
			(start 0.381 0.8382)
			(end -0.381 -0.8382)
			(stroke
				(width 0)
				(type default)
			)
			(fill no)
			(layer "B.CrtYd")
		)
		(fp_rect
			(start 0.381 0.8382)
			(end -0.381 -0.8382)
			(stroke
				(width 0)
				(type default)
			)
			(fill no)
			(layer "B.Fab")
		)
		(pad "1" smd custom
			(at 0 -0.4318 90)
			(size 0.127 0.127)
			(layers "B.Cu" "B.Mask" "B.Paste")
			(net "P3V3_STBY")
			(options
				(clearance outline)
				(anchor circle)
			)
			(primitives
				(gr_poly
					(pts
						(arc
							(start -0.2032 0.2794)
							(mid -0.239121 0.264521)
							(end -0.254 0.2286)
						)
						(arc
							(start -0.254 -0.2286)
							(mid -0.239121 -0.264521)
							(end -0.2032 -0.2794)
						)
						(arc
							(start 0.2032 -0.2794)
							(mid 0.239121 -0.264521)
							(end 0.254 -0.2286)
						)
						(arc
							(start 0.254 0.2286)
							(mid 0.239121 0.264521)
							(end 0.2032 0.2794)
						)
					)
					(width 0)
					(fill yes)
				)
			)
		)
		(pad "2" smd custom
			(at 0 0.4318 90)
			(size 0.127 0.127)
			(layers "B.Cu" "B.Mask" "B.Paste")
			(net "CHB_0_SA0")
			(options
				(clearance outline)
				(anchor circle)
			)
			(primitives
				(gr_poly
					(pts
						(arc
							(start -0.2032 0.2794)
							(mid -0.239121 0.264521)
							(end -0.254 0.2286)
						)
						(arc
							(start -0.254 -0.2286)
							(mid -0.239121 -0.264521)
							(end -0.2032 -0.2794)
						)
						(arc
							(start 0.2032 -0.2794)
							(mid 0.239121 -0.264521)
							(end 0.254 -0.2286)
						)
						(arc
							(start 0.254 0.2286)
							(mid 0.239121 0.264521)
							(end 0.2032 0.2794)
						)
					)
					(width 0)
					(fill yes)
				)
			)
		)
	)
	(footprint ""
		(layer "B.Cu")
		(at 100.457 -57.785 90)
		(property "Reference" "R259"
			(at 0 0 90)
			(layer "B.SilkS")
			(hide yes)
			(effects
				(font
					(size 1.27 1.27)
				)
				(justify mirror)
			)
		)
		(property "Value" "0R2J-2-GP"
			(at -0.064008 -3.993896 90)
			(unlocked yes)
			(layer "B.Fab")
			(hide yes)
			(effects
				(font
					(size 1.016 1.016)
					(thickness 0.1524)
				)
				(justify mirror)
			)
		)
		(property "Device Type" "R402H16"
			(at -0.064008 -5.517896 90)
			(unlocked yes)
			(layer "B.Fab")
			(hide yes)
			(effects
				(font
					(size 1.016 1.016)
					(thickness 0.1524)
				)
				(justify mirror)
			)
		)
		(duplicate_pad_numbers_are_jumpers no)
		(fp_rect
			(start 0.381 0.8382)
			(end -0.381 -0.8382)
			(stroke
				(width 0)
				(type default)
			)
			(fill no)
			(layer "B.CrtYd")
		)
		(fp_rect
			(start 0.381 0.8382)
			(end -0.381 -0.8382)
			(stroke
				(width 0)
				(type default)
			)
			(fill no)
			(layer "B.Fab")
		)
		(pad "1" smd custom
			(at 0 -0.4318 270)
			(size 0.127 0.127)
			(layers "B.Cu" "B.Mask" "B.Paste")
			(net "M_A_RESET#")
			(options
				(clearance outline)
				(anchor circle)
			)
			(primitives
				(gr_poly
					(pts
						(arc
							(start -0.2032 0.2794)
							(mid -0.239121 0.264521)
							(end -0.254 0.2286)
						)
						(arc
							(start -0.254 -0.2286)
							(mid -0.239121 -0.264521)
							(end -0.2032 -0.2794)
						)
						(arc
							(start 0.2032 -0.2794)
							(mid 0.239121 -0.264521)
							(end 0.254 -0.2286)
						)
						(arc
							(start 0.254 0.2286)
							(mid 0.239121 0.264521)
							(end 0.2032 0.2794)
						)
					)
					(width 0)
					(fill yes)
				)
			)
		)
		(pad "2" smd custom
			(at 0 0.4318 270)
			(size 0.127 0.127)
			(layers "B.Cu" "B.Mask" "B.Paste")
			(net "M_A_R_RESET#")
			(options
				(clearance outline)
				(anchor circle)
			)
			(primitives
				(gr_poly
					(pts
						(arc
							(start -0.2032 0.2794)
							(mid -0.239121 0.264521)
							(end -0.254 0.2286)
						)
						(arc
							(start -0.254 -0.2286)
							(mid -0.239121 -0.264521)
							(end -0.2032 -0.2794)
						)
						(arc
							(start 0.2032 -0.2794)
							(mid 0.239121 -0.264521)
							(end 0.254 -0.2286)
						)
						(arc
							(start 0.254 0.2286)
							(mid 0.239121 0.264521)
							(end 0.2032 0.2794)
						)
					)
					(width 0)
					(fill yes)
				)
			)
		)
	)
	(footprint ""
		(layer "B.Cu")
		(at 75.819 -32.893)
		(property "Reference" "TP46"
			(at 0 0 0)
			(layer "B.SilkS")
			(hide yes)
			(effects
				(font
					(size 1.27 1.27)
				)
				(justify mirror)
			)
		)
		(property "Value" "TPAD24"
			(at 0 -2.9972 0)
			(unlocked yes)
			(layer "B.Fab")
			(hide yes)
			(effects
				(font
					(size 1.016 1.016)
					(thickness 0.1524)
				)
				(justify mirror)
			)
		)
		(property "Device Type" "TPAD24"
			(at 0 -4.5212 0)
			(unlocked yes)
			(layer "B.Fab")
			(hide yes)
			(effects
				(font
					(size 1.016 1.016)
					(thickness 0.1524)
				)
				(justify mirror)
			)
		)
		(duplicate_pad_numbers_are_jumpers no)
		(fp_poly
			(pts
				(arc
					(start 0.3048 0)
					(mid -0.3048 0)
					(end 0.3048 0)
				)
			)
			(stroke
				(width 0)
				(type default)
			)
			(fill no)
			(layer "B.CrtYd")
		)
		(fp_poly
			(pts
				(arc
					(start 0.6096 0)
					(mid -0.6096 0)
					(end 0.6096 0)
				)
			)
			(stroke
				(width 0)
				(type default)
			)
			(fill no)
			(layer "B.Fab")
		)
		(pad "1" smd circle
			(at 0 0 180)
			(size 0.6096 0.6096)
			(layers "B.Cu" "B.Mask" "B.Paste")
			(net "GBE_MDIO_DATA0")
		)
	)
	(footprint ""
		(layer "B.Cu")
		(at 75.438 -52.324)
		(property "Reference" "R260"
			(at 0 0 0)
			(layer "B.SilkS")
			(hide yes)
			(effects
				(font
					(size 1.27 1.27)
				)
				(justify mirror)
			)
		)
		(property "Value" "240R3-GP"
			(at 0.0254 -2.5146 0)
			(unlocked yes)
			(layer "B.Fab")
			(hide yes)
			(effects
				(font
					(size 1.016 1.016)
					(thickness 0.1524)
				)
				(justify mirror)
			)
		)
		(property "Device Type" "R603H22"
			(at 0.0254 -4.0386 0)
			(unlocked yes)
			(layer "B.Fab")
			(hide yes)
			(effects
				(font
					(size 1.016 1.016)
					(thickness 0.1524)
				)
				(justify mirror)
			)
		)
		(duplicate_pad_numbers_are_jumpers no)
		(fp_line
			(start -0.4318 0)
			(end -0.2032 0)
			(stroke
				(width 0.2032)
				(type default)
			)
			(layer "B.SilkS")
		)
		(fp_line
			(start 0.2032 0)
			(end 0.4191 0)
			(stroke
				(width 0.2032)
				(type default)
			)
			(layer "B.SilkS")
		)
		(fp_rect
			(start 0.635 1.1811)
			(end -0.635 -1.1811)
			(stroke
				(width 0)
				(type default)
			)
			(fill no)
			(layer "B.CrtYd")
		)
		(fp_rect
			(start 0.635 1.1811)
			(end -0.635 -1.1811)
			(stroke
				(width 0)
				(type default)
			)
			(fill no)
			(layer "B.Fab")
		)
		(pad "1" smd custom
			(at 0 -0.6604 180)
			(size 0.19685 0.19685)
			(layers "B.Cu" "B.Mask" "B.Paste")
			(net "P1V0")
			(options
				(clearance outline)
				(anchor circle)
			)
			(primitives
				(gr_poly
					(pts
						(arc
							(start 0.508 0.2921)
							(mid 0.478242 0.363942)
							(end 0.4064 0.3937)
						)
						(arc
							(start -0.4064 0.3937)
							(mid -0.478242 0.363942)
							(end -0.508 0.2921)
						)
						(arc
							(start -0.508 -0.2921)
							(mid -0.478242 -0.363942)
							(end -0.4064 -0.3937)
						)
						(arc
							(start 0.4064 -0.3937)
							(mid 0.478242 -0.363942)
							(end 0.508 -0.2921)
						)
					)
					(width 0)
					(fill yes)
				)
			)
		)
		(pad "2" smd custom
			(at 0 0.6604 180)
			(size 0.19685 0.19685)
			(layers "B.Cu" "B.Mask" "B.Paste")
			(net "MEMORY_CPU_HOT#")
			(options
				(clearance outline)
				(anchor circle)
			)
			(primitives
				(gr_poly
					(pts
						(arc
							(start 0.508 0.2921)
							(mid 0.478242 0.363942)
							(end 0.4064 0.3937)
						)
						(arc
							(start -0.4064 0.3937)
							(mid -0.478242 0.363942)
							(end -0.508 0.2921)
						)
						(arc
							(start -0.508 -0.2921)
							(mid -0.478242 -0.363942)
							(end -0.4064 -0.3937)
						)
						(arc
							(start 0.4064 -0.3937)
							(mid 0.478242 -0.363942)
							(end 0.508 -0.2921)
						)
					)
					(width 0)
					(fill yes)
				)
			)
		)
	)
	(footprint ""
		(layer "B.Cu")
		(at 197.4596 -64.5922 -90)
		(property "Reference" "PC168"
			(at 0 0 90)
			(layer "B.SilkS")
			(hide yes)
			(effects
				(font
					(size 1.27 1.27)
				)
				(justify mirror)
			)
		)
		(property "Value" "SC10U6D3V3MX-GP"
			(at 0.0254 -2.0193 270)
			(unlocked yes)
			(layer "B.Fab")
			(hide yes)
			(effects
				(font
					(size 1.016 1.016)
					(thickness 0.1524)
				)
				(justify mirror)
			)
		)
		(property "Device Type" "C603H38"
			(at 0.0254 -3.5433 270)
			(unlocked yes)
			(layer "B.Fab")
			(hide yes)
			(effects
				(font
					(size 1.016 1.016)
					(thickness 0.1524)
				)
				(justify mirror)
			)
		)
		(duplicate_pad_numbers_are_jumpers no)
		(fp_line
			(start 0.4064 0)
			(end -0.4064 0)
			(stroke
				(width 0.2286)
				(type default)
			)
			(layer "B.SilkS")
		)
		(fp_rect
			(start 0.635 1.1811)
			(end -0.635 -1.1811)
			(stroke
				(width 0)
				(type default)
			)
			(fill no)
			(layer "B.CrtYd")
		)
		(fp_rect
			(start 0.635 1.1811)
			(end -0.635 -1.1811)
			(stroke
				(width 0)
				(type default)
			)
			(fill no)
			(layer "B.Fab")
		)
		(pad "1" smd custom
			(at 0 -0.6604 90)
			(size 0.19685 0.19685)
			(layers "B.Cu" "B.Mask" "B.Paste")
			(net "PV_VDDR")
			(options
				(clearance outline)
				(anchor circle)
			)
			(primitives
				(gr_poly
					(pts
						(arc
							(start 0.508 0.2921)
							(mid 0.478242 0.363942)
							(end 0.4064 0.3937)
						)
						(arc
							(start -0.4064 0.3937)
							(mid -0.478242 0.363942)
							(end -0.508 0.2921)
						)
						(arc
							(start -0.508 -0.2921)
							(mid -0.478242 -0.363942)
							(end -0.4064 -0.3937)
						)
						(arc
							(start 0.4064 -0.3937)
							(mid 0.478242 -0.363942)
							(end 0.508 -0.2921)
						)
					)
					(width 0)
					(fill yes)
				)
			)
		)
		(pad "2" smd custom
			(at 0 0.6604 90)
			(size 0.19685 0.19685)
			(layers "B.Cu" "B.Mask" "B.Paste")
			(net "GND")
			(options
				(clearance outline)
				(anchor circle)
			)
			(primitives
				(gr_poly
					(pts
						(arc
							(start 0.508 0.2921)
							(mid 0.478242 0.363942)
							(end 0.4064 0.3937)
						)
						(arc
							(start -0.4064 0.3937)
							(mid -0.478242 0.363942)
							(end -0.508 0.2921)
						)
						(arc
							(start -0.508 -0.2921)
							(mid -0.478242 -0.363942)
							(end -0.4064 -0.3937)
						)
						(arc
							(start 0.4064 -0.3937)
							(mid 0.478242 -0.363942)
							(end 0.508 -0.2921)
						)
					)
					(width 0)
					(fill yes)
				)
			)
		)
	)
	(footprint ""
		(layer "B.Cu")
		(at 74.041 -30.988 90)
		(property "Reference" "R121"
			(at 0 0 90)
			(layer "B.SilkS")
			(hide yes)
			(effects
				(font
					(size 1.27 1.27)
				)
				(justify mirror)
			)
		)
		(property "Value" "10KR2F-2-GP"
			(at -0.064008 -3.993896 90)
			(unlocked yes)
			(layer "B.Fab")
			(hide yes)
			(effects
				(font
					(size 1.016 1.016)
					(thickness 0.1524)
				)
				(justify mirror)
			)
		)
		(property "Device Type" "R402H16"
			(at -0.064008 -5.517896 90)
			(unlocked yes)
			(layer "B.Fab")
			(hide yes)
			(effects
				(font
					(size 1.016 1.016)
					(thickness 0.1524)
				)
				(justify mirror)
			)
		)
		(duplicate_pad_numbers_are_jumpers no)
		(fp_rect
			(start 0.381 0.8382)
			(end -0.381 -0.8382)
			(stroke
				(width 0)
				(type default)
			)
			(fill no)
			(layer "B.CrtYd")
		)
		(fp_rect
			(start 0.381 0.8382)
			(end -0.381 -0.8382)
			(stroke
				(width 0)
				(type default)
			)
			(fill no)
			(layer "B.Fab")
		)
		(pad "1" smd custom
			(at 0 -0.4318 270)
			(size 0.127 0.127)
			(layers "B.Cu" "B.Mask" "B.Paste")
			(net "P3V3_CPU")
			(options
				(clearance outline)
				(anchor circle)
			)
			(primitives
				(gr_poly
					(pts
						(arc
							(start -0.2032 0.2794)
							(mid -0.239121 0.264521)
							(end -0.254 0.2286)
						)
						(arc
							(start -0.254 -0.2286)
							(mid -0.239121 -0.264521)
							(end -0.2032 -0.2794)
						)
						(arc
							(start 0.2032 -0.2794)
							(mid 0.239121 -0.264521)
							(end 0.254 -0.2286)
						)
						(arc
							(start 0.254 0.2286)
							(mid 0.239121 0.264521)
							(end 0.2032 0.2794)
						)
					)
					(width 0)
					(fill yes)
				)
			)
		)
		(pad "2" smd custom
			(at 0 0.4318 270)
			(size 0.127 0.127)
			(layers "B.Cu" "B.Mask" "B.Paste")
			(net "SUSPWRDNACK")
			(options
				(clearance outline)
				(anchor circle)
			)
			(primitives
				(gr_poly
					(pts
						(arc
							(start -0.2032 0.2794)
							(mid -0.239121 0.264521)
							(end -0.254 0.2286)
						)
						(arc
							(start -0.254 -0.2286)
							(mid -0.239121 -0.264521)
							(end -0.2032 -0.2794)
						)
						(arc
							(start 0.2032 -0.2794)
							(mid 0.239121 -0.264521)
							(end 0.254 -0.2286)
						)
						(arc
							(start 0.254 0.2286)
							(mid 0.239121 0.264521)
							(end 0.2032 0.2794)
						)
					)
					(width 0)
					(fill yes)
				)
			)
		)
	)
	(footprint ""
		(layer "B.Cu")
		(at 95.631 -52.197 180)
		(property "Reference" "C119"
			(at 0 0 0)
			(layer "B.SilkS")
			(hide yes)
			(effects
				(font
					(size 1.27 1.27)
				)
				(justify mirror)
			)
		)
		(property "Value" "SC1U25V3KX-GP"
			(at 0 -2.8194 180)
			(unlocked yes)
			(layer "B.Fab")
			(hide yes)
			(effects
				(font
					(size 1.016 1.016)
					(thickness 0.1524)
				)
				(justify mirror)
			)
		)
		(property "Device Type" "C603H36"
			(at 0 -4.3434 180)
			(unlocked yes)
			(layer "B.Fab")
			(hide yes)
			(effects
				(font
					(size 1.016 1.016)
					(thickness 0.1524)
				)
				(justify mirror)
			)
		)
		(duplicate_pad_numbers_are_jumpers no)
		(fp_line
			(start 0.4064 0)
			(end -0.4064 0)
			(stroke
				(width 0.2286)
				(type default)
			)
			(layer "B.SilkS")
		)
		(fp_rect
			(start 0.635 1.1811)
			(end -0.635 -1.1811)
			(stroke
				(width 0)
				(type default)
			)
			(fill no)
			(layer "B.CrtYd")
		)
		(fp_rect
			(start 0.635 1.1811)
			(end -0.635 -1.1811)
			(stroke
				(width 0)
				(type default)
			)
			(fill no)
			(layer "B.Fab")
		)
		(pad "1" smd custom
			(at 0 -0.6604)
			(size 0.19685 0.19685)
			(layers "B.Cu" "B.Mask" "B.Paste")
			(net "VCCACKDDR0")
			(options
				(clearance outline)
				(anchor circle)
			)
			(primitives
				(gr_poly
					(pts
						(arc
							(start 0.508 0.2921)
							(mid 0.478242 0.363942)
							(end 0.4064 0.3937)
						)
						(arc
							(start -0.4064 0.3937)
							(mid -0.478242 0.363942)
							(end -0.508 0.2921)
						)
						(arc
							(start -0.508 -0.2921)
							(mid -0.478242 -0.363942)
							(end -0.4064 -0.3937)
						)
						(arc
							(start 0.4064 -0.3937)
							(mid 0.478242 -0.363942)
							(end 0.508 -0.2921)
						)
					)
					(width 0)
					(fill yes)
				)
			)
		)
		(pad "2" smd custom
			(at 0 0.6604)
			(size 0.19685 0.19685)
			(layers "B.Cu" "B.Mask" "B.Paste")
			(net "GND")
			(options
				(clearance outline)
				(anchor circle)
			)
			(primitives
				(gr_poly
					(pts
						(arc
							(start 0.508 0.2921)
							(mid 0.478242 0.363942)
							(end 0.4064 0.3937)
						)
						(arc
							(start -0.4064 0.3937)
							(mid -0.478242 0.363942)
							(end -0.508 0.2921)
						)
						(arc
							(start -0.508 -0.2921)
							(mid -0.478242 -0.363942)
							(end -0.4064 -0.3937)
						)
						(arc
							(start 0.4064 -0.3937)
							(mid 0.478242 -0.363942)
							(end 0.508 -0.2921)
						)
					)
					(width 0)
					(fill yes)
				)
			)
		)
	)
	(footprint ""
		(layer "B.Cu")
		(at 149.733 -59.309)
		(property "Reference" "C360"
			(at 0 0 0)
			(layer "B.SilkS")
			(hide yes)
			(effects
				(font
					(size 1.27 1.27)
				)
				(justify mirror)
			)
		)
		(property "Value" "SC47U6D3V5MX-1-GP"
			(at 0 -4.9022 0)
			(unlocked yes)
			(layer "B.Fab")
			(hide yes)
			(effects
				(font
					(size 1.016 1.016)
					(thickness 0.1524)
				)
				(justify mirror)
			)
		)
		(property "Device Type" "C805H54"
			(at 0 -6.8072 0)
			(unlocked yes)
			(layer "B.Fab")
			(hide yes)
			(effects
				(font
					(size 1.016 1.016)
					(thickness 0.1524)
				)
				(justify mirror)
			)
		)
		(duplicate_pad_numbers_are_jumpers no)
		(fp_line
			(start -0.6096 0)
			(end 0.6096 0)
			(stroke
				(width 0.3048)
				(type default)
			)
			(layer "B.SilkS")
		)
		(fp_poly
			(pts
				(xy 0.9017 1.4351) (xy -0.9017 1.4351) (xy -0.9017 -1.4351) (xy 0.9017 -1.4351)
			)
			(stroke
				(width 0)
				(type default)
			)
			(fill no)
			(layer "B.CrtYd")
		)
		(fp_poly
			(pts
				(xy -0.9017 1.4351) (xy -0.9017 -1.4351) (xy 0.9017 -1.4351) (xy 0.9017 1.4351)
			)
			(stroke
				(width 0)
				(type default)
			)
			(fill no)
			(layer "B.Fab")
		)
		(pad "1" smd rect
			(at 0 -0.8382 180)
			(size 1.5494 0.9398)
			(layers "B.Cu" "B.Mask" "B.Paste")
			(net "PV_VDDR")
		)
		(pad "2" smd rect
			(at 0 0.8382 180)
			(size 1.5494 0.9398)
			(layers "B.Cu" "B.Mask" "B.Paste")
			(net "GND")
		)
	)
	(footprint ""
		(layer "B.Cu")
		(at 48.641 -14.605 90)
		(property "Reference" "R425"
			(at 0 0 90)
			(layer "B.SilkS")
			(hide yes)
			(effects
				(font
					(size 1.27 1.27)
				)
				(justify mirror)
			)
		)
		(property "Value" "43D2R2F-GP"
			(at -1.7907 -1.1176 90)
			(unlocked yes)
			(layer "B.Fab")
			(hide yes)
			(effects
				(font
					(size 1.016 1.016)
					(thickness 0.1524)
				)
				(justify mirror)
			)
		)
		(property "Device Type" "R402H16"
			(at -1.7907 -2.6416 90)
			(unlocked yes)
			(layer "B.Fab")
			(hide yes)
			(effects
				(font
					(size 1.016 1.016)
					(thickness 0.1524)
				)
				(justify mirror)
			)
		)
		(duplicate_pad_numbers_are_jumpers no)
		(fp_rect
			(start 0.381 0.8382)
			(end -0.381 -0.8382)
			(stroke
				(width 0)
				(type default)
			)
			(fill no)
			(layer "B.CrtYd")
		)
		(fp_rect
			(start 0.381 0.8382)
			(end -0.381 -0.8382)
			(stroke
				(width 0)
				(type default)
			)
			(fill no)
			(layer "B.Fab")
		)
		(pad "1" smd custom
			(at 0 -0.4318 270)
			(size 0.127 0.127)
			(layers "B.Cu" "B.Mask" "B.Paste")
			(net "CLK_100M_PCIE2_REFCLK_DP")
			(options
				(clearance outline)
				(anchor circle)
			)
			(primitives
				(gr_poly
					(pts
						(arc
							(start -0.2032 0.2794)
							(mid -0.239121 0.264521)
							(end -0.254 0.2286)
						)
						(arc
							(start -0.254 -0.2286)
							(mid -0.239121 -0.264521)
							(end -0.2032 -0.2794)
						)
						(arc
							(start 0.2032 -0.2794)
							(mid 0.239121 -0.264521)
							(end 0.254 -0.2286)
						)
						(arc
							(start 0.254 0.2286)
							(mid 0.239121 0.264521)
							(end 0.2032 0.2794)
						)
					)
					(width 0)
					(fill yes)
				)
			)
		)
		(pad "2" smd custom
			(at 0 0.4318 270)
			(size 0.127 0.127)
			(layers "B.Cu" "B.Mask" "B.Paste")
			(net "GND")
			(options
				(clearance outline)
				(anchor circle)
			)
			(primitives
				(gr_poly
					(pts
						(arc
							(start -0.2032 0.2794)
							(mid -0.239121 0.264521)
							(end -0.254 0.2286)
						)
						(arc
							(start -0.254 -0.2286)
							(mid -0.239121 -0.264521)
							(end -0.2032 -0.2794)
						)
						(arc
							(start 0.2032 -0.2794)
							(mid 0.239121 -0.264521)
							(end 0.254 -0.2286)
						)
						(arc
							(start 0.254 0.2286)
							(mid 0.239121 0.264521)
							(end 0.2032 0.2794)
						)
					)
					(width 0)
					(fill yes)
				)
			)
		)
	)
	(footprint ""
		(layer "B.Cu")
		(at 82.931 -62.865)
		(property "Reference" "R266"
			(at 0 0 0)
			(layer "B.SilkS")
			(hide yes)
			(effects
				(font
					(size 1.27 1.27)
				)
				(justify mirror)
			)
		)
		(property "Value" "240R3-GP"
			(at 0.0254 -2.5146 0)
			(unlocked yes)
			(layer "B.Fab")
			(hide yes)
			(effects
				(font
					(size 1.016 1.016)
					(thickness 0.1524)
				)
				(justify mirror)
			)
		)
		(property "Device Type" "R603H22"
			(at 0.0254 -4.0386 0)
			(unlocked yes)
			(layer "B.Fab")
			(hide yes)
			(effects
				(font
					(size 1.016 1.016)
					(thickness 0.1524)
				)
				(justify mirror)
			)
		)
		(duplicate_pad_numbers_are_jumpers no)
		(fp_line
			(start -0.4318 0)
			(end -0.2032 0)
			(stroke
				(width 0.2032)
				(type default)
			)
			(layer "B.SilkS")
		)
		(fp_line
			(start 0.2032 0)
			(end 0.4191 0)
			(stroke
				(width 0.2032)
				(type default)
			)
			(layer "B.SilkS")
		)
		(fp_rect
			(start 0.635 1.1811)
			(end -0.635 -1.1811)
			(stroke
				(width 0)
				(type default)
			)
			(fill no)
			(layer "B.CrtYd")
		)
		(fp_rect
			(start 0.635 1.1811)
			(end -0.635 -1.1811)
			(stroke
				(width 0)
				(type default)
			)
			(fill no)
			(layer "B.Fab")
		)
		(pad "1" smd custom
			(at 0 -0.6604 180)
			(size 0.19685 0.19685)
			(layers "B.Cu" "B.Mask" "B.Paste")
			(net "P1V0")
			(options
				(clearance outline)
				(anchor circle)
			)
			(primitives
				(gr_poly
					(pts
						(arc
							(start 0.508 0.2921)
							(mid 0.478242 0.363942)
							(end 0.4064 0.3937)
						)
						(arc
							(start -0.4064 0.3937)
							(mid -0.478242 0.363942)
							(end -0.508 0.2921)
						)
						(arc
							(start -0.508 -0.2921)
							(mid -0.478242 -0.363942)
							(end -0.4064 -0.3937)
						)
						(arc
							(start 0.4064 -0.3937)
							(mid 0.478242 -0.363942)
							(end 0.508 -0.2921)
						)
					)
					(width 0)
					(fill yes)
				)
			)
		)
		(pad "2" smd custom
			(at 0 0.6604 180)
			(size 0.19685 0.19685)
			(layers "B.Cu" "B.Mask" "B.Paste")
			(net "PROCESSOR_HOT#")
			(options
				(clearance outline)
				(anchor circle)
			)
			(primitives
				(gr_poly
					(pts
						(arc
							(start 0.508 0.2921)
							(mid 0.478242 0.363942)
							(end 0.4064 0.3937)
						)
						(arc
							(start -0.4064 0.3937)
							(mid -0.478242 0.363942)
							(end -0.508 0.2921)
						)
						(arc
							(start -0.508 -0.2921)
							(mid -0.478242 -0.363942)
							(end -0.4064 -0.3937)
						)
						(arc
							(start 0.4064 -0.3937)
							(mid 0.478242 -0.363942)
							(end 0.508 -0.2921)
						)
					)
					(width 0)
					(fill yes)
				)
			)
		)
	)
	(footprint ""
		(layer "B.Cu")
		(at 73.533 -52.324 -90)
		(property "Reference" "Q11"
			(at 0 0 90)
			(layer "B.SilkS")
			(hide yes)
			(effects
				(font
					(size 1.27 1.27)
				)
				(justify mirror)
			)
		)
		(property "Value" "MMBT3904TT1G-GP"
			(at 0 -9.7282 270)
			(unlocked yes)
			(layer "B.Fab")
			(hide yes)
			(effects
				(font
					(size 1.016 1.016)
					(thickness 0.1524)
				)
				(justify mirror)
			)
		)
		(property "Device Type" "SC75CBE1D6H36"
			(at 0 -11.6332 270)
			(unlocked yes)
			(layer "B.Fab")
			(hide yes)
			(effects
				(font
					(size 1.016 1.016)
					(thickness 0.1524)
				)
				(justify mirror)
			)
		)
		(duplicate_pad_numbers_are_jumpers no)
		(fp_poly
			(pts
				(xy -0.381 -1.1938) (xy 0.381 -1.1938) (xy 0.381 -0.6604) (xy 1.0541 -0.6604) (xy 1.0541 0.6604)
				(xy 0.889 0.6604) (xy 0.889 1.1938) (xy -0.889 1.1938) (xy -0.889 0.6604) (xy -1.0541 0.6604) (xy -1.0541 -0.6604)
				(xy -0.381 -0.6604)
			)
			(stroke
				(width 0)
				(type default)
			)
			(fill no)
			(layer "B.CrtYd")
		)
		(fp_poly
			(pts
				(xy -0.381 -1.1938) (xy 0.381 -1.1938) (xy 0.381 -0.6604) (xy 1.0541 -0.6604) (xy 1.0541 0.6604)
				(xy 0.889 0.6604) (xy 0.889 1.1938) (xy -0.889 1.1938) (xy -0.889 0.6604) (xy -1.0541 0.6604) (xy -1.0541 -0.6604)
				(xy -0.381 -0.6604)
			)
			(stroke
				(width 0)
				(type default)
			)
			(fill no)
			(layer "B.Fab")
		)
		(pad "B" smd custom
			(at 0.508 0.6604 90)
			(size 0.127 0.127)
			(layers "B.Cu" "B.Mask" "B.Paste")
			(net "MEMORY_HOT_N_LV_B1")
			(options
				(clearance outline)
				(anchor circle)
			)
			(primitives
				(gr_poly
					(pts
						(arc
							(start -0.0508 -0.4064)
							(mid -0.194484 -0.346884)
							(end -0.254 -0.2032)
						)
						(arc
							(start -0.254 0.2032)
							(mid -0.194484 0.346884)
							(end -0.0508 0.4064)
						)
						(arc
							(start 0.0508 0.4064)
							(mid 0.194484 0.346884)
							(end 0.254 0.2032)
						)
						(arc
							(start 0.254 -0.2032)
							(mid 0.194484 -0.346884)
							(end 0.0508 -0.4064)
						)
					)
					(width 0)
					(fill yes)
				)
			)
		)
		(pad "C" smd custom
			(at 0 -0.6604 90)
			(size 0.127 0.127)
			(layers "B.Cu" "B.Mask" "B.Paste")
			(net "MEMORY_CPU_HOT#")
			(options
				(clearance outline)
				(anchor circle)
			)
			(primitives
				(gr_poly
					(pts
						(arc
							(start -0.0508 -0.4064)
							(mid -0.194484 -0.346884)
							(end -0.254 -0.2032)
						)
						(arc
							(start -0.254 0.2032)
							(mid -0.194484 0.346884)
							(end -0.0508 0.4064)
						)
						(arc
							(start 0.0508 0.4064)
							(mid 0.194484 0.346884)
							(end 0.254 0.2032)
						)
						(arc
							(start 0.254 -0.2032)
							(mid 0.194484 -0.346884)
							(end 0.0508 -0.4064)
						)
					)
					(width 0)
					(fill yes)
				)
			)
		)
		(pad "E" smd custom
			(at -0.508 0.6604 90)
			(size 0.127 0.127)
			(layers "B.Cu" "B.Mask" "B.Paste")
			(net "MEMORY_HOT_LV_E1#")
			(options
				(clearance outline)
				(anchor circle)
			)
			(primitives
				(gr_poly
					(pts
						(arc
							(start -0.0508 -0.4064)
							(mid -0.194484 -0.346884)
							(end -0.254 -0.2032)
						)
						(arc
							(start -0.254 0.2032)
							(mid -0.194484 0.346884)
							(end -0.0508 0.4064)
						)
						(arc
							(start 0.0508 0.4064)
							(mid 0.194484 0.346884)
							(end 0.254 0.2032)
						)
						(arc
							(start 0.254 -0.2032)
							(mid 0.194484 -0.346884)
							(end 0.0508 -0.4064)
						)
					)
					(width 0)
					(fill yes)
				)
			)
		)
	)
	(footprint ""
		(layer "B.Cu")
		(at 101.092 -68.326)
		(property "Reference" "PR3"
			(at 0 0 0)
			(layer "B.SilkS")
			(hide yes)
			(effects
				(font
					(size 1.27 1.27)
				)
				(justify mirror)
			)
		)
		(property "Value" "0R2J-2-GP"
			(at -0.064008 -3.993896 0)
			(unlocked yes)
			(layer "B.Fab")
			(hide yes)
			(effects
				(font
					(size 1.016 1.016)
					(thickness 0.1524)
				)
				(justify mirror)
			)
		)
		(property "Device Type" "R402H16"
			(at -0.064008 -5.517896 0)
			(unlocked yes)
			(layer "B.Fab")
			(hide yes)
			(effects
				(font
					(size 1.016 1.016)
					(thickness 0.1524)
				)
				(justify mirror)
			)
		)
		(duplicate_pad_numbers_are_jumpers no)
		(fp_rect
			(start 0.381 0.8382)
			(end -0.381 -0.8382)
			(stroke
				(width 0)
				(type default)
			)
			(fill no)
			(layer "B.CrtYd")
		)
		(fp_rect
			(start 0.381 0.8382)
			(end -0.381 -0.8382)
			(stroke
				(width 0)
				(type default)
			)
			(fill no)
			(layer "B.Fab")
		)
		(pad "1" smd custom
			(at 0 -0.4318 180)
			(size 0.127 0.127)
			(layers "B.Cu" "B.Mask" "B.Paste")
			(net "P1V1")
			(options
				(clearance outline)
				(anchor circle)
			)
			(primitives
				(gr_poly
					(pts
						(arc
							(start -0.2032 0.2794)
							(mid -0.239121 0.264521)
							(end -0.254 0.2286)
						)
						(arc
							(start -0.254 -0.2286)
							(mid -0.239121 -0.264521)
							(end -0.2032 -0.2794)
						)
						(arc
							(start 0.2032 -0.2794)
							(mid 0.239121 -0.264521)
							(end 0.254 -0.2286)
						)
						(arc
							(start 0.254 0.2286)
							(mid 0.239121 0.264521)
							(end 0.2032 0.2794)
						)
					)
					(width 0)
					(fill yes)
				)
			)
		)
		(pad "2" smd custom
			(at 0 0.4318 180)
			(size 0.127 0.127)
			(layers "B.Cu" "B.Mask" "B.Paste")
			(net "VR_P1V1_VFBR")
			(options
				(clearance outline)
				(anchor circle)
			)
			(primitives
				(gr_poly
					(pts
						(arc
							(start -0.2032 0.2794)
							(mid -0.239121 0.264521)
							(end -0.254 0.2286)
						)
						(arc
							(start -0.254 -0.2286)
							(mid -0.239121 -0.264521)
							(end -0.2032 -0.2794)
						)
						(arc
							(start 0.2032 -0.2794)
							(mid 0.239121 -0.264521)
							(end 0.254 -0.2286)
						)
						(arc
							(start 0.254 0.2286)
							(mid 0.239121 0.264521)
							(end 0.2032 0.2794)
						)
					)
					(width 0)
					(fill yes)
				)
			)
		)
	)
	(footprint ""
		(layer "B.Cu")
		(at 90.424 -40.6654 180)
		(property "Reference" "C176"
			(at 0 0 0)
			(layer "B.SilkS")
			(hide yes)
			(effects
				(font
					(size 1.27 1.27)
				)
				(justify mirror)
			)
		)
		(property "Value" "SC1U10V2KX-1GP"
			(at -1.1811 -2.7051 180)
			(unlocked yes)
			(layer "B.Fab")
			(hide yes)
			(effects
				(font
					(size 1.016 1.016)
					(thickness 0.1524)
				)
				(justify mirror)
			)
		)
		(property "Device Type" "C402H22"
			(at -1.1811 -4.2291 180)
			(unlocked yes)
			(layer "B.Fab")
			(hide yes)
			(effects
				(font
					(size 1.016 1.016)
					(thickness 0.1524)
				)
				(justify mirror)
			)
		)
		(duplicate_pad_numbers_are_jumpers no)
		(fp_rect
			(start 0.381 0.7366)
			(end -0.381 -0.7366)
			(stroke
				(width 0)
				(type default)
			)
			(fill no)
			(layer "B.CrtYd")
		)
		(fp_rect
			(start 0.381 0.7366)
			(end -0.381 -0.7366)
			(stroke
				(width 0)
				(type default)
			)
			(fill no)
			(layer "B.Fab")
		)
		(pad "1" smd custom
			(at 0 -0.4572)
			(size 0.1143 0.1143)
			(layers "B.Cu" "B.Mask" "B.Paste")
			(net "P3V3")
			(options
				(clearance outline)
				(anchor circle)
			)
			(primitives
				(gr_poly
					(pts
						(arc
							(start -0.254 0.1778)
							(mid -0.239121 0.213721)
							(end -0.2032 0.2286)
						)
						(arc
							(start 0.2032 0.2286)
							(mid 0.239121 0.213721)
							(end 0.254 0.1778)
						)
						(arc
							(start 0.254 -0.1778)
							(mid 0.239121 -0.213721)
							(end 0.2032 -0.2286)
						)
						(arc
							(start -0.2032 -0.2286)
							(mid -0.239121 -0.213721)
							(end -0.254 -0.1778)
						)
					)
					(width 0)
					(fill yes)
				)
			)
		)
		(pad "2" smd custom
			(at 0 0.4572)
			(size 0.1143 0.1143)
			(layers "B.Cu" "B.Mask" "B.Paste")
			(net "GND")
			(options
				(clearance outline)
				(anchor circle)
			)
			(primitives
				(gr_poly
					(pts
						(arc
							(start -0.254 0.1778)
							(mid -0.239121 0.213721)
							(end -0.2032 0.2286)
						)
						(arc
							(start 0.2032 0.2286)
							(mid 0.239121 0.213721)
							(end 0.254 0.1778)
						)
						(arc
							(start 0.254 -0.1778)
							(mid 0.239121 -0.213721)
							(end 0.2032 -0.2286)
						)
						(arc
							(start -0.2032 -0.2286)
							(mid -0.239121 -0.213721)
							(end -0.254 -0.1778)
						)
					)
					(width 0)
					(fill yes)
				)
			)
		)
	)
	(footprint ""
		(layer "B.Cu")
		(at 110.744 -27.702002)
		(property "Reference" "C237"
			(at 0 0 0)
			(layer "B.SilkS")
			(hide yes)
			(effects
				(font
					(size 1.27 1.27)
				)
				(justify mirror)
			)
		)
		(property "Value" "SC1U10V2KX-1GP"
			(at -1.1811 -2.7051 0)
			(unlocked yes)
			(layer "B.Fab")
			(hide yes)
			(effects
				(font
					(size 1.016 1.016)
					(thickness 0.1524)
				)
				(justify mirror)
			)
		)
		(property "Device Type" "C402H22"
			(at -1.1811 -4.2291 0)
			(unlocked yes)
			(layer "B.Fab")
			(hide yes)
			(effects
				(font
					(size 1.016 1.016)
					(thickness 0.1524)
				)
				(justify mirror)
			)
		)
		(duplicate_pad_numbers_are_jumpers no)
		(fp_rect
			(start 0.381 0.7366)
			(end -0.381 -0.7366)
			(stroke
				(width 0)
				(type default)
			)
			(fill no)
			(layer "B.CrtYd")
		)
		(fp_rect
			(start 0.381 0.7366)
			(end -0.381 -0.7366)
			(stroke
				(width 0)
				(type default)
			)
			(fill no)
			(layer "B.Fab")
		)
		(pad "1" smd custom
			(at 0 -0.4572 180)
			(size 0.1143 0.1143)
			(layers "B.Cu" "B.Mask" "B.Paste")
			(net "PV_VDDR")
			(options
				(clearance outline)
				(anchor circle)
			)
			(primitives
				(gr_poly
					(pts
						(arc
							(start -0.254 0.1778)
							(mid -0.239121 0.213721)
							(end -0.2032 0.2286)
						)
						(arc
							(start 0.2032 0.2286)
							(mid 0.239121 0.213721)
							(end 0.254 0.1778)
						)
						(arc
							(start 0.254 -0.1778)
							(mid 0.239121 -0.213721)
							(end 0.2032 -0.2286)
						)
						(arc
							(start -0.2032 -0.2286)
							(mid -0.239121 -0.213721)
							(end -0.254 -0.1778)
						)
					)
					(width 0)
					(fill yes)
				)
			)
		)
		(pad "2" smd custom
			(at 0 0.4572 180)
			(size 0.1143 0.1143)
			(layers "B.Cu" "B.Mask" "B.Paste")
			(net "GND")
			(options
				(clearance outline)
				(anchor circle)
			)
			(primitives
				(gr_poly
					(pts
						(arc
							(start -0.254 0.1778)
							(mid -0.239121 0.213721)
							(end -0.2032 0.2286)
						)
						(arc
							(start 0.2032 0.2286)
							(mid 0.239121 0.213721)
							(end 0.254 0.1778)
						)
						(arc
							(start 0.254 -0.1778)
							(mid 0.239121 -0.213721)
							(end 0.2032 -0.2286)
						)
						(arc
							(start -0.2032 -0.2286)
							(mid -0.239121 -0.213721)
							(end -0.254 -0.1778)
						)
					)
					(width 0)
					(fill yes)
				)
			)
		)
	)
	(footprint ""
		(layer "B.Cu")
		(at 74.041 -35.941 -90)
		(property "Reference" "R81"
			(at 0 0 90)
			(layer "B.SilkS")
			(hide yes)
			(effects
				(font
					(size 1.27 1.27)
				)
				(justify mirror)
			)
		)
		(property "Value" "1KR2F-3-GP"
			(at -0.064008 -3.993896 270)
			(unlocked yes)
			(layer "B.Fab")
			(hide yes)
			(effects
				(font
					(size 1.016 1.016)
					(thickness 0.1524)
				)
				(justify mirror)
			)
		)
		(property "Device Type" "R402H16"
			(at -0.064008 -5.517896 270)
			(unlocked yes)
			(layer "B.Fab")
			(hide yes)
			(effects
				(font
					(size 1.016 1.016)
					(thickness 0.1524)
				)
				(justify mirror)
			)
		)
		(duplicate_pad_numbers_are_jumpers no)
		(fp_rect
			(start 0.381 0.8382)
			(end -0.381 -0.8382)
			(stroke
				(width 0)
				(type default)
			)
			(fill no)
			(layer "B.CrtYd")
		)
		(fp_rect
			(start 0.381 0.8382)
			(end -0.381 -0.8382)
			(stroke
				(width 0)
				(type default)
			)
			(fill no)
			(layer "B.Fab")
		)
		(pad "1" smd custom
			(at 0 -0.4318 90)
			(size 0.127 0.127)
			(layers "B.Cu" "B.Mask" "B.Paste")
			(net "FLEX_CLK_SE1")
			(options
				(clearance outline)
				(anchor circle)
			)
			(primitives
				(gr_poly
					(pts
						(arc
							(start -0.2032 0.2794)
							(mid -0.239121 0.264521)
							(end -0.254 0.2286)
						)
						(arc
							(start -0.254 -0.2286)
							(mid -0.239121 -0.264521)
							(end -0.2032 -0.2794)
						)
						(arc
							(start 0.2032 -0.2794)
							(mid 0.239121 -0.264521)
							(end 0.254 -0.2286)
						)
						(arc
							(start 0.254 0.2286)
							(mid 0.239121 0.264521)
							(end 0.2032 0.2794)
						)
					)
					(width 0)
					(fill yes)
				)
			)
		)
		(pad "2" smd custom
			(at 0 0.4318 90)
			(size 0.127 0.127)
			(layers "B.Cu" "B.Mask" "B.Paste")
			(net "GND")
			(options
				(clearance outline)
				(anchor circle)
			)
			(primitives
				(gr_poly
					(pts
						(arc
							(start -0.2032 0.2794)
							(mid -0.239121 0.264521)
							(end -0.254 0.2286)
						)
						(arc
							(start -0.254 -0.2286)
							(mid -0.239121 -0.264521)
							(end -0.2032 -0.2794)
						)
						(arc
							(start 0.2032 -0.2794)
							(mid 0.239121 -0.264521)
							(end 0.254 -0.2286)
						)
						(arc
							(start 0.254 0.2286)
							(mid 0.239121 0.264521)
							(end 0.2032 0.2794)
						)
					)
					(width 0)
					(fill yes)
				)
			)
		)
	)
	(footprint ""
		(layer "B.Cu")
		(at 5.6642 -38.0238 -90)
		(property "Reference" "PC186"
			(at 0 0 90)
			(layer "B.SilkS")
			(hide yes)
			(effects
				(font
					(size 1.27 1.27)
				)
				(justify mirror)
			)
		)
		(property "Value" "SC22U25V5MX-GP"
			(at 0 -4.9022 270)
			(unlocked yes)
			(layer "B.Fab")
			(hide yes)
			(effects
				(font
					(size 1.016 1.016)
					(thickness 0.1524)
				)
				(justify mirror)
			)
		)
		(property "Device Type" "C805H58"
			(at 0 -6.8072 270)
			(unlocked yes)
			(layer "B.Fab")
			(hide yes)
			(effects
				(font
					(size 1.016 1.016)
					(thickness 0.1524)
				)
				(justify mirror)
			)
		)
		(duplicate_pad_numbers_are_jumpers no)
		(fp_line
			(start -0.6096 0)
			(end 0.6096 0)
			(stroke
				(width 0.3048)
				(type default)
			)
			(layer "B.SilkS")
		)
		(fp_poly
			(pts
				(xy 0.9017 1.4351) (xy -0.9017 1.4351) (xy -0.9017 -1.4351) (xy 0.9017 -1.4351)
			)
			(stroke
				(width 0)
				(type default)
			)
			(fill no)
			(layer "B.CrtYd")
		)
		(fp_poly
			(pts
				(xy -0.9017 1.4351) (xy -0.9017 -1.4351) (xy 0.9017 -1.4351) (xy 0.9017 1.4351)
			)
			(stroke
				(width 0)
				(type default)
			)
			(fill no)
			(layer "B.Fab")
		)
		(pad "1" smd rect
			(at 0 -0.8382 90)
			(size 1.5494 0.9398)
			(layers "B.Cu" "B.Mask" "B.Paste")
			(net "P3V3_STBY_VIN")
		)
		(pad "2" smd rect
			(at 0 0.8382 90)
			(size 1.5494 0.9398)
			(layers "B.Cu" "B.Mask" "B.Paste")
			(net "GND")
		)
	)
	(footprint ""
		(layer "B.Cu")
		(at 78.613 -38.4302 90)
		(property "Reference" "R330"
			(at 0 0 90)
			(layer "B.SilkS")
			(hide yes)
			(effects
				(font
					(size 1.27 1.27)
				)
				(justify mirror)
			)
		)
		(property "Value" "22R2F-1-GP"
			(at -0.064008 -3.993896 90)
			(unlocked yes)
			(layer "B.Fab")
			(hide yes)
			(effects
				(font
					(size 1.016 1.016)
					(thickness 0.1524)
				)
				(justify mirror)
			)
		)
		(property "Device Type" "R402H16"
			(at -0.064008 -5.517896 90)
			(unlocked yes)
			(layer "B.Fab")
			(hide yes)
			(effects
				(font
					(size 1.016 1.016)
					(thickness 0.1524)
				)
				(justify mirror)
			)
		)
		(duplicate_pad_numbers_are_jumpers no)
		(fp_rect
			(start 0.381 0.8382)
			(end -0.381 -0.8382)
			(stroke
				(width 0)
				(type default)
			)
			(fill no)
			(layer "B.CrtYd")
		)
		(fp_rect
			(start 0.381 0.8382)
			(end -0.381 -0.8382)
			(stroke
				(width 0)
				(type default)
			)
			(fill no)
			(layer "B.Fab")
		)
		(pad "1" smd custom
			(at 0 -0.4318 270)
			(size 0.127 0.127)
			(layers "B.Cu" "B.Mask" "B.Paste")
			(net "PMU_PLTRST#")
			(options
				(clearance outline)
				(anchor circle)
			)
			(primitives
				(gr_poly
					(pts
						(arc
							(start -0.2032 0.2794)
							(mid -0.239121 0.264521)
							(end -0.254 0.2286)
						)
						(arc
							(start -0.254 -0.2286)
							(mid -0.239121 -0.264521)
							(end -0.2032 -0.2794)
						)
						(arc
							(start 0.2032 -0.2794)
							(mid 0.239121 -0.264521)
							(end 0.254 -0.2286)
						)
						(arc
							(start 0.254 0.2286)
							(mid 0.239121 0.264521)
							(end 0.2032 0.2794)
						)
					)
					(width 0)
					(fill yes)
				)
			)
		)
		(pad "2" smd custom
			(at 0 0.4318 270)
			(size 0.127 0.127)
			(layers "B.Cu" "B.Mask" "B.Paste")
			(net "PMU_PLTRST_R#")
			(options
				(clearance outline)
				(anchor circle)
			)
			(primitives
				(gr_poly
					(pts
						(arc
							(start -0.2032 0.2794)
							(mid -0.239121 0.264521)
							(end -0.254 0.2286)
						)
						(arc
							(start -0.254 -0.2286)
							(mid -0.239121 -0.264521)
							(end -0.2032 -0.2794)
						)
						(arc
							(start 0.2032 -0.2794)
							(mid 0.239121 -0.264521)
							(end 0.254 -0.2286)
						)
						(arc
							(start 0.254 0.2286)
							(mid 0.239121 0.264521)
							(end 0.2032 0.2794)
						)
					)
					(width 0)
					(fill yes)
				)
			)
		)
	)
	(footprint ""
		(layer "B.Cu")
		(at 45.3644 -28.321)
		(property "Reference" "R437"
			(at 0 0 0)
			(layer "B.SilkS")
			(hide yes)
			(effects
				(font
					(size 1.27 1.27)
				)
				(justify mirror)
			)
		)
		(property "Value" "4K7R2F-GP"
			(at -1.7907 -1.1176 0)
			(unlocked yes)
			(layer "B.Fab")
			(hide yes)
			(effects
				(font
					(size 1.016 1.016)
					(thickness 0.1524)
				)
				(justify mirror)
			)
		)
		(property "Device Type" "R402H16"
			(at -1.7907 -2.6416 0)
			(unlocked yes)
			(layer "B.Fab")
			(hide yes)
			(effects
				(font
					(size 1.016 1.016)
					(thickness 0.1524)
				)
				(justify mirror)
			)
		)
		(duplicate_pad_numbers_are_jumpers no)
		(fp_rect
			(start 0.381 0.8382)
			(end -0.381 -0.8382)
			(stroke
				(width 0)
				(type default)
			)
			(fill no)
			(layer "B.CrtYd")
		)
		(fp_rect
			(start 0.381 0.8382)
			(end -0.381 -0.8382)
			(stroke
				(width 0)
				(type default)
			)
			(fill no)
			(layer "B.Fab")
		)
		(pad "1" smd custom
			(at 0 -0.4318 180)
			(size 0.127 0.127)
			(layers "B.Cu" "B.Mask" "B.Paste")
			(net "P3V3")
			(options
				(clearance outline)
				(anchor circle)
			)
			(primitives
				(gr_poly
					(pts
						(arc
							(start -0.2032 0.2794)
							(mid -0.239121 0.264521)
							(end -0.254 0.2286)
						)
						(arc
							(start -0.254 -0.2286)
							(mid -0.239121 -0.264521)
							(end -0.2032 -0.2794)
						)
						(arc
							(start 0.2032 -0.2794)
							(mid 0.239121 -0.264521)
							(end 0.254 -0.2286)
						)
						(arc
							(start 0.254 0.2286)
							(mid 0.239121 0.264521)
							(end 0.2032 0.2794)
						)
					)
					(width 0)
					(fill yes)
				)
			)
		)
		(pad "2" smd custom
			(at 0 0.4318 180)
			(size 0.127 0.127)
			(layers "B.Cu" "B.Mask" "B.Paste")
			(net "CLKBUFF_OE5#")
			(options
				(clearance outline)
				(anchor circle)
			)
			(primitives
				(gr_poly
					(pts
						(arc
							(start -0.2032 0.2794)
							(mid -0.239121 0.264521)
							(end -0.254 0.2286)
						)
						(arc
							(start -0.254 -0.2286)
							(mid -0.239121 -0.264521)
							(end -0.2032 -0.2794)
						)
						(arc
							(start 0.2032 -0.2794)
							(mid 0.239121 -0.264521)
							(end 0.254 -0.2286)
						)
						(arc
							(start 0.254 0.2286)
							(mid 0.239121 0.264521)
							(end 0.2032 0.2794)
						)
					)
					(width 0)
					(fill yes)
				)
			)
		)
	)
	(footprint ""
		(layer "B.Cu")
		(at 20.955 -12.7)
		(property "Reference" "C286"
			(at 0 0 0)
			(layer "B.SilkS")
			(hide yes)
			(effects
				(font
					(size 1.27 1.27)
				)
				(justify mirror)
			)
		)
		(property "Value" "SCD1U16V2KX-3GP"
			(at -1.1811 -2.7051 0)
			(unlocked yes)
			(layer "B.Fab")
			(hide yes)
			(effects
				(font
					(size 1.016 1.016)
					(thickness 0.1524)
				)
				(justify mirror)
			)
		)
		(property "Device Type" "C402H22"
			(at -1.1811 -4.2291 0)
			(unlocked yes)
			(layer "B.Fab")
			(hide yes)
			(effects
				(font
					(size 1.016 1.016)
					(thickness 0.1524)
				)
				(justify mirror)
			)
		)
		(duplicate_pad_numbers_are_jumpers no)
		(fp_rect
			(start 0.381 0.7366)
			(end -0.381 -0.7366)
			(stroke
				(width 0)
				(type default)
			)
			(fill no)
			(layer "B.CrtYd")
		)
		(fp_rect
			(start 0.381 0.7366)
			(end -0.381 -0.7366)
			(stroke
				(width 0)
				(type default)
			)
			(fill no)
			(layer "B.Fab")
		)
		(pad "1" smd custom
			(at 0 -0.4572 180)
			(size 0.1143 0.1143)
			(layers "B.Cu" "B.Mask" "B.Paste")
			(net "P2E_CPU_ETH10G_C_TX_DP11")
			(options
				(clearance outline)
				(anchor circle)
			)
			(primitives
				(gr_poly
					(pts
						(arc
							(start -0.254 0.1778)
							(mid -0.239121 0.213721)
							(end -0.2032 0.2286)
						)
						(arc
							(start 0.2032 0.2286)
							(mid 0.239121 0.213721)
							(end 0.254 0.1778)
						)
						(arc
							(start 0.254 -0.1778)
							(mid 0.239121 -0.213721)
							(end 0.2032 -0.2286)
						)
						(arc
							(start -0.2032 -0.2286)
							(mid -0.239121 -0.213721)
							(end -0.254 -0.1778)
						)
					)
					(width 0)
					(fill yes)
				)
			)
		)
		(pad "2" smd custom
			(at 0 0.4572 180)
			(size 0.1143 0.1143)
			(layers "B.Cu" "B.Mask" "B.Paste")
			(net "P2E_CPU_ETH10G_TX_DP11")
			(options
				(clearance outline)
				(anchor circle)
			)
			(primitives
				(gr_poly
					(pts
						(arc
							(start -0.254 0.1778)
							(mid -0.239121 0.213721)
							(end -0.2032 0.2286)
						)
						(arc
							(start 0.2032 0.2286)
							(mid 0.239121 0.213721)
							(end 0.254 0.1778)
						)
						(arc
							(start 0.254 -0.1778)
							(mid 0.239121 -0.213721)
							(end 0.2032 -0.2286)
						)
						(arc
							(start -0.2032 -0.2286)
							(mid -0.239121 -0.213721)
							(end -0.254 -0.1778)
						)
					)
					(width 0)
					(fill yes)
				)
			)
		)
	)
	(footprint ""
		(layer "B.Cu")
		(at 119.38 -60.579 -90)
		(property "Reference" "C104"
			(at 0 0 90)
			(layer "B.SilkS")
			(hide yes)
			(effects
				(font
					(size 1.27 1.27)
				)
				(justify mirror)
			)
		)
		(property "Value" "SC10U6D3V3MX-GP"
			(at 0 -2.8194 270)
			(unlocked yes)
			(layer "B.Fab")
			(hide yes)
			(effects
				(font
					(size 1.016 1.016)
					(thickness 0.1524)
				)
				(justify mirror)
			)
		)
		(property "Device Type" "C603H38"
			(at 0 -4.3434 270)
			(unlocked yes)
			(layer "B.Fab")
			(hide yes)
			(effects
				(font
					(size 1.016 1.016)
					(thickness 0.1524)
				)
				(justify mirror)
			)
		)
		(duplicate_pad_numbers_are_jumpers no)
		(fp_line
			(start 0.4064 0)
			(end -0.4064 0)
			(stroke
				(width 0.2286)
				(type default)
			)
			(layer "B.SilkS")
		)
		(fp_rect
			(start 0.635 1.1811)
			(end -0.635 -1.1811)
			(stroke
				(width 0)
				(type default)
			)
			(fill no)
			(layer "B.CrtYd")
		)
		(fp_rect
			(start 0.635 1.1811)
			(end -0.635 -1.1811)
			(stroke
				(width 0)
				(type default)
			)
			(fill no)
			(layer "B.Fab")
		)
		(pad "1" smd custom
			(at 0 -0.6604 90)
			(size 0.19685 0.19685)
			(layers "B.Cu" "B.Mask" "B.Paste")
			(net "PV_VTT_DDR_A")
			(options
				(clearance outline)
				(anchor circle)
			)
			(primitives
				(gr_poly
					(pts
						(arc
							(start 0.508 0.2921)
							(mid 0.478242 0.363942)
							(end 0.4064 0.3937)
						)
						(arc
							(start -0.4064 0.3937)
							(mid -0.478242 0.363942)
							(end -0.508 0.2921)
						)
						(arc
							(start -0.508 -0.2921)
							(mid -0.478242 -0.363942)
							(end -0.4064 -0.3937)
						)
						(arc
							(start 0.4064 -0.3937)
							(mid 0.478242 -0.363942)
							(end 0.508 -0.2921)
						)
					)
					(width 0)
					(fill yes)
				)
			)
		)
		(pad "2" smd custom
			(at 0 0.6604 90)
			(size 0.19685 0.19685)
			(layers "B.Cu" "B.Mask" "B.Paste")
			(net "GND")
			(options
				(clearance outline)
				(anchor circle)
			)
			(primitives
				(gr_poly
					(pts
						(arc
							(start 0.508 0.2921)
							(mid 0.478242 0.363942)
							(end 0.4064 0.3937)
						)
						(arc
							(start -0.4064 0.3937)
							(mid -0.478242 0.363942)
							(end -0.508 0.2921)
						)
						(arc
							(start -0.508 -0.2921)
							(mid -0.478242 -0.363942)
							(end -0.4064 -0.3937)
						)
						(arc
							(start 0.4064 -0.3937)
							(mid 0.478242 -0.363942)
							(end 0.508 -0.2921)
						)
					)
					(width 0)
					(fill yes)
				)
			)
		)
	)
	(footprint ""
		(layer "B.Cu")
		(at 8.509 -24.384 -90)
		(property "Reference" "PR118"
			(at 0 0 90)
			(layer "B.SilkS")
			(hide yes)
			(effects
				(font
					(size 1.27 1.27)
				)
				(justify mirror)
			)
		)
		(property "Value" "475KR2F-GP"
			(at -1.7907 -1.1176 270)
			(unlocked yes)
			(layer "B.Fab")
			(hide yes)
			(effects
				(font
					(size 1.016 1.016)
					(thickness 0.1524)
				)
				(justify mirror)
			)
		)
		(property "Device Type" "R402H16"
			(at -1.7907 -2.6416 270)
			(unlocked yes)
			(layer "B.Fab")
			(hide yes)
			(effects
				(font
					(size 1.016 1.016)
					(thickness 0.1524)
				)
				(justify mirror)
			)
		)
		(duplicate_pad_numbers_are_jumpers no)
		(fp_rect
			(start 0.381 0.8382)
			(end -0.381 -0.8382)
			(stroke
				(width 0)
				(type default)
			)
			(fill no)
			(layer "B.CrtYd")
		)
		(fp_rect
			(start 0.381 0.8382)
			(end -0.381 -0.8382)
			(stroke
				(width 0)
				(type default)
			)
			(fill no)
			(layer "B.Fab")
		)
		(pad "1" smd custom
			(at 0 -0.4318 90)
			(size 0.127 0.127)
			(layers "B.Cu" "B.Mask" "B.Paste")
			(net "P1V0_VREG")
			(options
				(clearance outline)
				(anchor circle)
			)
			(primitives
				(gr_poly
					(pts
						(arc
							(start -0.2032 0.2794)
							(mid -0.239121 0.264521)
							(end -0.254 0.2286)
						)
						(arc
							(start -0.254 -0.2286)
							(mid -0.239121 -0.264521)
							(end -0.2032 -0.2794)
						)
						(arc
							(start 0.2032 -0.2794)
							(mid 0.239121 -0.264521)
							(end 0.254 -0.2286)
						)
						(arc
							(start 0.254 0.2286)
							(mid 0.239121 0.264521)
							(end 0.2032 0.2794)
						)
					)
					(width 0)
					(fill yes)
				)
			)
		)
		(pad "2" smd custom
			(at 0 0.4318 90)
			(size 0.127 0.127)
			(layers "B.Cu" "B.Mask" "B.Paste")
			(net "P1V0_MODE")
			(options
				(clearance outline)
				(anchor circle)
			)
			(primitives
				(gr_poly
					(pts
						(arc
							(start -0.2032 0.2794)
							(mid -0.239121 0.264521)
							(end -0.254 0.2286)
						)
						(arc
							(start -0.254 -0.2286)
							(mid -0.239121 -0.264521)
							(end -0.2032 -0.2794)
						)
						(arc
							(start 0.2032 -0.2794)
							(mid 0.239121 -0.264521)
							(end 0.254 -0.2286)
						)
						(arc
							(start 0.254 0.2286)
							(mid 0.239121 0.264521)
							(end 0.2032 0.2794)
						)
					)
					(width 0)
					(fill yes)
				)
			)
		)
	)
	(footprint ""
		(layer "B.Cu")
		(at 99.187 -20.574 90)
		(property "Reference" "R381"
			(at 0 0 90)
			(layer "B.SilkS")
			(hide yes)
			(effects
				(font
					(size 1.27 1.27)
				)
				(justify mirror)
			)
		)
		(property "Value" "30D1R2F-L-GP"
			(at -0.064008 -3.993896 90)
			(unlocked yes)
			(layer "B.Fab")
			(hide yes)
			(effects
				(font
					(size 1.016 1.016)
					(thickness 0.1524)
				)
				(justify mirror)
			)
		)
		(property "Device Type" "R402H16"
			(at -0.064008 -5.517896 90)
			(unlocked yes)
			(layer "B.Fab")
			(hide yes)
			(effects
				(font
					(size 1.016 1.016)
					(thickness 0.1524)
				)
				(justify mirror)
			)
		)
		(duplicate_pad_numbers_are_jumpers no)
		(fp_rect
			(start 0.381 0.8382)
			(end -0.381 -0.8382)
			(stroke
				(width 0)
				(type default)
			)
			(fill no)
			(layer "B.CrtYd")
		)
		(fp_rect
			(start 0.381 0.8382)
			(end -0.381 -0.8382)
			(stroke
				(width 0)
				(type default)
			)
			(fill no)
			(layer "B.Fab")
		)
		(pad "1" smd custom
			(at 0 -0.4318 270)
			(size 0.127 0.127)
			(layers "B.Cu" "B.Mask" "B.Paste")
			(net "M_B_DQPU")
			(options
				(clearance outline)
				(anchor circle)
			)
			(primitives
				(gr_poly
					(pts
						(arc
							(start -0.2032 0.2794)
							(mid -0.239121 0.264521)
							(end -0.254 0.2286)
						)
						(arc
							(start -0.254 -0.2286)
							(mid -0.239121 -0.264521)
							(end -0.2032 -0.2794)
						)
						(arc
							(start 0.2032 -0.2794)
							(mid 0.239121 -0.264521)
							(end 0.254 -0.2286)
						)
						(arc
							(start 0.254 0.2286)
							(mid 0.239121 0.264521)
							(end 0.2032 0.2794)
						)
					)
					(width 0)
					(fill yes)
				)
			)
		)
		(pad "2" smd custom
			(at 0 0.4318 270)
			(size 0.127 0.127)
			(layers "B.Cu" "B.Mask" "B.Paste")
			(net "GND")
			(options
				(clearance outline)
				(anchor circle)
			)
			(primitives
				(gr_poly
					(pts
						(arc
							(start -0.2032 0.2794)
							(mid -0.239121 0.264521)
							(end -0.254 0.2286)
						)
						(arc
							(start -0.254 -0.2286)
							(mid -0.239121 -0.264521)
							(end -0.2032 -0.2794)
						)
						(arc
							(start 0.2032 -0.2794)
							(mid 0.239121 -0.264521)
							(end 0.254 -0.2286)
						)
						(arc
							(start 0.254 0.2286)
							(mid 0.239121 0.264521)
							(end 0.2032 0.2794)
						)
					)
					(width 0)
					(fill yes)
				)
			)
		)
	)
	(footprint ""
		(layer "B.Cu")
		(at 112.395 -32.274002 90)
		(property "Reference" "R353"
			(at 0 0 90)
			(layer "B.SilkS")
			(hide yes)
			(effects
				(font
					(size 1.27 1.27)
				)
				(justify mirror)
			)
		)
		(property "Value" "0R2J-2-GP"
			(at -0.064008 -3.993896 90)
			(unlocked yes)
			(layer "B.Fab")
			(hide yes)
			(effects
				(font
					(size 1.016 1.016)
					(thickness 0.1524)
				)
				(justify mirror)
			)
		)
		(property "Device Type" "R402H16"
			(at -0.064008 -5.517896 90)
			(unlocked yes)
			(layer "B.Fab")
			(hide yes)
			(effects
				(font
					(size 1.016 1.016)
					(thickness 0.1524)
				)
				(justify mirror)
			)
		)
		(duplicate_pad_numbers_are_jumpers no)
		(fp_rect
			(start 0.381 0.8382)
			(end -0.381 -0.8382)
			(stroke
				(width 0)
				(type default)
			)
			(fill no)
			(layer "B.CrtYd")
		)
		(fp_rect
			(start 0.381 0.8382)
			(end -0.381 -0.8382)
			(stroke
				(width 0)
				(type default)
			)
			(fill no)
			(layer "B.Fab")
		)
		(pad "1" smd custom
			(at 0 -0.4318 270)
			(size 0.127 0.127)
			(layers "B.Cu" "B.Mask" "B.Paste")
			(net "M_DRAM_PWROK")
			(options
				(clearance outline)
				(anchor circle)
			)
			(primitives
				(gr_poly
					(pts
						(arc
							(start -0.2032 0.2794)
							(mid -0.239121 0.264521)
							(end -0.254 0.2286)
						)
						(arc
							(start -0.254 -0.2286)
							(mid -0.239121 -0.264521)
							(end -0.2032 -0.2794)
						)
						(arc
							(start 0.2032 -0.2794)
							(mid 0.239121 -0.264521)
							(end 0.254 -0.2286)
						)
						(arc
							(start 0.254 0.2286)
							(mid 0.239121 0.264521)
							(end 0.2032 0.2794)
						)
					)
					(width 0)
					(fill yes)
				)
			)
		)
		(pad "2" smd custom
			(at 0 0.4318 270)
			(size 0.127 0.127)
			(layers "B.Cu" "B.Mask" "B.Paste")
			(net "GND")
			(options
				(clearance outline)
				(anchor circle)
			)
			(primitives
				(gr_poly
					(pts
						(arc
							(start -0.2032 0.2794)
							(mid -0.239121 0.264521)
							(end -0.254 0.2286)
						)
						(arc
							(start -0.254 -0.2286)
							(mid -0.239121 -0.264521)
							(end -0.2032 -0.2794)
						)
						(arc
							(start 0.2032 -0.2794)
							(mid 0.239121 -0.264521)
							(end 0.254 -0.2286)
						)
						(arc
							(start 0.254 0.2286)
							(mid 0.239121 0.264521)
							(end 0.2032 0.2794)
						)
					)
					(width 0)
					(fill yes)
				)
			)
		)
	)
	(footprint ""
		(layer "B.Cu")
		(at 201.295 -40.005 90)
		(property "Reference" "LED10"
			(at 0 0 90)
			(layer "B.SilkS")
			(hide yes)
			(effects
				(font
					(size 1.27 1.27)
				)
				(justify mirror)
			)
		)
		(property "Value" "LED-YG-51-GP"
			(at 0.0381 -2.6162 90)
			(unlocked yes)
			(layer "B.Fab")
			(hide yes)
			(effects
				(font
					(size 1.016 1.016)
					(thickness 0.1524)
				)
				(justify mirror)
			)
		)
		(property "Device Type" "LED1608AKH40"
			(at 0.0381 -4.1402 90)
			(unlocked yes)
			(layer "B.Fab")
			(hide yes)
			(effects
				(font
					(size 1.016 1.016)
					(thickness 0.1524)
				)
				(justify mirror)
			)
		)
		(duplicate_pad_numbers_are_jumpers no)
		(fp_line
			(start 0.5334 1.3081)
			(end -0.5334 1.3081)
			(stroke
				(width 0.254)
				(type default)
			)
			(layer "B.SilkS")
		)
		(fp_rect
			(start 0.6604 1.1811)
			(end -0.6604 -1.1811)
			(stroke
				(width 0)
				(type default)
			)
			(fill no)
			(layer "B.CrtYd")
		)
		(fp_rect
			(start 0.6604 1.1811)
			(end -0.6604 -1.1811)
			(stroke
				(width 0)
				(type default)
			)
			(fill no)
			(layer "B.Fab")
		)
		(pad "A" smd rect
			(at 0 -0.652526 270)
			(size 1.0668 0.8128)
			(layers "B.Cu" "B.Mask" "B.Paste")
			(net "PORT80_R_BIT5")
		)
		(pad "K" smd rect
			(at 0 0.652526 270)
			(size 1.0668 0.8128)
			(layers "B.Cu" "B.Mask" "B.Paste")
			(net "PORT80_BIT5")
		)
	)
	(footprint ""
		(layer "B.Cu")
		(at 187.0202 -34.8234 90)
		(property "Reference" "PC97"
			(at 0 0 90)
			(layer "B.SilkS")
			(hide yes)
			(effects
				(font
					(size 1.27 1.27)
				)
				(justify mirror)
			)
		)
		(property "Value" "SC1KP50V2KX-1GP"
			(at -1.8923 -1.2065 90)
			(unlocked yes)
			(layer "B.Fab")
			(hide yes)
			(effects
				(font
					(size 1.016 1.016)
					(thickness 0.1524)
				)
				(justify mirror)
			)
		)
		(property "Device Type" "C402H22"
			(at -1.8923 -2.7305 90)
			(unlocked yes)
			(layer "B.Fab")
			(hide yes)
			(effects
				(font
					(size 1.016 1.016)
					(thickness 0.1524)
				)
				(justify mirror)
			)
		)
		(duplicate_pad_numbers_are_jumpers no)
		(fp_rect
			(start 0.381 0.7366)
			(end -0.381 -0.7366)
			(stroke
				(width 0)
				(type default)
			)
			(fill no)
			(layer "B.CrtYd")
		)
		(fp_rect
			(start 0.381 0.7366)
			(end -0.381 -0.7366)
			(stroke
				(width 0)
				(type default)
			)
			(fill no)
			(layer "B.Fab")
		)
		(pad "1" smd custom
			(at 0 -0.4572 270)
			(size 0.1143 0.1143)
			(layers "B.Cu" "B.Mask" "B.Paste")
			(net "VR_PVDDR_A_IMON")
			(options
				(clearance outline)
				(anchor circle)
			)
			(primitives
				(gr_poly
					(pts
						(arc
							(start -0.254 0.1778)
							(mid -0.239121 0.213721)
							(end -0.2032 0.2286)
						)
						(arc
							(start 0.2032 0.2286)
							(mid 0.239121 0.213721)
							(end 0.254 0.1778)
						)
						(arc
							(start 0.254 -0.1778)
							(mid 0.239121 -0.213721)
							(end 0.2032 -0.2286)
						)
						(arc
							(start -0.2032 -0.2286)
							(mid -0.239121 -0.213721)
							(end -0.254 -0.1778)
						)
					)
					(width 0)
					(fill yes)
				)
			)
		)
		(pad "2" smd custom
			(at 0 0.4572 270)
			(size 0.1143 0.1143)
			(layers "B.Cu" "B.Mask" "B.Paste")
			(net "GND")
			(options
				(clearance outline)
				(anchor circle)
			)
			(primitives
				(gr_poly
					(pts
						(arc
							(start -0.254 0.1778)
							(mid -0.239121 0.213721)
							(end -0.2032 0.2286)
						)
						(arc
							(start 0.2032 0.2286)
							(mid 0.239121 0.213721)
							(end 0.254 0.1778)
						)
						(arc
							(start 0.254 -0.1778)
							(mid 0.239121 -0.213721)
							(end 0.2032 -0.2286)
						)
						(arc
							(start -0.2032 -0.2286)
							(mid -0.239121 -0.213721)
							(end -0.254 -0.1778)
						)
					)
					(width 0)
					(fill yes)
				)
			)
		)
	)
	(footprint ""
		(layer "B.Cu")
		(at 130.175 -56.388 180)
		(property "Reference" "PC146"
			(at 0 0 0)
			(layer "B.SilkS")
			(hide yes)
			(effects
				(font
					(size 1.27 1.27)
				)
				(justify mirror)
			)
		)
		(property "Value" "SC10U6D3V3MX-GP"
			(at 0 -2.8194 180)
			(unlocked yes)
			(layer "B.Fab")
			(hide yes)
			(effects
				(font
					(size 1.016 1.016)
					(thickness 0.1524)
				)
				(justify mirror)
			)
		)
		(property "Device Type" "C603H38"
			(at 0 -4.3434 180)
			(unlocked yes)
			(layer "B.Fab")
			(hide yes)
			(effects
				(font
					(size 1.016 1.016)
					(thickness 0.1524)
				)
				(justify mirror)
			)
		)
		(duplicate_pad_numbers_are_jumpers no)
		(fp_line
			(start 0.4064 0)
			(end -0.4064 0)
			(stroke
				(width 0.2286)
				(type default)
			)
			(layer "B.SilkS")
		)
		(fp_rect
			(start 0.635 1.1811)
			(end -0.635 -1.1811)
			(stroke
				(width 0)
				(type default)
			)
			(fill no)
			(layer "B.CrtYd")
		)
		(fp_rect
			(start 0.635 1.1811)
			(end -0.635 -1.1811)
			(stroke
				(width 0)
				(type default)
			)
			(fill no)
			(layer "B.Fab")
		)
		(pad "1" smd custom
			(at 0 -0.6604)
			(size 0.19685 0.19685)
			(layers "B.Cu" "B.Mask" "B.Paste")
			(net "GND")
			(options
				(clearance outline)
				(anchor circle)
			)
			(primitives
				(gr_poly
					(pts
						(arc
							(start 0.508 0.2921)
							(mid 0.478242 0.363942)
							(end 0.4064 0.3937)
						)
						(arc
							(start -0.4064 0.3937)
							(mid -0.478242 0.363942)
							(end -0.508 0.2921)
						)
						(arc
							(start -0.508 -0.2921)
							(mid -0.478242 -0.363942)
							(end -0.4064 -0.3937)
						)
						(arc
							(start 0.4064 -0.3937)
							(mid 0.478242 -0.363942)
							(end 0.508 -0.2921)
						)
					)
					(width 0)
					(fill yes)
				)
			)
		)
		(pad "2" smd custom
			(at 0 0.6604)
			(size 0.19685 0.19685)
			(layers "B.Cu" "B.Mask" "B.Paste")
			(net "PV_VTT_DDR_A")
			(options
				(clearance outline)
				(anchor circle)
			)
			(primitives
				(gr_poly
					(pts
						(arc
							(start 0.508 0.2921)
							(mid 0.478242 0.363942)
							(end 0.4064 0.3937)
						)
						(arc
							(start -0.4064 0.3937)
							(mid -0.478242 0.363942)
							(end -0.508 0.2921)
						)
						(arc
							(start -0.508 -0.2921)
							(mid -0.478242 -0.363942)
							(end -0.4064 -0.3937)
						)
						(arc
							(start 0.4064 -0.3937)
							(mid 0.478242 -0.363942)
							(end 0.508 -0.2921)
						)
					)
					(width 0)
					(fill yes)
				)
			)
		)
	)
	(footprint ""
		(layer "B.Cu")
		(at 190.373 -31.623 180)
		(property "Reference" "PR208"
			(at 0 0 0)
			(layer "B.SilkS")
			(hide yes)
			(effects
				(font
					(size 1.27 1.27)
				)
				(justify mirror)
			)
		)
		(property "Value" "5M1R2J-GP"
			(at -1.7907 -1.1176 180)
			(unlocked yes)
			(layer "B.Fab")
			(hide yes)
			(effects
				(font
					(size 1.016 1.016)
					(thickness 0.1524)
				)
				(justify mirror)
			)
		)
		(property "Device Type" "R402H16"
			(at -1.7907 -2.6416 180)
			(unlocked yes)
			(layer "B.Fab")
			(hide yes)
			(effects
				(font
					(size 1.016 1.016)
					(thickness 0.1524)
				)
				(justify mirror)
			)
		)
		(duplicate_pad_numbers_are_jumpers no)
		(fp_rect
			(start 0.381 0.8382)
			(end -0.381 -0.8382)
			(stroke
				(width 0)
				(type default)
			)
			(fill no)
			(layer "B.CrtYd")
		)
		(fp_rect
			(start 0.381 0.8382)
			(end -0.381 -0.8382)
			(stroke
				(width 0)
				(type default)
			)
			(fill no)
			(layer "B.Fab")
		)
		(pad "1" smd custom
			(at 0 -0.4318)
			(size 0.127 0.127)
			(layers "B.Cu" "B.Mask" "B.Paste")
			(net "VR_PVDDRA_ISUMP1")
			(options
				(clearance outline)
				(anchor circle)
			)
			(primitives
				(gr_poly
					(pts
						(arc
							(start -0.2032 0.2794)
							(mid -0.239121 0.264521)
							(end -0.254 0.2286)
						)
						(arc
							(start -0.254 -0.2286)
							(mid -0.239121 -0.264521)
							(end -0.2032 -0.2794)
						)
						(arc
							(start 0.2032 -0.2794)
							(mid 0.239121 -0.264521)
							(end 0.254 -0.2286)
						)
						(arc
							(start 0.254 0.2286)
							(mid 0.239121 0.264521)
							(end 0.2032 0.2794)
						)
					)
					(width 0)
					(fill yes)
				)
			)
		)
		(pad "2" smd custom
			(at 0 0.4318)
			(size 0.127 0.127)
			(layers "B.Cu" "B.Mask" "B.Paste")
			(net "GND")
			(options
				(clearance outline)
				(anchor circle)
			)
			(primitives
				(gr_poly
					(pts
						(arc
							(start -0.2032 0.2794)
							(mid -0.239121 0.264521)
							(end -0.254 0.2286)
						)
						(arc
							(start -0.254 -0.2286)
							(mid -0.239121 -0.264521)
							(end -0.2032 -0.2794)
						)
						(arc
							(start 0.2032 -0.2794)
							(mid 0.239121 -0.264521)
							(end 0.254 -0.2286)
						)
						(arc
							(start 0.254 0.2286)
							(mid 0.239121 0.264521)
							(end 0.2032 0.2794)
						)
					)
					(width 0)
					(fill yes)
				)
			)
		)
	)
	(footprint ""
		(layer "B.Cu")
		(at 197.4596 -62.0522 -90)
		(property "Reference" "PC156"
			(at 0 0 90)
			(layer "B.SilkS")
			(hide yes)
			(effects
				(font
					(size 1.27 1.27)
				)
				(justify mirror)
			)
		)
		(property "Value" "SC10U6D3V3MX-GP"
			(at 0.0254 -2.0193 270)
			(unlocked yes)
			(layer "B.Fab")
			(hide yes)
			(effects
				(font
					(size 1.016 1.016)
					(thickness 0.1524)
				)
				(justify mirror)
			)
		)
		(property "Device Type" "C603H38"
			(at 0.0254 -3.5433 270)
			(unlocked yes)
			(layer "B.Fab")
			(hide yes)
			(effects
				(font
					(size 1.016 1.016)
					(thickness 0.1524)
				)
				(justify mirror)
			)
		)
		(duplicate_pad_numbers_are_jumpers no)
		(fp_line
			(start 0.4064 0)
			(end -0.4064 0)
			(stroke
				(width 0.2286)
				(type default)
			)
			(layer "B.SilkS")
		)
		(fp_rect
			(start 0.635 1.1811)
			(end -0.635 -1.1811)
			(stroke
				(width 0)
				(type default)
			)
			(fill no)
			(layer "B.CrtYd")
		)
		(fp_rect
			(start 0.635 1.1811)
			(end -0.635 -1.1811)
			(stroke
				(width 0)
				(type default)
			)
			(fill no)
			(layer "B.Fab")
		)
		(pad "1" smd custom
			(at 0 -0.6604 90)
			(size 0.19685 0.19685)
			(layers "B.Cu" "B.Mask" "B.Paste")
			(net "PV_VDDR")
			(options
				(clearance outline)
				(anchor circle)
			)
			(primitives
				(gr_poly
					(pts
						(arc
							(start 0.508 0.2921)
							(mid 0.478242 0.363942)
							(end 0.4064 0.3937)
						)
						(arc
							(start -0.4064 0.3937)
							(mid -0.478242 0.363942)
							(end -0.508 0.2921)
						)
						(arc
							(start -0.508 -0.2921)
							(mid -0.478242 -0.363942)
							(end -0.4064 -0.3937)
						)
						(arc
							(start 0.4064 -0.3937)
							(mid 0.478242 -0.363942)
							(end 0.508 -0.2921)
						)
					)
					(width 0)
					(fill yes)
				)
			)
		)
		(pad "2" smd custom
			(at 0 0.6604 90)
			(size 0.19685 0.19685)
			(layers "B.Cu" "B.Mask" "B.Paste")
			(net "GND")
			(options
				(clearance outline)
				(anchor circle)
			)
			(primitives
				(gr_poly
					(pts
						(arc
							(start 0.508 0.2921)
							(mid 0.478242 0.363942)
							(end 0.4064 0.3937)
						)
						(arc
							(start -0.4064 0.3937)
							(mid -0.478242 0.363942)
							(end -0.508 0.2921)
						)
						(arc
							(start -0.508 -0.2921)
							(mid -0.478242 -0.363942)
							(end -0.4064 -0.3937)
						)
						(arc
							(start 0.4064 -0.3937)
							(mid 0.478242 -0.363942)
							(end 0.508 -0.2921)
						)
					)
					(width 0)
					(fill yes)
				)
			)
		)
	)
	(footprint ""
		(layer "B.Cu")
		(at 91.186 -43.053 180)
		(property "Reference" "C152"
			(at 0 0 0)
			(layer "B.SilkS")
			(hide yes)
			(effects
				(font
					(size 1.27 1.27)
				)
				(justify mirror)
			)
		)
		(property "Value" "SC1U10V2KX-1GP"
			(at -1.1811 -2.7051 180)
			(unlocked yes)
			(layer "B.Fab")
			(hide yes)
			(effects
				(font
					(size 1.016 1.016)
					(thickness 0.1524)
				)
				(justify mirror)
			)
		)
		(property "Device Type" "C402H22"
			(at -1.1811 -4.2291 180)
			(unlocked yes)
			(layer "B.Fab")
			(hide yes)
			(effects
				(font
					(size 1.016 1.016)
					(thickness 0.1524)
				)
				(justify mirror)
			)
		)
		(duplicate_pad_numbers_are_jumpers no)
		(fp_rect
			(start 0.381 0.7366)
			(end -0.381 -0.7366)
			(stroke
				(width 0)
				(type default)
			)
			(fill no)
			(layer "B.CrtYd")
		)
		(fp_rect
			(start 0.381 0.7366)
			(end -0.381 -0.7366)
			(stroke
				(width 0)
				(type default)
			)
			(fill no)
			(layer "B.Fab")
		)
		(pad "1" smd custom
			(at 0 -0.4572)
			(size 0.1143 0.1143)
			(layers "B.Cu" "B.Mask" "B.Paste")
			(net "P1V0_STBY")
			(options
				(clearance outline)
				(anchor circle)
			)
			(primitives
				(gr_poly
					(pts
						(arc
							(start -0.254 0.1778)
							(mid -0.239121 0.213721)
							(end -0.2032 0.2286)
						)
						(arc
							(start 0.2032 0.2286)
							(mid 0.239121 0.213721)
							(end 0.254 0.1778)
						)
						(arc
							(start 0.254 -0.1778)
							(mid 0.239121 -0.213721)
							(end 0.2032 -0.2286)
						)
						(arc
							(start -0.2032 -0.2286)
							(mid -0.239121 -0.213721)
							(end -0.254 -0.1778)
						)
					)
					(width 0)
					(fill yes)
				)
			)
		)
		(pad "2" smd custom
			(at 0 0.4572)
			(size 0.1143 0.1143)
			(layers "B.Cu" "B.Mask" "B.Paste")
			(net "GND")
			(options
				(clearance outline)
				(anchor circle)
			)
			(primitives
				(gr_poly
					(pts
						(arc
							(start -0.254 0.1778)
							(mid -0.239121 0.213721)
							(end -0.2032 0.2286)
						)
						(arc
							(start 0.2032 0.2286)
							(mid 0.239121 0.213721)
							(end 0.254 0.1778)
						)
						(arc
							(start 0.254 -0.1778)
							(mid 0.239121 -0.213721)
							(end 0.2032 -0.2286)
						)
						(arc
							(start -0.2032 -0.2286)
							(mid -0.239121 -0.213721)
							(end -0.254 -0.1778)
						)
					)
					(width 0)
					(fill yes)
				)
			)
		)
	)
	(footprint ""
		(layer "B.Cu")
		(at 197.739 -1.651 90)
		(property "Reference" "C292"
			(at 0 0 90)
			(layer "B.SilkS")
			(hide yes)
			(effects
				(font
					(size 1.27 1.27)
				)
				(justify mirror)
			)
		)
		(property "Value" "SC10U6D3V3MX-GP"
			(at 0 -2.8194 90)
			(unlocked yes)
			(layer "B.Fab")
			(hide yes)
			(effects
				(font
					(size 1.016 1.016)
					(thickness 0.1524)
				)
				(justify mirror)
			)
		)
		(property "Device Type" "C603H38"
			(at 0 -4.3434 90)
			(unlocked yes)
			(layer "B.Fab")
			(hide yes)
			(effects
				(font
					(size 1.016 1.016)
					(thickness 0.1524)
				)
				(justify mirror)
			)
		)
		(duplicate_pad_numbers_are_jumpers no)
		(fp_line
			(start 0.4064 0)
			(end -0.4064 0)
			(stroke
				(width 0.2286)
				(type default)
			)
			(layer "B.SilkS")
		)
		(fp_rect
			(start 0.635 1.1811)
			(end -0.635 -1.1811)
			(stroke
				(width 0)
				(type default)
			)
			(fill no)
			(layer "B.CrtYd")
		)
		(fp_rect
			(start 0.635 1.1811)
			(end -0.635 -1.1811)
			(stroke
				(width 0)
				(type default)
			)
			(fill no)
			(layer "B.Fab")
		)
		(pad "1" smd custom
			(at 0 -0.6604 270)
			(size 0.19685 0.19685)
			(layers "B.Cu" "B.Mask" "B.Paste")
			(net "PV_VTT_DDR_B")
			(options
				(clearance outline)
				(anchor circle)
			)
			(primitives
				(gr_poly
					(pts
						(arc
							(start 0.508 0.2921)
							(mid 0.478242 0.363942)
							(end 0.4064 0.3937)
						)
						(arc
							(start -0.4064 0.3937)
							(mid -0.478242 0.363942)
							(end -0.508 0.2921)
						)
						(arc
							(start -0.508 -0.2921)
							(mid -0.478242 -0.363942)
							(end -0.4064 -0.3937)
						)
						(arc
							(start 0.4064 -0.3937)
							(mid 0.478242 -0.363942)
							(end 0.508 -0.2921)
						)
					)
					(width 0)
					(fill yes)
				)
			)
		)
		(pad "2" smd custom
			(at 0 0.6604 270)
			(size 0.19685 0.19685)
			(layers "B.Cu" "B.Mask" "B.Paste")
			(net "GND")
			(options
				(clearance outline)
				(anchor circle)
			)
			(primitives
				(gr_poly
					(pts
						(arc
							(start 0.508 0.2921)
							(mid 0.478242 0.363942)
							(end 0.4064 0.3937)
						)
						(arc
							(start -0.4064 0.3937)
							(mid -0.478242 0.363942)
							(end -0.508 0.2921)
						)
						(arc
							(start -0.508 -0.2921)
							(mid -0.478242 -0.363942)
							(end -0.4064 -0.3937)
						)
						(arc
							(start 0.4064 -0.3937)
							(mid 0.478242 -0.363942)
							(end 0.508 -0.2921)
						)
					)
					(width 0)
					(fill yes)
				)
			)
		)
	)
	(footprint ""
		(layer "B.Cu")
		(at 128.778 -56.388)
		(property "Reference" "C112"
			(at 0 0 0)
			(layer "B.SilkS")
			(hide yes)
			(effects
				(font
					(size 1.27 1.27)
				)
				(justify mirror)
			)
		)
		(property "Value" "SC10U6D3V3MX-GP"
			(at 0 -2.8194 0)
			(unlocked yes)
			(layer "B.Fab")
			(hide yes)
			(effects
				(font
					(size 1.016 1.016)
					(thickness 0.1524)
				)
				(justify mirror)
			)
		)
		(property "Device Type" "C603H38"
			(at 0 -4.3434 0)
			(unlocked yes)
			(layer "B.Fab")
			(hide yes)
			(effects
				(font
					(size 1.016 1.016)
					(thickness 0.1524)
				)
				(justify mirror)
			)
		)
		(duplicate_pad_numbers_are_jumpers no)
		(fp_line
			(start 0.4064 0)
			(end -0.4064 0)
			(stroke
				(width 0.2286)
				(type default)
			)
			(layer "B.SilkS")
		)
		(fp_rect
			(start 0.635 1.1811)
			(end -0.635 -1.1811)
			(stroke
				(width 0)
				(type default)
			)
			(fill no)
			(layer "B.CrtYd")
		)
		(fp_rect
			(start 0.635 1.1811)
			(end -0.635 -1.1811)
			(stroke
				(width 0)
				(type default)
			)
			(fill no)
			(layer "B.Fab")
		)
		(pad "1" smd custom
			(at 0 -0.6604 180)
			(size 0.19685 0.19685)
			(layers "B.Cu" "B.Mask" "B.Paste")
			(net "PV_VTT_DDR_A")
			(options
				(clearance outline)
				(anchor circle)
			)
			(primitives
				(gr_poly
					(pts
						(arc
							(start 0.508 0.2921)
							(mid 0.478242 0.363942)
							(end 0.4064 0.3937)
						)
						(arc
							(start -0.4064 0.3937)
							(mid -0.478242 0.363942)
							(end -0.508 0.2921)
						)
						(arc
							(start -0.508 -0.2921)
							(mid -0.478242 -0.363942)
							(end -0.4064 -0.3937)
						)
						(arc
							(start 0.4064 -0.3937)
							(mid 0.478242 -0.363942)
							(end 0.508 -0.2921)
						)
					)
					(width 0)
					(fill yes)
				)
			)
		)
		(pad "2" smd custom
			(at 0 0.6604 180)
			(size 0.19685 0.19685)
			(layers "B.Cu" "B.Mask" "B.Paste")
			(net "GND")
			(options
				(clearance outline)
				(anchor circle)
			)
			(primitives
				(gr_poly
					(pts
						(arc
							(start 0.508 0.2921)
							(mid 0.478242 0.363942)
							(end 0.4064 0.3937)
						)
						(arc
							(start -0.4064 0.3937)
							(mid -0.478242 0.363942)
							(end -0.508 0.2921)
						)
						(arc
							(start -0.508 -0.2921)
							(mid -0.478242 -0.363942)
							(end -0.4064 -0.3937)
						)
						(arc
							(start 0.4064 -0.3937)
							(mid 0.478242 -0.363942)
							(end 0.508 -0.2921)
						)
					)
					(width 0)
					(fill yes)
				)
			)
		)
	)
	(footprint ""
		(layer "B.Cu")
		(at 16.764 -33.655 -90)
		(property "Reference" "PC151"
			(at 0 0 90)
			(layer "B.SilkS")
			(hide yes)
			(effects
				(font
					(size 1.27 1.27)
				)
				(justify mirror)
			)
		)
		(property "Value" "SC1U10V2KX-1GP"
			(at -1.8923 -1.2065 270)
			(unlocked yes)
			(layer "B.Fab")
			(hide yes)
			(effects
				(font
					(size 1.016 1.016)
					(thickness 0.1524)
				)
				(justify mirror)
			)
		)
		(property "Device Type" "C402H22"
			(at -1.8923 -2.7305 270)
			(unlocked yes)
			(layer "B.Fab")
			(hide yes)
			(effects
				(font
					(size 1.016 1.016)
					(thickness 0.1524)
				)
				(justify mirror)
			)
		)
		(duplicate_pad_numbers_are_jumpers no)
		(fp_rect
			(start 0.381 0.7366)
			(end -0.381 -0.7366)
			(stroke
				(width 0)
				(type default)
			)
			(fill no)
			(layer "B.CrtYd")
		)
		(fp_rect
			(start 0.381 0.7366)
			(end -0.381 -0.7366)
			(stroke
				(width 0)
				(type default)
			)
			(fill no)
			(layer "B.Fab")
		)
		(pad "1" smd custom
			(at 0 -0.4572 90)
			(size 0.1143 0.1143)
			(layers "B.Cu" "B.Mask" "B.Paste")
			(net "AGND_P3V3_STBY")
			(options
				(clearance outline)
				(anchor circle)
			)
			(primitives
				(gr_poly
					(pts
						(arc
							(start -0.254 0.1778)
							(mid -0.239121 0.213721)
							(end -0.2032 0.2286)
						)
						(arc
							(start 0.2032 0.2286)
							(mid 0.239121 0.213721)
							(end 0.254 0.1778)
						)
						(arc
							(start 0.254 -0.1778)
							(mid 0.239121 -0.213721)
							(end 0.2032 -0.2286)
						)
						(arc
							(start -0.2032 -0.2286)
							(mid -0.239121 -0.213721)
							(end -0.254 -0.1778)
						)
					)
					(width 0)
					(fill yes)
				)
			)
		)
		(pad "2" smd custom
			(at 0 0.4572 90)
			(size 0.1143 0.1143)
			(layers "B.Cu" "B.Mask" "B.Paste")
			(net "P3V3_STBY_ROVP")
			(options
				(clearance outline)
				(anchor circle)
			)
			(primitives
				(gr_poly
					(pts
						(arc
							(start -0.254 0.1778)
							(mid -0.239121 0.213721)
							(end -0.2032 0.2286)
						)
						(arc
							(start 0.2032 0.2286)
							(mid 0.239121 0.213721)
							(end 0.254 0.1778)
						)
						(arc
							(start 0.254 -0.1778)
							(mid 0.239121 -0.213721)
							(end 0.2032 -0.2286)
						)
						(arc
							(start -0.2032 -0.2286)
							(mid -0.239121 -0.213721)
							(end -0.254 -0.1778)
						)
					)
					(width 0)
					(fill yes)
				)
			)
		)
	)
	(footprint ""
		(layer "B.Cu")
		(at 70.8406 -15.4686 90)
		(property "Reference" "PC124"
			(at 0 0 90)
			(layer "B.SilkS")
			(hide yes)
			(effects
				(font
					(size 1.27 1.27)
				)
				(justify mirror)
			)
		)
		(property "Value" "SC22U6D3V5MX-2GP"
			(at 0 -4.9022 90)
			(unlocked yes)
			(layer "B.Fab")
			(hide yes)
			(effects
				(font
					(size 1.016 1.016)
					(thickness 0.1524)
				)
				(justify mirror)
			)
		)
		(property "Device Type" "C805H58"
			(at 0 -6.8072 90)
			(unlocked yes)
			(layer "B.Fab")
			(hide yes)
			(effects
				(font
					(size 1.016 1.016)
					(thickness 0.1524)
				)
				(justify mirror)
			)
		)
		(duplicate_pad_numbers_are_jumpers no)
		(fp_line
			(start -0.6096 0)
			(end 0.6096 0)
			(stroke
				(width 0.3048)
				(type default)
			)
			(layer "B.SilkS")
		)
		(fp_poly
			(pts
				(xy 0.9017 1.4351) (xy -0.9017 1.4351) (xy -0.9017 -1.4351) (xy 0.9017 -1.4351)
			)
			(stroke
				(width 0)
				(type default)
			)
			(fill no)
			(layer "B.CrtYd")
		)
		(fp_poly
			(pts
				(xy -0.9017 1.4351) (xy -0.9017 -1.4351) (xy 0.9017 -1.4351) (xy 0.9017 1.4351)
			)
			(stroke
				(width 0)
				(type default)
			)
			(fill no)
			(layer "B.Fab")
		)
		(pad "1" smd rect
			(at 0 -0.8382 270)
			(size 1.5494 0.9398)
			(layers "B.Cu" "B.Mask" "B.Paste")
			(net "P1V8_STBY_VOUT")
		)
		(pad "2" smd rect
			(at 0 0.8382 270)
			(size 1.5494 0.9398)
			(layers "B.Cu" "B.Mask" "B.Paste")
			(net "GND")
		)
	)
	(footprint ""
		(layer "B.Cu")
		(at 197.231 -66.04 90)
		(property "Reference" "R400"
			(at 0 0 90)
			(layer "B.SilkS")
			(hide yes)
			(effects
				(font
					(size 1.27 1.27)
				)
				(justify mirror)
			)
		)
		(property "Value" "300R2F-GP"
			(at -1.7907 -1.1176 90)
			(unlocked yes)
			(layer "B.Fab")
			(hide yes)
			(effects
				(font
					(size 1.016 1.016)
					(thickness 0.1524)
				)
				(justify mirror)
			)
		)
		(property "Device Type" "R402H16"
			(at -1.7907 -2.6416 90)
			(unlocked yes)
			(layer "B.Fab")
			(hide yes)
			(effects
				(font
					(size 1.016 1.016)
					(thickness 0.1524)
				)
				(justify mirror)
			)
		)
		(duplicate_pad_numbers_are_jumpers no)
		(fp_rect
			(start 0.381 0.8382)
			(end -0.381 -0.8382)
			(stroke
				(width 0)
				(type default)
			)
			(fill no)
			(layer "B.CrtYd")
		)
		(fp_rect
			(start 0.381 0.8382)
			(end -0.381 -0.8382)
			(stroke
				(width 0)
				(type default)
			)
			(fill no)
			(layer "B.Fab")
		)
		(pad "1" smd custom
			(at 0 -0.4318 270)
			(size 0.127 0.127)
			(layers "B.Cu" "B.Mask" "B.Paste")
			(net "P3V3")
			(options
				(clearance outline)
				(anchor circle)
			)
			(primitives
				(gr_poly
					(pts
						(arc
							(start -0.2032 0.2794)
							(mid -0.239121 0.264521)
							(end -0.254 0.2286)
						)
						(arc
							(start -0.254 -0.2286)
							(mid -0.239121 -0.264521)
							(end -0.2032 -0.2794)
						)
						(arc
							(start 0.2032 -0.2794)
							(mid 0.239121 -0.264521)
							(end 0.254 -0.2286)
						)
						(arc
							(start 0.254 0.2286)
							(mid 0.239121 0.264521)
							(end 0.2032 0.2794)
						)
					)
					(width 0)
					(fill yes)
				)
			)
		)
		(pad "2" smd custom
			(at 0 0.4318 270)
			(size 0.127 0.127)
			(layers "B.Cu" "B.Mask" "B.Paste")
			(net "DIAG_LED")
			(options
				(clearance outline)
				(anchor circle)
			)
			(primitives
				(gr_poly
					(pts
						(arc
							(start -0.2032 0.2794)
							(mid -0.239121 0.264521)
							(end -0.254 0.2286)
						)
						(arc
							(start -0.254 -0.2286)
							(mid -0.239121 -0.264521)
							(end -0.2032 -0.2794)
						)
						(arc
							(start 0.2032 -0.2794)
							(mid 0.239121 -0.264521)
							(end 0.254 -0.2286)
						)
						(arc
							(start 0.254 0.2286)
							(mid 0.239121 0.264521)
							(end 0.2032 0.2794)
						)
					)
					(width 0)
					(fill yes)
				)
			)
		)
	)
	(footprint ""
		(layer "B.Cu")
		(at 197.358 -38.6588 180)
		(property "Reference" "PC111"
			(at 0 0 0)
			(layer "B.SilkS")
			(hide yes)
			(effects
				(font
					(size 1.27 1.27)
				)
				(justify mirror)
			)
		)
		(property "Value" "SC10U16V6KX-2GP"
			(at -0.0127 -3.4671 180)
			(unlocked yes)
			(layer "B.Fab")
			(hide yes)
			(effects
				(font
					(size 1.016 1.016)
					(thickness 0.1524)
				)
				(justify mirror)
			)
		)
		(property "Device Type" "C1206H71"
			(at -0.0127 -4.9911 180)
			(unlocked yes)
			(layer "B.Fab")
			(hide yes)
			(effects
				(font
					(size 1.016 1.016)
					(thickness 0.1524)
				)
				(justify mirror)
			)
		)
		(duplicate_pad_numbers_are_jumpers no)
		(fp_rect
			(start 1.0541 1.9812)
			(end -1.0541 -1.9812)
			(stroke
				(width 0)
				(type default)
			)
			(fill no)
			(layer "B.CrtYd")
		)
		(fp_rect
			(start 1.0541 1.9812)
			(end -1.0541 -1.9812)
			(stroke
				(width 0)
				(type default)
			)
			(fill no)
			(layer "B.Fab")
		)
		(pad "1" smd rect
			(at 0 -1.3462)
			(size 1.8542 1.016)
			(layers "B.Cu" "B.Mask" "B.Paste")
			(net "VDDR_5VBIAS")
		)
		(pad "2" smd rect
			(at 0 1.3462)
			(size 1.8542 1.016)
			(layers "B.Cu" "B.Mask" "B.Paste")
			(net "GND")
		)
	)
	(footprint ""
		(layer "B.Cu")
		(at 118.1608 -4.445 -90)
		(property "Reference" "U41"
			(at 0 0 90)
			(layer "B.SilkS")
			(hide yes)
			(effects
				(font
					(size 1.27 1.27)
				)
				(justify mirror)
			)
		)
		(property "Value" "SNLVC1G126DCKR-GP"
			(at 0 -8.0772 270)
			(unlocked yes)
			(layer "B.Fab")
			(hide yes)
			(effects
				(font
					(size 1.016 1.016)
					(thickness 0.1524)
				)
				(justify mirror)
			)
		)
		(property "Device Type" "SC70-5H44"
			(at 0 -9.6012 270)
			(unlocked yes)
			(layer "B.Fab")
			(hide yes)
			(effects
				(font
					(size 1.016 1.016)
					(thickness 0.1524)
				)
				(justify mirror)
			)
		)
		(duplicate_pad_numbers_are_jumpers no)
		(fp_line
			(start -1.0033 0.3302)
			(end 1.0033 0.3302)
			(stroke
				(width 0.1524)
				(type default)
			)
			(layer "B.SilkS")
		)
		(fp_line
			(start 1.0033 0.3302)
			(end 1.0033 -0.3302)
			(stroke
				(width 0.1524)
				(type default)
			)
			(layer "B.SilkS")
		)
		(fp_line
			(start -1.0033 -0.3302)
			(end -1.0033 0.3302)
			(stroke
				(width 0.1524)
				(type default)
			)
			(layer "B.SilkS")
		)
		(fp_line
			(start 1.0033 -0.3302)
			(end -1.0033 -0.3302)
			(stroke
				(width 0.1524)
				(type default)
			)
			(layer "B.SilkS")
		)
		(fp_poly
			(pts
				(xy 1.0033 1.4859) (xy 1.0033 0.8001) (xy 1.1811 0.8001) (xy 1.1811 -0.8001) (xy 1.0033 -0.8001)
				(xy 1.0033 -1.4859) (xy -1.0033 -1.4859) (xy -1.0033 -0.8001) (xy -1.1811 -0.8001) (xy -1.1811 0.8001)
				(xy -1.0033 0.8001) (xy -1.0033 1.4859) (xy -0.2921 1.4859) (xy -0.2921 0.8001) (xy 0.2921 0.8001)
				(xy 0.2921 1.4859)
			)
			(stroke
				(width 0)
				(type default)
			)
			(fill no)
			(layer "B.CrtYd")
		)
		(fp_poly
			(pts
				(xy 1.0033 1.4859) (xy 1.0033 0.8001) (xy 1.1811 0.8001) (xy 1.1811 -0.8001) (xy 1.0033 -0.8001)
				(xy 1.0033 -1.4859) (xy -1.0033 -1.4859) (xy -1.0033 -0.8001) (xy -1.1811 -0.8001) (xy -1.1811 0.8001)
				(xy -1.0033 0.8001) (xy -1.0033 1.4859) (xy -0.2921 1.4859) (xy -0.2921 0.8001) (xy 0.2921 0.8001)
				(xy 0.2921 1.4859)
			)
			(stroke
				(width 0)
				(type default)
			)
			(fill no)
			(layer "B.Fab")
		)
		(pad "1" smd rect
			(at -0.65024 -0.93472 90)
			(size 0.3556 0.762)
			(layers "B.Cu" "B.Mask" "B.Paste")
			(net "P3V3")
		)
		(pad "2" smd rect
			(at 0 -0.93472 90)
			(size 0.3556 0.762)
			(layers "B.Cu" "B.Mask" "B.Paste")
			(net "CLK_GEN_PG")
		)
		(pad "3" smd rect
			(at 0.65024 -0.93472 90)
			(size 0.3556 0.762)
			(layers "B.Cu" "B.Mask" "B.Paste")
			(net "GND")
		)
		(pad "4" smd rect
			(at 0.65024 0.93472 90)
			(size 0.3556 0.762)
			(layers "B.Cu" "B.Mask" "B.Paste")
			(net "POWER_GOOD")
		)
		(pad "5" smd rect
			(at -0.65024 0.93472 90)
			(size 0.3556 0.762)
			(layers "B.Cu" "B.Mask" "B.Paste")
			(net "P3V3")
		)
	)
	(footprint ""
		(layer "B.Cu")
		(at 103.251 -51.451002 180)
		(property "Reference" "C128"
			(at 0 0 0)
			(layer "B.SilkS")
			(hide yes)
			(effects
				(font
					(size 1.27 1.27)
				)
				(justify mirror)
			)
		)
		(property "Value" "SC1U10V2KX-1GP"
			(at -1.1811 -2.7051 180)
			(unlocked yes)
			(layer "B.Fab")
			(hide yes)
			(effects
				(font
					(size 1.016 1.016)
					(thickness 0.1524)
				)
				(justify mirror)
			)
		)
		(property "Device Type" "C402H22"
			(at -1.1811 -4.2291 180)
			(unlocked yes)
			(layer "B.Fab")
			(hide yes)
			(effects
				(font
					(size 1.016 1.016)
					(thickness 0.1524)
				)
				(justify mirror)
			)
		)
		(duplicate_pad_numbers_are_jumpers no)
		(fp_rect
			(start 0.381 0.7366)
			(end -0.381 -0.7366)
			(stroke
				(width 0)
				(type default)
			)
			(fill no)
			(layer "B.CrtYd")
		)
		(fp_rect
			(start 0.381 0.7366)
			(end -0.381 -0.7366)
			(stroke
				(width 0)
				(type default)
			)
			(fill no)
			(layer "B.Fab")
		)
		(pad "1" smd custom
			(at 0 -0.4572)
			(size 0.1143 0.1143)
			(layers "B.Cu" "B.Mask" "B.Paste")
			(net "PV_VDDR")
			(options
				(clearance outline)
				(anchor circle)
			)
			(primitives
				(gr_poly
					(pts
						(arc
							(start -0.254 0.1778)
							(mid -0.239121 0.213721)
							(end -0.2032 0.2286)
						)
						(arc
							(start 0.2032 0.2286)
							(mid 0.239121 0.213721)
							(end 0.254 0.1778)
						)
						(arc
							(start 0.254 -0.1778)
							(mid 0.239121 -0.213721)
							(end 0.2032 -0.2286)
						)
						(arc
							(start -0.2032 -0.2286)
							(mid -0.239121 -0.213721)
							(end -0.254 -0.1778)
						)
					)
					(width 0)
					(fill yes)
				)
			)
		)
		(pad "2" smd custom
			(at 0 0.4572)
			(size 0.1143 0.1143)
			(layers "B.Cu" "B.Mask" "B.Paste")
			(net "GND")
			(options
				(clearance outline)
				(anchor circle)
			)
			(primitives
				(gr_poly
					(pts
						(arc
							(start -0.254 0.1778)
							(mid -0.239121 0.213721)
							(end -0.2032 0.2286)
						)
						(arc
							(start 0.2032 0.2286)
							(mid 0.239121 0.213721)
							(end 0.254 0.1778)
						)
						(arc
							(start 0.254 -0.1778)
							(mid 0.239121 -0.213721)
							(end 0.2032 -0.2286)
						)
						(arc
							(start -0.2032 -0.2286)
							(mid -0.239121 -0.213721)
							(end -0.254 -0.1778)
						)
					)
					(width 0)
					(fill yes)
				)
			)
		)
	)
	(footprint ""
		(layer "B.Cu")
		(at 15.875 -66.4718 90)
		(property "Reference" "C177"
			(at 0 0 90)
			(layer "B.SilkS")
			(hide yes)
			(effects
				(font
					(size 1.27 1.27)
				)
				(justify mirror)
			)
		)
		(property "Value" "SCD1U16V2KX-3GP"
			(at -1.8923 -1.2065 90)
			(unlocked yes)
			(layer "B.Fab")
			(hide yes)
			(effects
				(font
					(size 1.016 1.016)
					(thickness 0.1524)
				)
				(justify mirror)
			)
		)
		(property "Device Type" "C402H22"
			(at -1.8923 -2.7305 90)
			(unlocked yes)
			(layer "B.Fab")
			(hide yes)
			(effects
				(font
					(size 1.016 1.016)
					(thickness 0.1524)
				)
				(justify mirror)
			)
		)
		(duplicate_pad_numbers_are_jumpers no)
		(fp_rect
			(start 0.381 0.7366)
			(end -0.381 -0.7366)
			(stroke
				(width 0)
				(type default)
			)
			(fill no)
			(layer "B.CrtYd")
		)
		(fp_rect
			(start 0.381 0.7366)
			(end -0.381 -0.7366)
			(stroke
				(width 0)
				(type default)
			)
			(fill no)
			(layer "B.Fab")
		)
		(pad "1" smd custom
			(at 0 -0.4572 270)
			(size 0.1143 0.1143)
			(layers "B.Cu" "B.Mask" "B.Paste")
			(net "P3V3")
			(options
				(clearance outline)
				(anchor circle)
			)
			(primitives
				(gr_poly
					(pts
						(arc
							(start -0.254 0.1778)
							(mid -0.239121 0.213721)
							(end -0.2032 0.2286)
						)
						(arc
							(start 0.2032 0.2286)
							(mid 0.239121 0.213721)
							(end 0.254 0.1778)
						)
						(arc
							(start 0.254 -0.1778)
							(mid 0.239121 -0.213721)
							(end 0.2032 -0.2286)
						)
						(arc
							(start -0.2032 -0.2286)
							(mid -0.239121 -0.213721)
							(end -0.254 -0.1778)
						)
					)
					(width 0)
					(fill yes)
				)
			)
		)
		(pad "2" smd custom
			(at 0 0.4572 270)
			(size 0.1143 0.1143)
			(layers "B.Cu" "B.Mask" "B.Paste")
			(net "GND")
			(options
				(clearance outline)
				(anchor circle)
			)
			(primitives
				(gr_poly
					(pts
						(arc
							(start -0.254 0.1778)
							(mid -0.239121 0.213721)
							(end -0.2032 0.2286)
						)
						(arc
							(start 0.2032 0.2286)
							(mid 0.239121 0.213721)
							(end 0.254 0.1778)
						)
						(arc
							(start 0.254 -0.1778)
							(mid 0.239121 -0.213721)
							(end 0.2032 -0.2286)
						)
						(arc
							(start -0.2032 -0.2286)
							(mid -0.239121 -0.213721)
							(end -0.254 -0.1778)
						)
					)
					(width 0)
					(fill yes)
				)
			)
		)
	)
	(footprint ""
		(layer "B.Cu")
		(at 78.486 -23.6474)
		(property "Reference" "PR220"
			(at 0 0 0)
			(layer "B.SilkS")
			(hide yes)
			(effects
				(font
					(size 1.27 1.27)
				)
				(justify mirror)
			)
		)
		(property "Value" "0R2J-2-GP"
			(at -0.064008 -3.993896 0)
			(unlocked yes)
			(layer "B.Fab")
			(hide yes)
			(effects
				(font
					(size 1.016 1.016)
					(thickness 0.1524)
				)
				(justify mirror)
			)
		)
		(property "Device Type" "R402H16"
			(at -0.064008 -5.517896 0)
			(unlocked yes)
			(layer "B.Fab")
			(hide yes)
			(effects
				(font
					(size 1.016 1.016)
					(thickness 0.1524)
				)
				(justify mirror)
			)
		)
		(duplicate_pad_numbers_are_jumpers no)
		(fp_rect
			(start 0.381 0.8382)
			(end -0.381 -0.8382)
			(stroke
				(width 0)
				(type default)
			)
			(fill no)
			(layer "B.CrtYd")
		)
		(fp_rect
			(start 0.381 0.8382)
			(end -0.381 -0.8382)
			(stroke
				(width 0)
				(type default)
			)
			(fill no)
			(layer "B.Fab")
		)
		(pad "1" smd custom
			(at 0 -0.4318 180)
			(size 0.127 0.127)
			(layers "B.Cu" "B.Mask" "B.Paste")
			(net "P3V3_STBY")
			(options
				(clearance outline)
				(anchor circle)
			)
			(primitives
				(gr_poly
					(pts
						(arc
							(start -0.2032 0.2794)
							(mid -0.239121 0.264521)
							(end -0.254 0.2286)
						)
						(arc
							(start -0.254 -0.2286)
							(mid -0.239121 -0.264521)
							(end -0.2032 -0.2794)
						)
						(arc
							(start 0.2032 -0.2794)
							(mid 0.239121 -0.264521)
							(end 0.254 -0.2286)
						)
						(arc
							(start 0.254 0.2286)
							(mid 0.239121 0.264521)
							(end 0.2032 0.2794)
						)
					)
					(width 0)
					(fill yes)
				)
			)
		)
		(pad "2" smd custom
			(at 0 0.4318 180)
			(size 0.127 0.127)
			(layers "B.Cu" "B.Mask" "B.Paste")
			(net "TPS74801_1V35_BIAS")
			(options
				(clearance outline)
				(anchor circle)
			)
			(primitives
				(gr_poly
					(pts
						(arc
							(start -0.2032 0.2794)
							(mid -0.239121 0.264521)
							(end -0.254 0.2286)
						)
						(arc
							(start -0.254 -0.2286)
							(mid -0.239121 -0.264521)
							(end -0.2032 -0.2794)
						)
						(arc
							(start 0.2032 -0.2794)
							(mid 0.239121 -0.264521)
							(end 0.254 -0.2286)
						)
						(arc
							(start 0.254 0.2286)
							(mid 0.239121 0.264521)
							(end 0.2032 0.2794)
						)
					)
					(width 0)
					(fill yes)
				)
			)
		)
	)
	(footprint ""
		(layer "B.Cu")
		(at 85.344 -27.686 180)
		(property "Reference" "R372"
			(at 0 0 0)
			(layer "B.SilkS")
			(hide yes)
			(effects
				(font
					(size 1.27 1.27)
				)
				(justify mirror)
			)
		)
		(property "Value" "402R2F-GP"
			(at -0.064008 -3.993896 180)
			(unlocked yes)
			(layer "B.Fab")
			(hide yes)
			(effects
				(font
					(size 1.016 1.016)
					(thickness 0.1524)
				)
				(justify mirror)
			)
		)
		(property "Device Type" "R402H16"
			(at -0.064008 -5.517896 180)
			(unlocked yes)
			(layer "B.Fab")
			(hide yes)
			(effects
				(font
					(size 1.016 1.016)
					(thickness 0.1524)
				)
				(justify mirror)
			)
		)
		(duplicate_pad_numbers_are_jumpers no)
		(fp_rect
			(start 0.381 0.8382)
			(end -0.381 -0.8382)
			(stroke
				(width 0)
				(type default)
			)
			(fill no)
			(layer "B.CrtYd")
		)
		(fp_rect
			(start 0.381 0.8382)
			(end -0.381 -0.8382)
			(stroke
				(width 0)
				(type default)
			)
			(fill no)
			(layer "B.Fab")
		)
		(pad "1" smd custom
			(at 0 -0.4318)
			(size 0.127 0.127)
			(layers "B.Cu" "B.Mask" "B.Paste")
			(net "GBE_OBSP")
			(options
				(clearance outline)
				(anchor circle)
			)
			(primitives
				(gr_poly
					(pts
						(arc
							(start -0.2032 0.2794)
							(mid -0.239121 0.264521)
							(end -0.254 0.2286)
						)
						(arc
							(start -0.254 -0.2286)
							(mid -0.239121 -0.264521)
							(end -0.2032 -0.2794)
						)
						(arc
							(start 0.2032 -0.2794)
							(mid 0.239121 -0.264521)
							(end 0.254 -0.2286)
						)
						(arc
							(start 0.254 0.2286)
							(mid 0.239121 0.264521)
							(end 0.2032 0.2794)
						)
					)
					(width 0)
					(fill yes)
				)
			)
		)
		(pad "2" smd custom
			(at 0 0.4318)
			(size 0.127 0.127)
			(layers "B.Cu" "B.Mask" "B.Paste")
			(net "GBE_OBSN")
			(options
				(clearance outline)
				(anchor circle)
			)
			(primitives
				(gr_poly
					(pts
						(arc
							(start -0.2032 0.2794)
							(mid -0.239121 0.264521)
							(end -0.254 0.2286)
						)
						(arc
							(start -0.254 -0.2286)
							(mid -0.239121 -0.264521)
							(end -0.2032 -0.2794)
						)
						(arc
							(start 0.2032 -0.2794)
							(mid 0.239121 -0.264521)
							(end 0.254 -0.2286)
						)
						(arc
							(start 0.254 0.2286)
							(mid 0.239121 0.264521)
							(end 0.2032 0.2794)
						)
					)
					(width 0)
					(fill yes)
				)
			)
		)
	)
	(footprint ""
		(layer "B.Cu")
		(at 100.620068 -42.297096 180)
		(property "Reference" "C171"
			(at 0 0 0)
			(layer "B.SilkS")
			(hide yes)
			(effects
				(font
					(size 1.27 1.27)
				)
				(justify mirror)
			)
		)
		(property "Value" "SC1U10V2KX-1GP"
			(at -1.1811 -2.7051 180)
			(unlocked yes)
			(layer "B.Fab")
			(hide yes)
			(effects
				(font
					(size 1.016 1.016)
					(thickness 0.1524)
				)
				(justify mirror)
			)
		)
		(property "Device Type" "C402H22"
			(at -1.1811 -4.2291 180)
			(unlocked yes)
			(layer "B.Fab")
			(hide yes)
			(effects
				(font
					(size 1.016 1.016)
					(thickness 0.1524)
				)
				(justify mirror)
			)
		)
		(duplicate_pad_numbers_are_jumpers no)
		(fp_rect
			(start 0.381 0.7366)
			(end -0.381 -0.7366)
			(stroke
				(width 0)
				(type default)
			)
			(fill no)
			(layer "B.CrtYd")
		)
		(fp_rect
			(start 0.381 0.7366)
			(end -0.381 -0.7366)
			(stroke
				(width 0)
				(type default)
			)
			(fill no)
			(layer "B.Fab")
		)
		(pad "1" smd custom
			(at 0 -0.4572)
			(size 0.1143 0.1143)
			(layers "B.Cu" "B.Mask" "B.Paste")
			(net "PVNN")
			(options
				(clearance outline)
				(anchor circle)
			)
			(primitives
				(gr_poly
					(pts
						(arc
							(start -0.254 0.1778)
							(mid -0.239121 0.213721)
							(end -0.2032 0.2286)
						)
						(arc
							(start 0.2032 0.2286)
							(mid 0.239121 0.213721)
							(end 0.254 0.1778)
						)
						(arc
							(start 0.254 -0.1778)
							(mid 0.239121 -0.213721)
							(end 0.2032 -0.2286)
						)
						(arc
							(start -0.2032 -0.2286)
							(mid -0.239121 -0.213721)
							(end -0.254 -0.1778)
						)
					)
					(width 0)
					(fill yes)
				)
			)
		)
		(pad "2" smd custom
			(at 0 0.4572)
			(size 0.1143 0.1143)
			(layers "B.Cu" "B.Mask" "B.Paste")
			(net "GND")
			(options
				(clearance outline)
				(anchor circle)
			)
			(primitives
				(gr_poly
					(pts
						(arc
							(start -0.254 0.1778)
							(mid -0.239121 0.213721)
							(end -0.2032 0.2286)
						)
						(arc
							(start 0.2032 0.2286)
							(mid 0.239121 0.213721)
							(end 0.254 0.1778)
						)
						(arc
							(start 0.254 -0.1778)
							(mid 0.239121 -0.213721)
							(end 0.2032 -0.2286)
						)
						(arc
							(start -0.2032 -0.2286)
							(mid -0.239121 -0.213721)
							(end -0.254 -0.1778)
						)
					)
					(width 0)
					(fill yes)
				)
			)
		)
	)
	(footprint ""
		(layer "B.Cu")
		(at 151.765 -36.068 90)
		(property "Reference" "C233"
			(at 0 0 90)
			(layer "B.SilkS")
			(hide yes)
			(effects
				(font
					(size 1.27 1.27)
				)
				(justify mirror)
			)
		)
		(property "Value" "SCD1U10V2KX-5GP"
			(at -1.1811 -2.7051 90)
			(unlocked yes)
			(layer "B.Fab")
			(hide yes)
			(effects
				(font
					(size 1.016 1.016)
					(thickness 0.1524)
				)
				(justify mirror)
			)
		)
		(property "Device Type" "C402H22"
			(at -1.1811 -4.2291 90)
			(unlocked yes)
			(layer "B.Fab")
			(hide yes)
			(effects
				(font
					(size 1.016 1.016)
					(thickness 0.1524)
				)
				(justify mirror)
			)
		)
		(duplicate_pad_numbers_are_jumpers no)
		(fp_rect
			(start 0.381 0.7366)
			(end -0.381 -0.7366)
			(stroke
				(width 0)
				(type default)
			)
			(fill no)
			(layer "B.CrtYd")
		)
		(fp_rect
			(start 0.381 0.7366)
			(end -0.381 -0.7366)
			(stroke
				(width 0)
				(type default)
			)
			(fill no)
			(layer "B.Fab")
		)
		(pad "1" smd custom
			(at 0 -0.4572 270)
			(size 0.1143 0.1143)
			(layers "B.Cu" "B.Mask" "B.Paste")
			(net "P1V2_FPGA_D")
			(options
				(clearance outline)
				(anchor circle)
			)
			(primitives
				(gr_poly
					(pts
						(arc
							(start -0.254 0.1778)
							(mid -0.239121 0.213721)
							(end -0.2032 0.2286)
						)
						(arc
							(start 0.2032 0.2286)
							(mid 0.239121 0.213721)
							(end 0.254 0.1778)
						)
						(arc
							(start 0.254 -0.1778)
							(mid 0.239121 -0.213721)
							(end 0.2032 -0.2286)
						)
						(arc
							(start -0.2032 -0.2286)
							(mid -0.239121 -0.213721)
							(end -0.254 -0.1778)
						)
					)
					(width 0)
					(fill yes)
				)
			)
		)
		(pad "2" smd custom
			(at 0 0.4572 270)
			(size 0.1143 0.1143)
			(layers "B.Cu" "B.Mask" "B.Paste")
			(net "GND")
			(options
				(clearance outline)
				(anchor circle)
			)
			(primitives
				(gr_poly
					(pts
						(arc
							(start -0.254 0.1778)
							(mid -0.239121 0.213721)
							(end -0.2032 0.2286)
						)
						(arc
							(start 0.2032 0.2286)
							(mid 0.239121 0.213721)
							(end 0.254 0.1778)
						)
						(arc
							(start 0.254 -0.1778)
							(mid 0.239121 -0.213721)
							(end 0.2032 -0.2286)
						)
						(arc
							(start -0.2032 -0.2286)
							(mid -0.239121 -0.213721)
							(end -0.254 -0.1778)
						)
					)
					(width 0)
					(fill yes)
				)
			)
		)
	)
	(footprint ""
		(layer "B.Cu")
		(at 34.7726 -48.895 90)
		(property "Reference" "PR182"
			(at 0 0 90)
			(layer "B.SilkS")
			(hide yes)
			(effects
				(font
					(size 1.27 1.27)
				)
				(justify mirror)
			)
		)
		(property "Value" "0R2J-2-GP"
			(at -1.7907 -1.1176 90)
			(unlocked yes)
			(layer "B.Fab")
			(hide yes)
			(effects
				(font
					(size 1.016 1.016)
					(thickness 0.1524)
				)
				(justify mirror)
			)
		)
		(property "Device Type" "R402H16"
			(at -1.7907 -2.6416 90)
			(unlocked yes)
			(layer "B.Fab")
			(hide yes)
			(effects
				(font
					(size 1.016 1.016)
					(thickness 0.1524)
				)
				(justify mirror)
			)
		)
		(duplicate_pad_numbers_are_jumpers no)
		(fp_rect
			(start 0.381 0.8382)
			(end -0.381 -0.8382)
			(stroke
				(width 0)
				(type default)
			)
			(fill no)
			(layer "B.CrtYd")
		)
		(fp_rect
			(start 0.381 0.8382)
			(end -0.381 -0.8382)
			(stroke
				(width 0)
				(type default)
			)
			(fill no)
			(layer "B.Fab")
		)
		(pad "1" smd custom
			(at 0 -0.4318 270)
			(size 0.127 0.127)
			(layers "B.Cu" "B.Mask" "B.Paste")
			(net "P1V8_STBY_PG")
			(options
				(clearance outline)
				(anchor circle)
			)
			(primitives
				(gr_poly
					(pts
						(arc
							(start -0.2032 0.2794)
							(mid -0.239121 0.264521)
							(end -0.254 0.2286)
						)
						(arc
							(start -0.254 -0.2286)
							(mid -0.239121 -0.264521)
							(end -0.2032 -0.2794)
						)
						(arc
							(start 0.2032 -0.2794)
							(mid 0.239121 -0.264521)
							(end 0.254 -0.2286)
						)
						(arc
							(start 0.254 0.2286)
							(mid 0.239121 0.264521)
							(end 0.2032 0.2794)
						)
					)
					(width 0)
					(fill yes)
				)
			)
		)
		(pad "2" smd custom
			(at 0 0.4318 270)
			(size 0.127 0.127)
			(layers "B.Cu" "B.Mask" "B.Paste")
			(net "P1V5_STBY_EN")
			(options
				(clearance outline)
				(anchor circle)
			)
			(primitives
				(gr_poly
					(pts
						(arc
							(start -0.2032 0.2794)
							(mid -0.239121 0.264521)
							(end -0.254 0.2286)
						)
						(arc
							(start -0.254 -0.2286)
							(mid -0.239121 -0.264521)
							(end -0.2032 -0.2794)
						)
						(arc
							(start 0.2032 -0.2794)
							(mid 0.239121 -0.264521)
							(end 0.254 -0.2286)
						)
						(arc
							(start 0.254 0.2286)
							(mid 0.239121 0.264521)
							(end 0.2032 0.2794)
						)
					)
					(width 0)
					(fill yes)
				)
			)
		)
	)
	(footprint ""
		(layer "B.Cu")
		(at 41.656 -65.278 -90)
		(property "Reference" "PR35"
			(at 0 0 90)
			(layer "B.SilkS")
			(hide yes)
			(effects
				(font
					(size 1.27 1.27)
				)
				(justify mirror)
			)
		)
		(property "Value" "0R2J-2-GP"
			(at -1.7907 -1.1176 270)
			(unlocked yes)
			(layer "B.Fab")
			(hide yes)
			(effects
				(font
					(size 1.016 1.016)
					(thickness 0.1524)
				)
				(justify mirror)
			)
		)
		(property "Device Type" "R402H16"
			(at -1.7907 -2.6416 270)
			(unlocked yes)
			(layer "B.Fab")
			(hide yes)
			(effects
				(font
					(size 1.016 1.016)
					(thickness 0.1524)
				)
				(justify mirror)
			)
		)
		(duplicate_pad_numbers_are_jumpers no)
		(fp_rect
			(start 0.381 0.8382)
			(end -0.381 -0.8382)
			(stroke
				(width 0)
				(type default)
			)
			(fill no)
			(layer "B.CrtYd")
		)
		(fp_rect
			(start 0.381 0.8382)
			(end -0.381 -0.8382)
			(stroke
				(width 0)
				(type default)
			)
			(fill no)
			(layer "B.Fab")
		)
		(pad "1" smd custom
			(at 0 -0.4318 90)
			(size 0.127 0.127)
			(layers "B.Cu" "B.Mask" "B.Paste")
			(net "PVNN")
			(options
				(clearance outline)
				(anchor circle)
			)
			(primitives
				(gr_poly
					(pts
						(arc
							(start -0.2032 0.2794)
							(mid -0.239121 0.264521)
							(end -0.254 0.2286)
						)
						(arc
							(start -0.254 -0.2286)
							(mid -0.239121 -0.264521)
							(end -0.2032 -0.2794)
						)
						(arc
							(start 0.2032 -0.2794)
							(mid 0.239121 -0.264521)
							(end 0.254 -0.2286)
						)
						(arc
							(start 0.254 0.2286)
							(mid 0.239121 0.264521)
							(end 0.2032 0.2794)
						)
					)
					(width 0)
					(fill yes)
				)
			)
		)
		(pad "2" smd custom
			(at 0 0.4318 90)
			(size 0.127 0.127)
			(layers "B.Cu" "B.Mask" "B.Paste")
			(net "VR_PVNN_ISUMN_R2")
			(options
				(clearance outline)
				(anchor circle)
			)
			(primitives
				(gr_poly
					(pts
						(arc
							(start -0.2032 0.2794)
							(mid -0.239121 0.264521)
							(end -0.254 0.2286)
						)
						(arc
							(start -0.254 -0.2286)
							(mid -0.239121 -0.264521)
							(end -0.2032 -0.2794)
						)
						(arc
							(start 0.2032 -0.2794)
							(mid 0.239121 -0.264521)
							(end 0.254 -0.2286)
						)
						(arc
							(start 0.254 0.2286)
							(mid 0.239121 0.264521)
							(end 0.2032 0.2794)
						)
					)
					(width 0)
					(fill yes)
				)
			)
		)
	)
	(footprint ""
		(layer "B.Cu")
		(at 103.502968 -41.842436 -90)
		(property "Reference" "TP27"
			(at 0 0 90)
			(layer "B.SilkS")
			(hide yes)
			(effects
				(font
					(size 1.27 1.27)
				)
				(justify mirror)
			)
		)
		(property "Value" "TPAD24"
			(at 0 -2.9972 270)
			(unlocked yes)
			(layer "B.Fab")
			(hide yes)
			(effects
				(font
					(size 1.016 1.016)
					(thickness 0.1524)
				)
				(justify mirror)
			)
		)
		(property "Device Type" "TPAD24"
			(at 0 -4.5212 270)
			(unlocked yes)
			(layer "B.Fab")
			(hide yes)
			(effects
				(font
					(size 1.016 1.016)
					(thickness 0.1524)
				)
				(justify mirror)
			)
		)
		(duplicate_pad_numbers_are_jumpers no)
		(fp_poly
			(pts
				(arc
					(start 0 -0.3048)
					(mid 0 0.3048)
					(end 0 -0.3048)
				)
			)
			(stroke
				(width 0)
				(type default)
			)
			(fill no)
			(layer "B.CrtYd")
		)
		(fp_poly
			(pts
				(arc
					(start 0 -0.6096)
					(mid 0 0.6096)
					(end 0 -0.6096)
				)
			)
			(stroke
				(width 0)
				(type default)
			)
			(fill no)
			(layer "B.Fab")
		)
		(pad "1" smd circle
			(at 0 0 90)
			(size 0.6096 0.6096)
			(layers "B.Cu" "B.Mask" "B.Paste")
			(net "TP_CPU_RSVD6")
		)
	)
	(footprint ""
		(layer "B.Cu")
		(at 8.255 -22.606 180)
		(property "Reference" "PR120"
			(at 0 0 0)
			(layer "B.SilkS")
			(hide yes)
			(effects
				(font
					(size 1.27 1.27)
				)
				(justify mirror)
			)
		)
		(property "Value" "100KR2F-L1-GP"
			(at -1.7907 -1.1176 180)
			(unlocked yes)
			(layer "B.Fab")
			(hide yes)
			(effects
				(font
					(size 1.016 1.016)
					(thickness 0.1524)
				)
				(justify mirror)
			)
		)
		(property "Device Type" "R402H16"
			(at -1.7907 -2.6416 180)
			(unlocked yes)
			(layer "B.Fab")
			(hide yes)
			(effects
				(font
					(size 1.016 1.016)
					(thickness 0.1524)
				)
				(justify mirror)
			)
		)
		(duplicate_pad_numbers_are_jumpers no)
		(fp_rect
			(start 0.381 0.8382)
			(end -0.381 -0.8382)
			(stroke
				(width 0)
				(type default)
			)
			(fill no)
			(layer "B.CrtYd")
		)
		(fp_rect
			(start 0.381 0.8382)
			(end -0.381 -0.8382)
			(stroke
				(width 0)
				(type default)
			)
			(fill no)
			(layer "B.Fab")
		)
		(pad "1" smd custom
			(at 0 -0.4318)
			(size 0.127 0.127)
			(layers "B.Cu" "B.Mask" "B.Paste")
			(net "AGND_P1V0")
			(options
				(clearance outline)
				(anchor circle)
			)
			(primitives
				(gr_poly
					(pts
						(arc
							(start -0.2032 0.2794)
							(mid -0.239121 0.264521)
							(end -0.254 0.2286)
						)
						(arc
							(start -0.254 -0.2286)
							(mid -0.239121 -0.264521)
							(end -0.2032 -0.2794)
						)
						(arc
							(start 0.2032 -0.2794)
							(mid 0.239121 -0.264521)
							(end 0.254 -0.2286)
						)
						(arc
							(start 0.254 0.2286)
							(mid 0.239121 0.264521)
							(end 0.2032 0.2794)
						)
					)
					(width 0)
					(fill yes)
				)
			)
		)
		(pad "2" smd custom
			(at 0 0.4318)
			(size 0.127 0.127)
			(layers "B.Cu" "B.Mask" "B.Paste")
			(net "P1V0_MODE")
			(options
				(clearance outline)
				(anchor circle)
			)
			(primitives
				(gr_poly
					(pts
						(arc
							(start -0.2032 0.2794)
							(mid -0.239121 0.264521)
							(end -0.254 0.2286)
						)
						(arc
							(start -0.254 -0.2286)
							(mid -0.239121 -0.264521)
							(end -0.2032 -0.2794)
						)
						(arc
							(start 0.2032 -0.2794)
							(mid 0.239121 -0.264521)
							(end 0.254 -0.2286)
						)
						(arc
							(start 0.254 0.2286)
							(mid 0.239121 0.264521)
							(end 0.2032 0.2794)
						)
					)
					(width 0)
					(fill yes)
				)
			)
		)
	)
	(footprint ""
		(layer "B.Cu")
		(at 84.328 -64.516 90)
		(property "Reference" "R280"
			(at 0 0 90)
			(layer "B.SilkS")
			(hide yes)
			(effects
				(font
					(size 1.27 1.27)
				)
				(justify mirror)
			)
		)
		(property "Value" "1KR2F-3-GP"
			(at -0.064008 -3.993896 90)
			(unlocked yes)
			(layer "B.Fab")
			(hide yes)
			(effects
				(font
					(size 1.016 1.016)
					(thickness 0.1524)
				)
				(justify mirror)
			)
		)
		(property "Device Type" "R402H16"
			(at -0.064008 -5.517896 90)
			(unlocked yes)
			(layer "B.Fab")
			(hide yes)
			(effects
				(font
					(size 1.016 1.016)
					(thickness 0.1524)
				)
				(justify mirror)
			)
		)
		(duplicate_pad_numbers_are_jumpers no)
		(fp_rect
			(start 0.381 0.8382)
			(end -0.381 -0.8382)
			(stroke
				(width 0)
				(type default)
			)
			(fill no)
			(layer "B.CrtYd")
		)
		(fp_rect
			(start 0.381 0.8382)
			(end -0.381 -0.8382)
			(stroke
				(width 0)
				(type default)
			)
			(fill no)
			(layer "B.Fab")
		)
		(pad "1" smd custom
			(at 0 -0.4318 270)
			(size 0.127 0.127)
			(layers "B.Cu" "B.Mask" "B.Paste")
			(net "P1V0")
			(options
				(clearance outline)
				(anchor circle)
			)
			(primitives
				(gr_poly
					(pts
						(arc
							(start -0.2032 0.2794)
							(mid -0.239121 0.264521)
							(end -0.254 0.2286)
						)
						(arc
							(start -0.254 -0.2286)
							(mid -0.239121 -0.264521)
							(end -0.2032 -0.2794)
						)
						(arc
							(start 0.2032 -0.2794)
							(mid 0.239121 -0.264521)
							(end 0.254 -0.2286)
						)
						(arc
							(start 0.254 0.2286)
							(mid 0.239121 0.264521)
							(end 0.2032 0.2794)
						)
					)
					(width 0)
					(fill yes)
				)
			)
		)
		(pad "2" smd custom
			(at 0 0.4318 270)
			(size 0.127 0.127)
			(layers "B.Cu" "B.Mask" "B.Paste")
			(net "H_PROCESSOR_HOT_N_R")
			(options
				(clearance outline)
				(anchor circle)
			)
			(primitives
				(gr_poly
					(pts
						(arc
							(start -0.2032 0.2794)
							(mid -0.239121 0.264521)
							(end -0.254 0.2286)
						)
						(arc
							(start -0.254 -0.2286)
							(mid -0.239121 -0.264521)
							(end -0.2032 -0.2794)
						)
						(arc
							(start 0.2032 -0.2794)
							(mid 0.239121 -0.264521)
							(end 0.254 -0.2286)
						)
						(arc
							(start 0.254 0.2286)
							(mid 0.239121 0.264521)
							(end 0.2032 0.2794)
						)
					)
					(width 0)
					(fill yes)
				)
			)
		)
	)
	(footprint ""
		(layer "B.Cu")
		(at 65.8622 -19.3548 90)
		(property "Reference" "PC126"
			(at 0 0 90)
			(layer "B.SilkS")
			(hide yes)
			(effects
				(font
					(size 1.27 1.27)
				)
				(justify mirror)
			)
		)
		(property "Value" "SC5P50V2CN-2GP"
			(at -1.8923 -1.2065 90)
			(unlocked yes)
			(layer "B.Fab")
			(hide yes)
			(effects
				(font
					(size 1.016 1.016)
					(thickness 0.1524)
				)
				(justify mirror)
			)
		)
		(property "Device Type" "C402H22"
			(at -1.8923 -2.7305 90)
			(unlocked yes)
			(layer "B.Fab")
			(hide yes)
			(effects
				(font
					(size 1.016 1.016)
					(thickness 0.1524)
				)
				(justify mirror)
			)
		)
		(duplicate_pad_numbers_are_jumpers no)
		(fp_rect
			(start 0.381 0.7366)
			(end -0.381 -0.7366)
			(stroke
				(width 0)
				(type default)
			)
			(fill no)
			(layer "B.CrtYd")
		)
		(fp_rect
			(start 0.381 0.7366)
			(end -0.381 -0.7366)
			(stroke
				(width 0)
				(type default)
			)
			(fill no)
			(layer "B.Fab")
		)
		(pad "1" smd custom
			(at 0 -0.4572 270)
			(size 0.1143 0.1143)
			(layers "B.Cu" "B.Mask" "B.Paste")
			(net "VR_FB_R_P1V8_STBY")
			(options
				(clearance outline)
				(anchor circle)
			)
			(primitives
				(gr_poly
					(pts
						(arc
							(start -0.254 0.1778)
							(mid -0.239121 0.213721)
							(end -0.2032 0.2286)
						)
						(arc
							(start 0.2032 0.2286)
							(mid 0.239121 0.213721)
							(end 0.254 0.1778)
						)
						(arc
							(start 0.254 -0.1778)
							(mid 0.239121 -0.213721)
							(end 0.2032 -0.2286)
						)
						(arc
							(start -0.2032 -0.2286)
							(mid -0.239121 -0.213721)
							(end -0.254 -0.1778)
						)
					)
					(width 0)
					(fill yes)
				)
			)
		)
		(pad "2" smd custom
			(at 0 0.4572 270)
			(size 0.1143 0.1143)
			(layers "B.Cu" "B.Mask" "B.Paste")
			(net "VR_FB_P1V8_STBY")
			(options
				(clearance outline)
				(anchor circle)
			)
			(primitives
				(gr_poly
					(pts
						(arc
							(start -0.254 0.1778)
							(mid -0.239121 0.213721)
							(end -0.2032 0.2286)
						)
						(arc
							(start 0.2032 0.2286)
							(mid 0.239121 0.213721)
							(end 0.254 0.1778)
						)
						(arc
							(start 0.254 -0.1778)
							(mid 0.239121 -0.213721)
							(end 0.2032 -0.2286)
						)
						(arc
							(start -0.2032 -0.2286)
							(mid -0.239121 -0.213721)
							(end -0.254 -0.1778)
						)
					)
					(width 0)
					(fill yes)
				)
			)
		)
	)
	(footprint ""
		(layer "B.Cu")
		(at 171.8818 -12.879578 180)
		(property "Reference" "C366"
			(at 0 0 0)
			(layer "B.SilkS")
			(hide yes)
			(effects
				(font
					(size 1.27 1.27)
				)
				(justify mirror)
			)
		)
		(property "Value" "SC47U6D3V5MX-1-GP"
			(at 0 -4.9022 180)
			(unlocked yes)
			(layer "B.Fab")
			(hide yes)
			(effects
				(font
					(size 1.016 1.016)
					(thickness 0.1524)
				)
				(justify mirror)
			)
		)
		(property "Device Type" "C805H54"
			(at 0 -6.8072 180)
			(unlocked yes)
			(layer "B.Fab")
			(hide yes)
			(effects
				(font
					(size 1.016 1.016)
					(thickness 0.1524)
				)
				(justify mirror)
			)
		)
		(duplicate_pad_numbers_are_jumpers no)
		(fp_line
			(start -0.6096 0)
			(end 0.6096 0)
			(stroke
				(width 0.3048)
				(type default)
			)
			(layer "B.SilkS")
		)
		(fp_poly
			(pts
				(xy 0.9017 1.4351) (xy -0.9017 1.4351) (xy -0.9017 -1.4351) (xy 0.9017 -1.4351)
			)
			(stroke
				(width 0)
				(type default)
			)
			(fill no)
			(layer "B.CrtYd")
		)
		(fp_poly
			(pts
				(xy -0.9017 1.4351) (xy -0.9017 -1.4351) (xy 0.9017 -1.4351) (xy 0.9017 1.4351)
			)
			(stroke
				(width 0)
				(type default)
			)
			(fill no)
			(layer "B.Fab")
		)
		(pad "1" smd rect
			(at 0 -0.8382)
			(size 1.5494 0.9398)
			(layers "B.Cu" "B.Mask" "B.Paste")
			(net "PV_VDDR")
		)
		(pad "2" smd rect
			(at 0 0.8382)
			(size 1.5494 0.9398)
			(layers "B.Cu" "B.Mask" "B.Paste")
			(net "GND")
		)
	)
	(footprint ""
		(layer "B.Cu")
		(at 93.853 -14.097 180)
		(property "Reference" "C320"
			(at 0 0 0)
			(layer "B.SilkS")
			(hide yes)
			(effects
				(font
					(size 1.27 1.27)
				)
				(justify mirror)
			)
		)
		(property "Value" "SC22U25V5MX-GP"
			(at 0 -4.9022 180)
			(unlocked yes)
			(layer "B.Fab")
			(hide yes)
			(effects
				(font
					(size 1.016 1.016)
					(thickness 0.1524)
				)
				(justify mirror)
			)
		)
		(property "Device Type" "C805H58"
			(at 0 -6.8072 180)
			(unlocked yes)
			(layer "B.Fab")
			(hide yes)
			(effects
				(font
					(size 1.016 1.016)
					(thickness 0.1524)
				)
				(justify mirror)
			)
		)
		(duplicate_pad_numbers_are_jumpers no)
		(fp_line
			(start -0.6096 0)
			(end 0.6096 0)
			(stroke
				(width 0.3048)
				(type default)
			)
			(layer "B.SilkS")
		)
		(fp_poly
			(pts
				(xy 0.9017 1.4351) (xy -0.9017 1.4351) (xy -0.9017 -1.4351) (xy 0.9017 -1.4351)
			)
			(stroke
				(width 0)
				(type default)
			)
			(fill no)
			(layer "B.CrtYd")
		)
		(fp_poly
			(pts
				(xy -0.9017 1.4351) (xy -0.9017 -1.4351) (xy 0.9017 -1.4351) (xy 0.9017 1.4351)
			)
			(stroke
				(width 0)
				(type default)
			)
			(fill no)
			(layer "B.Fab")
		)
		(pad "1" smd rect
			(at 0 -0.8382)
			(size 1.5494 0.9398)
			(layers "B.Cu" "B.Mask" "B.Paste")
			(net "P12V")
		)
		(pad "2" smd rect
			(at 0 0.8382)
			(size 1.5494 0.9398)
			(layers "B.Cu" "B.Mask" "B.Paste")
			(net "GND")
		)
	)
	(footprint ""
		(layer "B.Cu")
		(at 36.449 -20.447 180)
		(property "Reference" "R452"
			(at 0 0 0)
			(layer "B.SilkS")
			(hide yes)
			(effects
				(font
					(size 1.27 1.27)
				)
				(justify mirror)
			)
		)
		(property "Value" "4K7R2F-GP"
			(at -1.7907 -1.1176 180)
			(unlocked yes)
			(layer "B.Fab")
			(hide yes)
			(effects
				(font
					(size 1.016 1.016)
					(thickness 0.1524)
				)
				(justify mirror)
			)
		)
		(property "Device Type" "R402H16"
			(at -1.7907 -2.6416 180)
			(unlocked yes)
			(layer "B.Fab")
			(hide yes)
			(effects
				(font
					(size 1.016 1.016)
					(thickness 0.1524)
				)
				(justify mirror)
			)
		)
		(duplicate_pad_numbers_are_jumpers no)
		(fp_rect
			(start 0.381 0.8382)
			(end -0.381 -0.8382)
			(stroke
				(width 0)
				(type default)
			)
			(fill no)
			(layer "B.CrtYd")
		)
		(fp_rect
			(start 0.381 0.8382)
			(end -0.381 -0.8382)
			(stroke
				(width 0)
				(type default)
			)
			(fill no)
			(layer "B.Fab")
		)
		(pad "1" smd custom
			(at 0 -0.4318)
			(size 0.127 0.127)
			(layers "B.Cu" "B.Mask" "B.Paste")
			(net "CLKBUFF_BYPASS_OR_PLL")
			(options
				(clearance outline)
				(anchor circle)
			)
			(primitives
				(gr_poly
					(pts
						(arc
							(start -0.2032 0.2794)
							(mid -0.239121 0.264521)
							(end -0.254 0.2286)
						)
						(arc
							(start -0.254 -0.2286)
							(mid -0.239121 -0.264521)
							(end -0.2032 -0.2794)
						)
						(arc
							(start 0.2032 -0.2794)
							(mid 0.239121 -0.264521)
							(end 0.254 -0.2286)
						)
						(arc
							(start 0.254 0.2286)
							(mid 0.239121 0.264521)
							(end 0.2032 0.2794)
						)
					)
					(width 0)
					(fill yes)
				)
			)
		)
		(pad "2" smd custom
			(at 0 0.4318)
			(size 0.127 0.127)
			(layers "B.Cu" "B.Mask" "B.Paste")
			(net "GND")
			(options
				(clearance outline)
				(anchor circle)
			)
			(primitives
				(gr_poly
					(pts
						(arc
							(start -0.2032 0.2794)
							(mid -0.239121 0.264521)
							(end -0.254 0.2286)
						)
						(arc
							(start -0.254 -0.2286)
							(mid -0.239121 -0.264521)
							(end -0.2032 -0.2794)
						)
						(arc
							(start 0.2032 -0.2794)
							(mid 0.239121 -0.264521)
							(end 0.254 -0.2286)
						)
						(arc
							(start 0.254 0.2286)
							(mid 0.239121 0.264521)
							(end 0.2032 0.2794)
						)
					)
					(width 0)
					(fill yes)
				)
			)
		)
	)
	(footprint ""
		(layer "B.Cu")
		(at 33.7058 -47.7774)
		(property "Reference" "PC132"
			(at 0 0 0)
			(layer "B.SilkS")
			(hide yes)
			(effects
				(font
					(size 1.27 1.27)
				)
				(justify mirror)
			)
		)
		(property "Value" "SC470P50V2KX-3GP"
			(at -1.8923 -1.2065 0)
			(unlocked yes)
			(layer "B.Fab")
			(hide yes)
			(effects
				(font
					(size 1.016 1.016)
					(thickness 0.1524)
				)
				(justify mirror)
			)
		)
		(property "Device Type" "C402H22"
			(at -1.8923 -2.7305 0)
			(unlocked yes)
			(layer "B.Fab")
			(hide yes)
			(effects
				(font
					(size 1.016 1.016)
					(thickness 0.1524)
				)
				(justify mirror)
			)
		)
		(duplicate_pad_numbers_are_jumpers no)
		(fp_rect
			(start 0.381 0.7366)
			(end -0.381 -0.7366)
			(stroke
				(width 0)
				(type default)
			)
			(fill no)
			(layer "B.CrtYd")
		)
		(fp_rect
			(start 0.381 0.7366)
			(end -0.381 -0.7366)
			(stroke
				(width 0)
				(type default)
			)
			(fill no)
			(layer "B.Fab")
		)
		(pad "1" smd custom
			(at 0 -0.4572 180)
			(size 0.1143 0.1143)
			(layers "B.Cu" "B.Mask" "B.Paste")
			(net "GND")
			(options
				(clearance outline)
				(anchor circle)
			)
			(primitives
				(gr_poly
					(pts
						(arc
							(start -0.254 0.1778)
							(mid -0.239121 0.213721)
							(end -0.2032 0.2286)
						)
						(arc
							(start 0.2032 0.2286)
							(mid 0.239121 0.213721)
							(end 0.254 0.1778)
						)
						(arc
							(start 0.254 -0.1778)
							(mid 0.239121 -0.213721)
							(end 0.2032 -0.2286)
						)
						(arc
							(start -0.2032 -0.2286)
							(mid -0.239121 -0.213721)
							(end -0.254 -0.1778)
						)
					)
					(width 0)
					(fill yes)
				)
			)
		)
		(pad "2" smd custom
			(at 0 0.4572 180)
			(size 0.1143 0.1143)
			(layers "B.Cu" "B.Mask" "B.Paste")
			(net "P1V5_STBY_SS")
			(options
				(clearance outline)
				(anchor circle)
			)
			(primitives
				(gr_poly
					(pts
						(arc
							(start -0.254 0.1778)
							(mid -0.239121 0.213721)
							(end -0.2032 0.2286)
						)
						(arc
							(start 0.2032 0.2286)
							(mid 0.239121 0.213721)
							(end 0.254 0.1778)
						)
						(arc
							(start 0.254 -0.1778)
							(mid 0.239121 -0.213721)
							(end 0.2032 -0.2286)
						)
						(arc
							(start -0.2032 -0.2286)
							(mid -0.239121 -0.213721)
							(end -0.254 -0.1778)
						)
					)
					(width 0)
					(fill yes)
				)
			)
		)
	)
	(footprint ""
		(layer "B.Cu")
		(at 41.148 -14.605 90)
		(property "Reference" "R429"
			(at 0 0 90)
			(layer "B.SilkS")
			(hide yes)
			(effects
				(font
					(size 1.27 1.27)
				)
				(justify mirror)
			)
		)
		(property "Value" "43D2R2F-GP"
			(at -1.7907 -1.1176 90)
			(unlocked yes)
			(layer "B.Fab")
			(hide yes)
			(effects
				(font
					(size 1.016 1.016)
					(thickness 0.1524)
				)
				(justify mirror)
			)
		)
		(property "Device Type" "R402H16"
			(at -1.7907 -2.6416 90)
			(unlocked yes)
			(layer "B.Fab")
			(hide yes)
			(effects
				(font
					(size 1.016 1.016)
					(thickness 0.1524)
				)
				(justify mirror)
			)
		)
		(duplicate_pad_numbers_are_jumpers no)
		(fp_rect
			(start 0.381 0.8382)
			(end -0.381 -0.8382)
			(stroke
				(width 0)
				(type default)
			)
			(fill no)
			(layer "B.CrtYd")
		)
		(fp_rect
			(start 0.381 0.8382)
			(end -0.381 -0.8382)
			(stroke
				(width 0)
				(type default)
			)
			(fill no)
			(layer "B.Fab")
		)
		(pad "1" smd custom
			(at 0 -0.4318 270)
			(size 0.127 0.127)
			(layers "B.Cu" "B.Mask" "B.Paste")
			(net "CLK_100M_PCIE_SAS_DP")
			(options
				(clearance outline)
				(anchor circle)
			)
			(primitives
				(gr_poly
					(pts
						(arc
							(start -0.2032 0.2794)
							(mid -0.239121 0.264521)
							(end -0.254 0.2286)
						)
						(arc
							(start -0.254 -0.2286)
							(mid -0.239121 -0.264521)
							(end -0.2032 -0.2794)
						)
						(arc
							(start 0.2032 -0.2794)
							(mid 0.239121 -0.264521)
							(end 0.254 -0.2286)
						)
						(arc
							(start 0.254 0.2286)
							(mid 0.239121 0.264521)
							(end 0.2032 0.2794)
						)
					)
					(width 0)
					(fill yes)
				)
			)
		)
		(pad "2" smd custom
			(at 0 0.4318 270)
			(size 0.127 0.127)
			(layers "B.Cu" "B.Mask" "B.Paste")
			(net "GND")
			(options
				(clearance outline)
				(anchor circle)
			)
			(primitives
				(gr_poly
					(pts
						(arc
							(start -0.2032 0.2794)
							(mid -0.239121 0.264521)
							(end -0.254 0.2286)
						)
						(arc
							(start -0.254 -0.2286)
							(mid -0.239121 -0.264521)
							(end -0.2032 -0.2794)
						)
						(arc
							(start 0.2032 -0.2794)
							(mid 0.239121 -0.264521)
							(end 0.254 -0.2286)
						)
						(arc
							(start 0.254 0.2286)
							(mid 0.239121 0.264521)
							(end 0.2032 0.2794)
						)
					)
					(width 0)
					(fill yes)
				)
			)
		)
	)
	(footprint ""
		(layer "B.Cu")
		(at 40.64 -15.9004)
		(property "Reference" "R368"
			(at 0 0 0)
			(layer "B.SilkS")
			(hide yes)
			(effects
				(font
					(size 1.27 1.27)
				)
				(justify mirror)
			)
		)
		(property "Value" "33R2F-3-GP"
			(at -0.064008 -3.993896 0)
			(unlocked yes)
			(layer "B.Fab")
			(hide yes)
			(effects
				(font
					(size 1.016 1.016)
					(thickness 0.1524)
				)
				(justify mirror)
			)
		)
		(property "Device Type" "R402H16"
			(at -0.064008 -5.517896 0)
			(unlocked yes)
			(layer "B.Fab")
			(hide yes)
			(effects
				(font
					(size 1.016 1.016)
					(thickness 0.1524)
				)
				(justify mirror)
			)
		)
		(duplicate_pad_numbers_are_jumpers no)
		(fp_rect
			(start 0.381 0.8382)
			(end -0.381 -0.8382)
			(stroke
				(width 0)
				(type default)
			)
			(fill no)
			(layer "B.CrtYd")
		)
		(fp_rect
			(start 0.381 0.8382)
			(end -0.381 -0.8382)
			(stroke
				(width 0)
				(type default)
			)
			(fill no)
			(layer "B.Fab")
		)
		(pad "1" smd custom
			(at 0 -0.4318 180)
			(size 0.127 0.127)
			(layers "B.Cu" "B.Mask" "B.Paste")
			(net "CLK_100M_CLKBUFF_SAS_R_DP")
			(options
				(clearance outline)
				(anchor circle)
			)
			(primitives
				(gr_poly
					(pts
						(arc
							(start -0.2032 0.2794)
							(mid -0.239121 0.264521)
							(end -0.254 0.2286)
						)
						(arc
							(start -0.254 -0.2286)
							(mid -0.239121 -0.264521)
							(end -0.2032 -0.2794)
						)
						(arc
							(start 0.2032 -0.2794)
							(mid 0.239121 -0.264521)
							(end 0.254 -0.2286)
						)
						(arc
							(start 0.254 0.2286)
							(mid 0.239121 0.264521)
							(end 0.2032 0.2794)
						)
					)
					(width 0)
					(fill yes)
				)
			)
		)
		(pad "2" smd custom
			(at 0 0.4318 180)
			(size 0.127 0.127)
			(layers "B.Cu" "B.Mask" "B.Paste")
			(net "CLK_100M_PCIE_SAS_DP")
			(options
				(clearance outline)
				(anchor circle)
			)
			(primitives
				(gr_poly
					(pts
						(arc
							(start -0.2032 0.2794)
							(mid -0.239121 0.264521)
							(end -0.254 0.2286)
						)
						(arc
							(start -0.254 -0.2286)
							(mid -0.239121 -0.264521)
							(end -0.2032 -0.2794)
						)
						(arc
							(start 0.2032 -0.2794)
							(mid 0.239121 -0.264521)
							(end 0.254 -0.2286)
						)
						(arc
							(start 0.254 0.2286)
							(mid 0.239121 0.264521)
							(end 0.2032 0.2794)
						)
					)
					(width 0)
					(fill yes)
				)
			)
		)
	)
	(footprint ""
		(layer "B.Cu")
		(at 74.168 -43.434 90)
		(property "Reference" "R68"
			(at 0 0 90)
			(layer "B.SilkS")
			(hide yes)
			(effects
				(font
					(size 1.27 1.27)
				)
				(justify mirror)
			)
		)
		(property "Value" "4K7R2F-GP"
			(at -0.064008 -3.993896 90)
			(unlocked yes)
			(layer "B.Fab")
			(hide yes)
			(effects
				(font
					(size 1.016 1.016)
					(thickness 0.1524)
				)
				(justify mirror)
			)
		)
		(property "Device Type" "R402H16"
			(at -0.064008 -5.517896 90)
			(unlocked yes)
			(layer "B.Fab")
			(hide yes)
			(effects
				(font
					(size 1.016 1.016)
					(thickness 0.1524)
				)
				(justify mirror)
			)
		)
		(duplicate_pad_numbers_are_jumpers no)
		(fp_rect
			(start 0.381 0.8382)
			(end -0.381 -0.8382)
			(stroke
				(width 0)
				(type default)
			)
			(fill no)
			(layer "B.CrtYd")
		)
		(fp_rect
			(start 0.381 0.8382)
			(end -0.381 -0.8382)
			(stroke
				(width 0)
				(type default)
			)
			(fill no)
			(layer "B.Fab")
		)
		(pad "1" smd custom
			(at 0 -0.4318 270)
			(size 0.127 0.127)
			(layers "B.Cu" "B.Mask" "B.Paste")
			(net "P3V3")
			(options
				(clearance outline)
				(anchor circle)
			)
			(primitives
				(gr_poly
					(pts
						(arc
							(start -0.2032 0.2794)
							(mid -0.239121 0.264521)
							(end -0.254 0.2286)
						)
						(arc
							(start -0.254 -0.2286)
							(mid -0.239121 -0.264521)
							(end -0.2032 -0.2794)
						)
						(arc
							(start 0.2032 -0.2794)
							(mid 0.239121 -0.264521)
							(end 0.254 -0.2286)
						)
						(arc
							(start 0.254 0.2286)
							(mid 0.239121 0.264521)
							(end 0.2032 0.2794)
						)
					)
					(width 0)
					(fill yes)
				)
			)
		)
		(pad "2" smd custom
			(at 0 0.4318 270)
			(size 0.127 0.127)
			(layers "B.Cu" "B.Mask" "B.Paste")
			(net "CPU_ERR_N1")
			(options
				(clearance outline)
				(anchor circle)
			)
			(primitives
				(gr_poly
					(pts
						(arc
							(start -0.2032 0.2794)
							(mid -0.239121 0.264521)
							(end -0.254 0.2286)
						)
						(arc
							(start -0.254 -0.2286)
							(mid -0.239121 -0.264521)
							(end -0.2032 -0.2794)
						)
						(arc
							(start 0.2032 -0.2794)
							(mid 0.239121 -0.264521)
							(end 0.254 -0.2286)
						)
						(arc
							(start 0.254 0.2286)
							(mid 0.239121 0.264521)
							(end 0.2032 0.2794)
						)
					)
					(width 0)
					(fill yes)
				)
			)
		)
	)
	(footprint ""
		(layer "B.Cu")
		(at 188.595 -27.94 180)
		(property "Reference" "PR212"
			(at 0 0 0)
			(layer "B.SilkS")
			(hide yes)
			(effects
				(font
					(size 1.27 1.27)
				)
				(justify mirror)
			)
		)
		(property "Value" "100R2F-L1-GP-U"
			(at -1.7907 -1.1176 180)
			(unlocked yes)
			(layer "B.Fab")
			(hide yes)
			(effects
				(font
					(size 1.016 1.016)
					(thickness 0.1524)
				)
				(justify mirror)
			)
		)
		(property "Device Type" "R402H14"
			(at -1.7907 -2.6416 180)
			(unlocked yes)
			(layer "B.Fab")
			(hide yes)
			(effects
				(font
					(size 1.016 1.016)
					(thickness 0.1524)
				)
				(justify mirror)
			)
		)
		(duplicate_pad_numbers_are_jumpers no)
		(fp_rect
			(start 0.381 0.8382)
			(end -0.381 -0.8382)
			(stroke
				(width 0)
				(type default)
			)
			(fill no)
			(layer "B.CrtYd")
		)
		(fp_rect
			(start 0.381 0.8382)
			(end -0.381 -0.8382)
			(stroke
				(width 0)
				(type default)
			)
			(fill no)
			(layer "B.Fab")
		)
		(pad "1" smd custom
			(at 0 -0.4318)
			(size 0.127 0.127)
			(layers "B.Cu" "B.Mask" "B.Paste")
			(net "VR_PVDDR_A_SUMN_C")
			(options
				(clearance outline)
				(anchor circle)
			)
			(primitives
				(gr_poly
					(pts
						(arc
							(start -0.2032 0.2794)
							(mid -0.239121 0.264521)
							(end -0.254 0.2286)
						)
						(arc
							(start -0.254 -0.2286)
							(mid -0.239121 -0.264521)
							(end -0.2032 -0.2794)
						)
						(arc
							(start 0.2032 -0.2794)
							(mid 0.239121 -0.264521)
							(end 0.254 -0.2286)
						)
						(arc
							(start 0.254 0.2286)
							(mid 0.239121 0.264521)
							(end 0.2032 0.2794)
						)
					)
					(width 0)
					(fill yes)
				)
			)
		)
		(pad "2" smd custom
			(at 0 0.4318)
			(size 0.127 0.127)
			(layers "B.Cu" "B.Mask" "B.Paste")
			(net "VR_PVDDRA_ISUMN1")
			(options
				(clearance outline)
				(anchor circle)
			)
			(primitives
				(gr_poly
					(pts
						(arc
							(start -0.2032 0.2794)
							(mid -0.239121 0.264521)
							(end -0.254 0.2286)
						)
						(arc
							(start -0.254 -0.2286)
							(mid -0.239121 -0.264521)
							(end -0.2032 -0.2794)
						)
						(arc
							(start 0.2032 -0.2794)
							(mid 0.239121 -0.264521)
							(end 0.254 -0.2286)
						)
						(arc
							(start 0.254 0.2286)
							(mid 0.239121 0.264521)
							(end 0.2032 0.2794)
						)
					)
					(width 0)
					(fill yes)
				)
			)
		)
	)
	(footprint ""
		(layer "B.Cu")
		(at 33.147 -43.688 90)
		(property "Reference" "PC137"
			(at 0 0 90)
			(layer "B.SilkS")
			(hide yes)
			(effects
				(font
					(size 1.27 1.27)
				)
				(justify mirror)
			)
		)
		(property "Value" "SC1KP50V2KX-1GP"
			(at -1.8923 -1.2065 90)
			(unlocked yes)
			(layer "B.Fab")
			(hide yes)
			(effects
				(font
					(size 1.016 1.016)
					(thickness 0.1524)
				)
				(justify mirror)
			)
		)
		(property "Device Type" "C402H22"
			(at -1.8923 -2.7305 90)
			(unlocked yes)
			(layer "B.Fab")
			(hide yes)
			(effects
				(font
					(size 1.016 1.016)
					(thickness 0.1524)
				)
				(justify mirror)
			)
		)
		(duplicate_pad_numbers_are_jumpers no)
		(fp_rect
			(start 0.381 0.7366)
			(end -0.381 -0.7366)
			(stroke
				(width 0)
				(type default)
			)
			(fill no)
			(layer "B.CrtYd")
		)
		(fp_rect
			(start 0.381 0.7366)
			(end -0.381 -0.7366)
			(stroke
				(width 0)
				(type default)
			)
			(fill no)
			(layer "B.Fab")
		)
		(pad "1" smd custom
			(at 0 -0.4572 270)
			(size 0.1143 0.1143)
			(layers "B.Cu" "B.Mask" "B.Paste")
			(net "P1V5_STBY_OUT")
			(options
				(clearance outline)
				(anchor circle)
			)
			(primitives
				(gr_poly
					(pts
						(arc
							(start -0.254 0.1778)
							(mid -0.239121 0.213721)
							(end -0.2032 0.2286)
						)
						(arc
							(start 0.2032 0.2286)
							(mid 0.239121 0.213721)
							(end 0.254 0.1778)
						)
						(arc
							(start 0.254 -0.1778)
							(mid 0.239121 -0.213721)
							(end 0.2032 -0.2286)
						)
						(arc
							(start -0.2032 -0.2286)
							(mid -0.239121 -0.213721)
							(end -0.254 -0.1778)
						)
					)
					(width 0)
					(fill yes)
				)
			)
		)
		(pad "2" smd custom
			(at 0 0.4572 270)
			(size 0.1143 0.1143)
			(layers "B.Cu" "B.Mask" "B.Paste")
			(net "P1V5_STBY_FB")
			(options
				(clearance outline)
				(anchor circle)
			)
			(primitives
				(gr_poly
					(pts
						(arc
							(start -0.254 0.1778)
							(mid -0.239121 0.213721)
							(end -0.2032 0.2286)
						)
						(arc
							(start 0.2032 0.2286)
							(mid 0.239121 0.213721)
							(end 0.254 0.1778)
						)
						(arc
							(start 0.254 -0.1778)
							(mid 0.239121 -0.213721)
							(end 0.2032 -0.2286)
						)
						(arc
							(start -0.2032 -0.2286)
							(mid -0.239121 -0.213721)
							(end -0.254 -0.1778)
						)
					)
					(width 0)
					(fill yes)
				)
			)
		)
	)
	(footprint ""
		(layer "B.Cu")
		(at 129.286 -25.273 180)
		(property "Reference" "R32"
			(at 0 0 0)
			(layer "B.SilkS")
			(hide yes)
			(effects
				(font
					(size 1.27 1.27)
				)
				(justify mirror)
			)
		)
		(property "Value" "1KR2F-3-GP"
			(at -0.064008 -3.993896 180)
			(unlocked yes)
			(layer "B.Fab")
			(hide yes)
			(effects
				(font
					(size 1.016 1.016)
					(thickness 0.1524)
				)
				(justify mirror)
			)
		)
		(property "Device Type" "R402H16"
			(at -0.064008 -5.517896 180)
			(unlocked yes)
			(layer "B.Fab")
			(hide yes)
			(effects
				(font
					(size 1.016 1.016)
					(thickness 0.1524)
				)
				(justify mirror)
			)
		)
		(duplicate_pad_numbers_are_jumpers no)
		(fp_rect
			(start 0.381 0.8382)
			(end -0.381 -0.8382)
			(stroke
				(width 0)
				(type default)
			)
			(fill no)
			(layer "B.CrtYd")
		)
		(fp_rect
			(start 0.381 0.8382)
			(end -0.381 -0.8382)
			(stroke
				(width 0)
				(type default)
			)
			(fill no)
			(layer "B.Fab")
		)
		(pad "1" smd custom
			(at 0 -0.4318)
			(size 0.127 0.127)
			(layers "B.Cu" "B.Mask" "B.Paste")
			(net "P3V3_STBY")
			(options
				(clearance outline)
				(anchor circle)
			)
			(primitives
				(gr_poly
					(pts
						(arc
							(start -0.2032 0.2794)
							(mid -0.239121 0.264521)
							(end -0.254 0.2286)
						)
						(arc
							(start -0.254 -0.2286)
							(mid -0.239121 -0.264521)
							(end -0.2032 -0.2794)
						)
						(arc
							(start 0.2032 -0.2794)
							(mid 0.239121 -0.264521)
							(end 0.254 -0.2286)
						)
						(arc
							(start 0.254 0.2286)
							(mid 0.239121 0.264521)
							(end 0.2032 0.2794)
						)
					)
					(width 0)
					(fill yes)
				)
			)
		)
		(pad "2" smd custom
			(at 0 0.4318)
			(size 0.127 0.127)
			(layers "B.Cu" "B.Mask" "B.Paste")
			(net "CPU_THERMTRIP_LVC#")
			(options
				(clearance outline)
				(anchor circle)
			)
			(primitives
				(gr_poly
					(pts
						(arc
							(start -0.2032 0.2794)
							(mid -0.239121 0.264521)
							(end -0.254 0.2286)
						)
						(arc
							(start -0.254 -0.2286)
							(mid -0.239121 -0.264521)
							(end -0.2032 -0.2794)
						)
						(arc
							(start 0.2032 -0.2794)
							(mid 0.239121 -0.264521)
							(end 0.254 -0.2286)
						)
						(arc
							(start 0.254 0.2286)
							(mid 0.239121 0.264521)
							(end 0.2032 0.2794)
						)
					)
					(width 0)
					(fill yes)
				)
			)
		)
	)
	(footprint ""
		(layer "B.Cu")
		(at 90.2081 -33.4518 90)
		(property "Reference" "C212"
			(at 0 0 90)
			(layer "B.SilkS")
			(hide yes)
			(effects
				(font
					(size 1.27 1.27)
				)
				(justify mirror)
			)
		)
		(property "Value" "SC1U10V2KX-1GP"
			(at -1.1811 -2.7051 90)
			(unlocked yes)
			(layer "B.Fab")
			(hide yes)
			(effects
				(font
					(size 1.016 1.016)
					(thickness 0.1524)
				)
				(justify mirror)
			)
		)
		(property "Device Type" "C402H22"
			(at -1.1811 -4.2291 90)
			(unlocked yes)
			(layer "B.Fab")
			(hide yes)
			(effects
				(font
					(size 1.016 1.016)
					(thickness 0.1524)
				)
				(justify mirror)
			)
		)
		(duplicate_pad_numbers_are_jumpers no)
		(fp_rect
			(start 0.381 0.7366)
			(end -0.381 -0.7366)
			(stroke
				(width 0)
				(type default)
			)
			(fill no)
			(layer "B.CrtYd")
		)
		(fp_rect
			(start 0.381 0.7366)
			(end -0.381 -0.7366)
			(stroke
				(width 0)
				(type default)
			)
			(fill no)
			(layer "B.Fab")
		)
		(pad "1" smd custom
			(at 0 -0.4572 270)
			(size 0.1143 0.1143)
			(layers "B.Cu" "B.Mask" "B.Paste")
			(net "P1V0")
			(options
				(clearance outline)
				(anchor circle)
			)
			(primitives
				(gr_poly
					(pts
						(arc
							(start -0.254 0.1778)
							(mid -0.239121 0.213721)
							(end -0.2032 0.2286)
						)
						(arc
							(start 0.2032 0.2286)
							(mid 0.239121 0.213721)
							(end 0.254 0.1778)
						)
						(arc
							(start 0.254 -0.1778)
							(mid 0.239121 -0.213721)
							(end 0.2032 -0.2286)
						)
						(arc
							(start -0.2032 -0.2286)
							(mid -0.239121 -0.213721)
							(end -0.254 -0.1778)
						)
					)
					(width 0)
					(fill yes)
				)
			)
		)
		(pad "2" smd custom
			(at 0 0.4572 270)
			(size 0.1143 0.1143)
			(layers "B.Cu" "B.Mask" "B.Paste")
			(net "GND")
			(options
				(clearance outline)
				(anchor circle)
			)
			(primitives
				(gr_poly
					(pts
						(arc
							(start -0.254 0.1778)
							(mid -0.239121 0.213721)
							(end -0.2032 0.2286)
						)
						(arc
							(start 0.2032 0.2286)
							(mid 0.239121 0.213721)
							(end 0.254 0.1778)
						)
						(arc
							(start 0.254 -0.1778)
							(mid 0.239121 -0.213721)
							(end 0.2032 -0.2286)
						)
						(arc
							(start -0.2032 -0.2286)
							(mid -0.239121 -0.213721)
							(end -0.254 -0.1778)
						)
					)
					(width 0)
					(fill yes)
				)
			)
		)
	)
	(footprint ""
		(layer "B.Cu")
		(at 77.343 -21.209 180)
		(property "Reference" "PR222"
			(at 0 0 0)
			(layer "B.SilkS")
			(hide yes)
			(effects
				(font
					(size 1.27 1.27)
				)
				(justify mirror)
			)
		)
		(property "Value" "10KR2F-2-GP"
			(at -0.064008 -3.993896 180)
			(unlocked yes)
			(layer "B.Fab")
			(hide yes)
			(effects
				(font
					(size 1.016 1.016)
					(thickness 0.1524)
				)
				(justify mirror)
			)
		)
		(property "Device Type" "R402H16"
			(at -0.064008 -5.517896 180)
			(unlocked yes)
			(layer "B.Fab")
			(hide yes)
			(effects
				(font
					(size 1.016 1.016)
					(thickness 0.1524)
				)
				(justify mirror)
			)
		)
		(duplicate_pad_numbers_are_jumpers no)
		(fp_rect
			(start 0.381 0.8382)
			(end -0.381 -0.8382)
			(stroke
				(width 0)
				(type default)
			)
			(fill no)
			(layer "B.CrtYd")
		)
		(fp_rect
			(start 0.381 0.8382)
			(end -0.381 -0.8382)
			(stroke
				(width 0)
				(type default)
			)
			(fill no)
			(layer "B.Fab")
		)
		(pad "1" smd custom
			(at 0 -0.4318)
			(size 0.127 0.127)
			(layers "B.Cu" "B.Mask" "B.Paste")
			(net "PWRGD_P1V35_PG")
			(options
				(clearance outline)
				(anchor circle)
			)
			(primitives
				(gr_poly
					(pts
						(arc
							(start -0.2032 0.2794)
							(mid -0.239121 0.264521)
							(end -0.254 0.2286)
						)
						(arc
							(start -0.254 -0.2286)
							(mid -0.239121 -0.264521)
							(end -0.2032 -0.2794)
						)
						(arc
							(start 0.2032 -0.2794)
							(mid 0.239121 -0.264521)
							(end 0.254 -0.2286)
						)
						(arc
							(start 0.254 0.2286)
							(mid 0.239121 0.264521)
							(end 0.2032 0.2794)
						)
					)
					(width 0)
					(fill yes)
				)
			)
		)
		(pad "2" smd custom
			(at 0 0.4318)
			(size 0.127 0.127)
			(layers "B.Cu" "B.Mask" "B.Paste")
			(net "P3V3_STBY")
			(options
				(clearance outline)
				(anchor circle)
			)
			(primitives
				(gr_poly
					(pts
						(arc
							(start -0.2032 0.2794)
							(mid -0.239121 0.264521)
							(end -0.254 0.2286)
						)
						(arc
							(start -0.254 -0.2286)
							(mid -0.239121 -0.264521)
							(end -0.2032 -0.2794)
						)
						(arc
							(start 0.2032 -0.2794)
							(mid 0.239121 -0.264521)
							(end 0.254 -0.2286)
						)
						(arc
							(start 0.254 0.2286)
							(mid 0.239121 0.264521)
							(end 0.2032 0.2794)
						)
					)
					(width 0)
					(fill yes)
				)
			)
		)
	)
	(footprint ""
		(layer "B.Cu")
		(at 34.163 -51.054 -90)
		(property "Reference" "PC131"
			(at 0 0 90)
			(layer "B.SilkS")
			(hide yes)
			(effects
				(font
					(size 1.27 1.27)
				)
				(justify mirror)
			)
		)
		(property "Value" "SCD1U16V2KX-3GP"
			(at -1.8923 -1.2065 270)
			(unlocked yes)
			(layer "B.Fab")
			(hide yes)
			(effects
				(font
					(size 1.016 1.016)
					(thickness 0.1524)
				)
				(justify mirror)
			)
		)
		(property "Device Type" "C402H22"
			(at -1.8923 -2.7305 270)
			(unlocked yes)
			(layer "B.Fab")
			(hide yes)
			(effects
				(font
					(size 1.016 1.016)
					(thickness 0.1524)
				)
				(justify mirror)
			)
		)
		(duplicate_pad_numbers_are_jumpers no)
		(fp_rect
			(start 0.381 0.7366)
			(end -0.381 -0.7366)
			(stroke
				(width 0)
				(type default)
			)
			(fill no)
			(layer "B.CrtYd")
		)
		(fp_rect
			(start 0.381 0.7366)
			(end -0.381 -0.7366)
			(stroke
				(width 0)
				(type default)
			)
			(fill no)
			(layer "B.Fab")
		)
		(pad "1" smd custom
			(at 0 -0.4572 90)
			(size 0.1143 0.1143)
			(layers "B.Cu" "B.Mask" "B.Paste")
			(net "P1V5_STBY_EN")
			(options
				(clearance outline)
				(anchor circle)
			)
			(primitives
				(gr_poly
					(pts
						(arc
							(start -0.254 0.1778)
							(mid -0.239121 0.213721)
							(end -0.2032 0.2286)
						)
						(arc
							(start 0.2032 0.2286)
							(mid 0.239121 0.213721)
							(end 0.254 0.1778)
						)
						(arc
							(start 0.254 -0.1778)
							(mid 0.239121 -0.213721)
							(end 0.2032 -0.2286)
						)
						(arc
							(start -0.2032 -0.2286)
							(mid -0.239121 -0.213721)
							(end -0.254 -0.1778)
						)
					)
					(width 0)
					(fill yes)
				)
			)
		)
		(pad "2" smd custom
			(at 0 0.4572 90)
			(size 0.1143 0.1143)
			(layers "B.Cu" "B.Mask" "B.Paste")
			(net "GND")
			(options
				(clearance outline)
				(anchor circle)
			)
			(primitives
				(gr_poly
					(pts
						(arc
							(start -0.254 0.1778)
							(mid -0.239121 0.213721)
							(end -0.2032 0.2286)
						)
						(arc
							(start 0.2032 0.2286)
							(mid 0.239121 0.213721)
							(end 0.254 0.1778)
						)
						(arc
							(start 0.254 -0.1778)
							(mid 0.239121 -0.213721)
							(end 0.2032 -0.2286)
						)
						(arc
							(start -0.2032 -0.2286)
							(mid -0.239121 -0.213721)
							(end -0.254 -0.1778)
						)
					)
					(width 0)
					(fill yes)
				)
			)
		)
	)
	(footprint ""
		(layer "B.Cu")
		(at 99.568 -19.431)
		(property "Reference" "C257"
			(at 0 0 0)
			(layer "B.SilkS")
			(hide yes)
			(effects
				(font
					(size 1.27 1.27)
				)
				(justify mirror)
			)
		)
		(property "Value" "SCD1U16V2JX-1-GP"
			(at -1.1811 -2.7051 0)
			(unlocked yes)
			(layer "B.Fab")
			(hide yes)
			(effects
				(font
					(size 1.016 1.016)
					(thickness 0.1524)
				)
				(justify mirror)
			)
		)
		(property "Device Type" "C402H22"
			(at -1.1811 -4.2291 0)
			(unlocked yes)
			(layer "B.Fab")
			(hide yes)
			(effects
				(font
					(size 1.016 1.016)
					(thickness 0.1524)
				)
				(justify mirror)
			)
		)
		(duplicate_pad_numbers_are_jumpers no)
		(fp_rect
			(start 0.381 0.7366)
			(end -0.381 -0.7366)
			(stroke
				(width 0)
				(type default)
			)
			(fill no)
			(layer "B.CrtYd")
		)
		(fp_rect
			(start 0.381 0.7366)
			(end -0.381 -0.7366)
			(stroke
				(width 0)
				(type default)
			)
			(fill no)
			(layer "B.Fab")
		)
		(pad "1" smd custom
			(at 0 -0.4572 180)
			(size 0.1143 0.1143)
			(layers "B.Cu" "B.Mask" "B.Paste")
			(net "VCCCLKDDR1")
			(options
				(clearance outline)
				(anchor circle)
			)
			(primitives
				(gr_poly
					(pts
						(arc
							(start -0.254 0.1778)
							(mid -0.239121 0.213721)
							(end -0.2032 0.2286)
						)
						(arc
							(start 0.2032 0.2286)
							(mid 0.239121 0.213721)
							(end 0.254 0.1778)
						)
						(arc
							(start 0.254 -0.1778)
							(mid 0.239121 -0.213721)
							(end 0.2032 -0.2286)
						)
						(arc
							(start -0.2032 -0.2286)
							(mid -0.239121 -0.213721)
							(end -0.254 -0.1778)
						)
					)
					(width 0)
					(fill yes)
				)
			)
		)
		(pad "2" smd custom
			(at 0 0.4572 180)
			(size 0.1143 0.1143)
			(layers "B.Cu" "B.Mask" "B.Paste")
			(net "GND")
			(options
				(clearance outline)
				(anchor circle)
			)
			(primitives
				(gr_poly
					(pts
						(arc
							(start -0.254 0.1778)
							(mid -0.239121 0.213721)
							(end -0.2032 0.2286)
						)
						(arc
							(start 0.2032 0.2286)
							(mid 0.239121 0.213721)
							(end 0.254 0.1778)
						)
						(arc
							(start 0.254 -0.1778)
							(mid 0.239121 -0.213721)
							(end 0.2032 -0.2286)
						)
						(arc
							(start -0.2032 -0.2286)
							(mid -0.239121 -0.213721)
							(end -0.254 -0.1778)
						)
					)
					(width 0)
					(fill yes)
				)
			)
		)
	)
	(footprint ""
		(layer "B.Cu")
		(at 15.875 -24.003 90)
		(property "Reference" "PR96"
			(at 0 0 90)
			(layer "B.SilkS")
			(hide yes)
			(effects
				(font
					(size 1.27 1.27)
				)
				(justify mirror)
			)
		)
		(property "Value" "15KR2F-GP"
			(at -1.7907 -1.1176 90)
			(unlocked yes)
			(layer "B.Fab")
			(hide yes)
			(effects
				(font
					(size 1.016 1.016)
					(thickness 0.1524)
				)
				(justify mirror)
			)
		)
		(property "Device Type" "R402H16"
			(at -1.7907 -2.6416 90)
			(unlocked yes)
			(layer "B.Fab")
			(hide yes)
			(effects
				(font
					(size 1.016 1.016)
					(thickness 0.1524)
				)
				(justify mirror)
			)
		)
		(duplicate_pad_numbers_are_jumpers no)
		(fp_rect
			(start 0.381 0.8382)
			(end -0.381 -0.8382)
			(stroke
				(width 0)
				(type default)
			)
			(fill no)
			(layer "B.CrtYd")
		)
		(fp_rect
			(start 0.381 0.8382)
			(end -0.381 -0.8382)
			(stroke
				(width 0)
				(type default)
			)
			(fill no)
			(layer "B.Fab")
		)
		(pad "1" smd custom
			(at 0 -0.4318 270)
			(size 0.127 0.127)
			(layers "B.Cu" "B.Mask" "B.Paste")
			(net "GND")
			(options
				(clearance outline)
				(anchor circle)
			)
			(primitives
				(gr_poly
					(pts
						(arc
							(start -0.2032 0.2794)
							(mid -0.239121 0.264521)
							(end -0.254 0.2286)
						)
						(arc
							(start -0.254 -0.2286)
							(mid -0.239121 -0.264521)
							(end -0.2032 -0.2794)
						)
						(arc
							(start 0.2032 -0.2794)
							(mid 0.239121 -0.264521)
							(end 0.254 -0.2286)
						)
						(arc
							(start 0.254 0.2286)
							(mid 0.239121 0.264521)
							(end 0.2032 0.2794)
						)
					)
					(width 0)
					(fill yes)
				)
			)
		)
		(pad "2" smd custom
			(at 0 0.4318 270)
			(size 0.127 0.127)
			(layers "B.Cu" "B.Mask" "B.Paste")
			(net "PG_P1V0")
			(options
				(clearance outline)
				(anchor circle)
			)
			(primitives
				(gr_poly
					(pts
						(arc
							(start -0.2032 0.2794)
							(mid -0.239121 0.264521)
							(end -0.254 0.2286)
						)
						(arc
							(start -0.254 -0.2286)
							(mid -0.239121 -0.264521)
							(end -0.2032 -0.2794)
						)
						(arc
							(start 0.2032 -0.2794)
							(mid 0.239121 -0.264521)
							(end 0.254 -0.2286)
						)
						(arc
							(start 0.254 0.2286)
							(mid 0.239121 0.264521)
							(end 0.2032 0.2794)
						)
					)
					(width 0)
					(fill yes)
				)
			)
		)
	)
	(footprint ""
		(layer "B.Cu")
		(at 88.011 -18.542)
		(property "Reference" "PR221"
			(at 0 0 0)
			(layer "B.SilkS")
			(hide yes)
			(effects
				(font
					(size 1.27 1.27)
				)
				(justify mirror)
			)
		)
		(property "Value" "0R6J-3-GP"
			(at 0.0508 -4.8514 0)
			(unlocked yes)
			(layer "B.Fab")
			(hide yes)
			(effects
				(font
					(size 1.016 1.016)
					(thickness 0.1524)
				)
				(justify mirror)
			)
		)
		(property "Device Type" "R1206H28"
			(at 0 -6.3754 0)
			(unlocked yes)
			(layer "B.Fab")
			(hide yes)
			(effects
				(font
					(size 1.016 1.016)
					(thickness 0.1524)
				)
				(justify mirror)
			)
		)
		(duplicate_pad_numbers_are_jumpers no)
		(fp_line
			(start -0.7239 -0.381)
			(end 0.7239 -0.381)
			(stroke
				(width 0.1524)
				(type default)
			)
			(layer "B.SilkS")
		)
		(fp_line
			(start -0.7239 0.381)
			(end -0.7239 -0.381)
			(stroke
				(width 0.1524)
				(type default)
			)
			(layer "B.SilkS")
		)
		(fp_line
			(start 0.7239 -0.381)
			(end 0.7239 0.381)
			(stroke
				(width 0.1524)
				(type default)
			)
			(layer "B.SilkS")
		)
		(fp_line
			(start 0.7239 0.381)
			(end -0.7239 0.381)
			(stroke
				(width 0.1524)
				(type default)
			)
			(layer "B.SilkS")
		)
		(fp_poly
			(pts
				(xy 0.7239 0.381) (xy -0.7239 0.381) (xy -0.7239 -0.381) (xy 0.7239 -0.381)
			)
			(stroke
				(width 0)
				(type default)
			)
			(fill yes)
			(layer "B.SilkS")
		)
		(fp_rect
			(start 1.0541 1.9812)
			(end -1.0541 -1.9812)
			(stroke
				(width 0)
				(type default)
			)
			(fill no)
			(layer "B.CrtYd")
		)
		(fp_rect
			(start 1.0541 1.9812)
			(end -1.0541 -1.9812)
			(stroke
				(width 0)
				(type default)
			)
			(fill no)
			(layer "B.Fab")
		)
		(pad "1" smd rect
			(at 0 -1.3462 180)
			(size 1.8542 1.016)
			(layers "B.Cu" "B.Mask" "B.Paste")
			(net "P1V35")
		)
		(pad "2" smd rect
			(at 0 1.3462 180)
			(size 1.8542 1.016)
			(layers "B.Cu" "B.Mask" "B.Paste")
			(net "TPS74801_1V35_OUT")
		)
	)
	(footprint ""
		(layer "B.Cu")
		(at 75.819 -61.849)
		(property "Reference" "R190"
			(at 0 0 0)
			(layer "B.SilkS")
			(hide yes)
			(effects
				(font
					(size 1.27 1.27)
				)
				(justify mirror)
			)
		)
		(property "Value" "0R2J-2-GP"
			(at -0.064008 -3.993896 0)
			(unlocked yes)
			(layer "B.Fab")
			(hide yes)
			(effects
				(font
					(size 1.016 1.016)
					(thickness 0.1524)
				)
				(justify mirror)
			)
		)
		(property "Device Type" "R402H16"
			(at -0.064008 -5.517896 0)
			(unlocked yes)
			(layer "B.Fab")
			(hide yes)
			(effects
				(font
					(size 1.016 1.016)
					(thickness 0.1524)
				)
				(justify mirror)
			)
		)
		(duplicate_pad_numbers_are_jumpers no)
		(fp_rect
			(start 0.381 0.8382)
			(end -0.381 -0.8382)
			(stroke
				(width 0)
				(type default)
			)
			(fill no)
			(layer "B.CrtYd")
		)
		(fp_rect
			(start 0.381 0.8382)
			(end -0.381 -0.8382)
			(stroke
				(width 0)
				(type default)
			)
			(fill no)
			(layer "B.Fab")
		)
		(pad "1" smd custom
			(at 0 -0.4318 180)
			(size 0.127 0.127)
			(layers "B.Cu" "B.Mask" "B.Paste")
			(net "PVNN")
			(options
				(clearance outline)
				(anchor circle)
			)
			(primitives
				(gr_poly
					(pts
						(arc
							(start -0.2032 0.2794)
							(mid -0.239121 0.264521)
							(end -0.254 0.2286)
						)
						(arc
							(start -0.254 -0.2286)
							(mid -0.239121 -0.264521)
							(end -0.2032 -0.2794)
						)
						(arc
							(start 0.2032 -0.2794)
							(mid 0.239121 -0.264521)
							(end 0.254 -0.2286)
						)
						(arc
							(start 0.254 0.2286)
							(mid 0.239121 0.264521)
							(end 0.2032 0.2794)
						)
					)
					(width 0)
					(fill yes)
				)
			)
		)
		(pad "2" smd custom
			(at 0 0.4318 180)
			(size 0.127 0.127)
			(layers "B.Cu" "B.Mask" "B.Paste")
			(net "PVNN_SENSE")
			(options
				(clearance outline)
				(anchor circle)
			)
			(primitives
				(gr_poly
					(pts
						(arc
							(start -0.2032 0.2794)
							(mid -0.239121 0.264521)
							(end -0.254 0.2286)
						)
						(arc
							(start -0.254 -0.2286)
							(mid -0.239121 -0.264521)
							(end -0.2032 -0.2794)
						)
						(arc
							(start 0.2032 -0.2794)
							(mid 0.239121 -0.264521)
							(end 0.254 -0.2286)
						)
						(arc
							(start 0.254 0.2286)
							(mid 0.239121 0.264521)
							(end 0.2032 0.2794)
						)
					)
					(width 0)
					(fill yes)
				)
			)
		)
	)
	(footprint ""
		(layer "B.Cu")
		(at 95.2754 -30.1498 -90)
		(property "Reference" "TP48"
			(at 0 0 90)
			(layer "B.SilkS")
			(hide yes)
			(effects
				(font
					(size 1.27 1.27)
				)
				(justify mirror)
			)
		)
		(property "Value" "TPAD24"
			(at 0 -2.9972 270)
			(unlocked yes)
			(layer "B.Fab")
			(hide yes)
			(effects
				(font
					(size 1.016 1.016)
					(thickness 0.1524)
				)
				(justify mirror)
			)
		)
		(property "Device Type" "TPAD24"
			(at 0 -4.5212 270)
			(unlocked yes)
			(layer "B.Fab")
			(hide yes)
			(effects
				(font
					(size 1.016 1.016)
					(thickness 0.1524)
				)
				(justify mirror)
			)
		)
		(duplicate_pad_numbers_are_jumpers no)
		(fp_poly
			(pts
				(arc
					(start 0 -0.3048)
					(mid 0 0.3048)
					(end 0 -0.3048)
				)
			)
			(stroke
				(width 0)
				(type default)
			)
			(fill no)
			(layer "B.CrtYd")
		)
		(fp_poly
			(pts
				(arc
					(start 0 -0.6096)
					(mid 0 0.6096)
					(end 0 -0.6096)
				)
			)
			(stroke
				(width 0)
				(type default)
			)
			(fill no)
			(layer "B.Fab")
		)
		(pad "1" smd circle
			(at 0 0 90)
			(size 0.6096 0.6096)
			(layers "B.Cu" "B.Mask" "B.Paste")
			(net "TP_CPU_RSVD15")
		)
	)
	(footprint ""
		(layer "B.Cu")
		(at 66.3702 -23.3426 180)
		(property "Reference" "R394"
			(at 0 0 0)
			(layer "B.SilkS")
			(hide yes)
			(effects
				(font
					(size 1.27 1.27)
				)
				(justify mirror)
			)
		)
		(property "Value" "300R2F-GP"
			(at -1.7907 -1.1176 180)
			(unlocked yes)
			(layer "B.Fab")
			(hide yes)
			(effects
				(font
					(size 1.016 1.016)
					(thickness 0.1524)
				)
				(justify mirror)
			)
		)
		(property "Device Type" "R402H16"
			(at -1.7907 -2.6416 180)
			(unlocked yes)
			(layer "B.Fab")
			(hide yes)
			(effects
				(font
					(size 1.016 1.016)
					(thickness 0.1524)
				)
				(justify mirror)
			)
		)
		(duplicate_pad_numbers_are_jumpers no)
		(fp_rect
			(start 0.381 0.8382)
			(end -0.381 -0.8382)
			(stroke
				(width 0)
				(type default)
			)
			(fill no)
			(layer "B.CrtYd")
		)
		(fp_rect
			(start 0.381 0.8382)
			(end -0.381 -0.8382)
			(stroke
				(width 0)
				(type default)
			)
			(fill no)
			(layer "B.Fab")
		)
		(pad "1" smd custom
			(at 0 -0.4318)
			(size 0.127 0.127)
			(layers "B.Cu" "B.Mask" "B.Paste")
			(net "P3V3")
			(options
				(clearance outline)
				(anchor circle)
			)
			(primitives
				(gr_poly
					(pts
						(arc
							(start -0.2032 0.2794)
							(mid -0.239121 0.264521)
							(end -0.254 0.2286)
						)
						(arc
							(start -0.254 -0.2286)
							(mid -0.239121 -0.264521)
							(end -0.2032 -0.2794)
						)
						(arc
							(start 0.2032 -0.2794)
							(mid 0.239121 -0.264521)
							(end 0.254 -0.2286)
						)
						(arc
							(start 0.254 0.2286)
							(mid 0.239121 0.264521)
							(end 0.2032 0.2794)
						)
					)
					(width 0)
					(fill yes)
				)
			)
		)
		(pad "2" smd custom
			(at 0 0.4318)
			(size 0.127 0.127)
			(layers "B.Cu" "B.Mask" "B.Paste")
			(net "LED_MSATA_DAS_R")
			(options
				(clearance outline)
				(anchor circle)
			)
			(primitives
				(gr_poly
					(pts
						(arc
							(start -0.2032 0.2794)
							(mid -0.239121 0.264521)
							(end -0.254 0.2286)
						)
						(arc
							(start -0.254 -0.2286)
							(mid -0.239121 -0.264521)
							(end -0.2032 -0.2794)
						)
						(arc
							(start 0.2032 -0.2794)
							(mid 0.239121 -0.264521)
							(end 0.254 -0.2286)
						)
						(arc
							(start 0.254 0.2286)
							(mid 0.239121 0.264521)
							(end 0.2032 0.2794)
						)
					)
					(width 0)
					(fill yes)
				)
			)
		)
	)
	(footprint ""
		(layer "B.Cu")
		(at 203.2 -70.993 -90)
		(property "Reference" "R1"
			(at 0 0 90)
			(layer "B.SilkS")
			(hide yes)
			(effects
				(font
					(size 1.27 1.27)
				)
				(justify mirror)
			)
		)
		(property "Value" "1KR5F-1-GP"
			(at 0 -4.9022 270)
			(unlocked yes)
			(layer "B.Fab")
			(hide yes)
			(effects
				(font
					(size 1.016 1.016)
					(thickness 0.1524)
				)
				(justify mirror)
			)
		)
		(property "Device Type" "R805H24"
			(at 0 -6.8072 270)
			(unlocked yes)
			(layer "B.Fab")
			(hide yes)
			(effects
				(font
					(size 1.016 1.016)
					(thickness 0.1524)
				)
				(justify mirror)
			)
		)
		(duplicate_pad_numbers_are_jumpers no)
		(fp_line
			(start -0.6096 0)
			(end -0.2794 0)
			(stroke
				(width 0.3048)
				(type default)
			)
			(layer "B.SilkS")
		)
		(fp_line
			(start 0.2794 0)
			(end 0.6096 0)
			(stroke
				(width 0.3048)
				(type default)
			)
			(layer "B.SilkS")
		)
		(fp_poly
			(pts
				(xy 0.9017 1.4351) (xy -0.9017 1.4351) (xy -0.9017 -1.4351) (xy 0.9017 -1.4351)
			)
			(stroke
				(width 0)
				(type default)
			)
			(fill no)
			(layer "B.CrtYd")
		)
		(fp_poly
			(pts
				(xy -0.9017 1.4351) (xy -0.9017 -1.4351) (xy 0.9017 -1.4351) (xy 0.9017 1.4351)
			)
			(stroke
				(width 0)
				(type default)
			)
			(fill no)
			(layer "B.Fab")
		)
		(pad "1" smd rect
			(at 0 -0.8382 90)
			(size 1.5494 0.9398)
			(layers "B.Cu" "B.Mask" "B.Paste")
			(net "P12V")
		)
		(pad "2" smd rect
			(at 0 0.8382 90)
			(size 1.5494 0.9398)
			(layers "B.Cu" "B.Mask" "B.Paste")
			(net "PWR_STATUS_LED")
		)
	)
	(footprint ""
		(layer "B.Cu")
		(at 183.007 -29.591 90)
		(property "Reference" "PC192"
			(at 0 0 90)
			(layer "B.SilkS")
			(hide yes)
			(effects
				(font
					(size 1.27 1.27)
				)
				(justify mirror)
			)
		)
		(property "Value" "SC1500P50V2KX-2GP"
			(at -1.8923 -1.2065 90)
			(unlocked yes)
			(layer "B.Fab")
			(hide yes)
			(effects
				(font
					(size 1.016 1.016)
					(thickness 0.1524)
				)
				(justify mirror)
			)
		)
		(property "Device Type" "C402H22"
			(at -1.8923 -2.7305 90)
			(unlocked yes)
			(layer "B.Fab")
			(hide yes)
			(effects
				(font
					(size 1.016 1.016)
					(thickness 0.1524)
				)
				(justify mirror)
			)
		)
		(duplicate_pad_numbers_are_jumpers no)
		(fp_rect
			(start 0.381 0.7366)
			(end -0.381 -0.7366)
			(stroke
				(width 0)
				(type default)
			)
			(fill no)
			(layer "B.CrtYd")
		)
		(fp_rect
			(start 0.381 0.7366)
			(end -0.381 -0.7366)
			(stroke
				(width 0)
				(type default)
			)
			(fill no)
			(layer "B.Fab")
		)
		(pad "1" smd custom
			(at 0 -0.4572 270)
			(size 0.1143 0.1143)
			(layers "B.Cu" "B.Mask" "B.Paste")
			(net "VSENSE_PVDDR_A_VSEN_FB")
			(options
				(clearance outline)
				(anchor circle)
			)
			(primitives
				(gr_poly
					(pts
						(arc
							(start -0.254 0.1778)
							(mid -0.239121 0.213721)
							(end -0.2032 0.2286)
						)
						(arc
							(start 0.2032 0.2286)
							(mid 0.239121 0.213721)
							(end 0.254 0.1778)
						)
						(arc
							(start 0.254 -0.1778)
							(mid 0.239121 -0.213721)
							(end 0.2032 -0.2286)
						)
						(arc
							(start -0.2032 -0.2286)
							(mid -0.239121 -0.213721)
							(end -0.254 -0.1778)
						)
					)
					(width 0)
					(fill yes)
				)
			)
		)
		(pad "2" smd custom
			(at 0 0.4572 270)
			(size 0.1143 0.1143)
			(layers "B.Cu" "B.Mask" "B.Paste")
			(net "VR_PVDDR_A_VSEN")
			(options
				(clearance outline)
				(anchor circle)
			)
			(primitives
				(gr_poly
					(pts
						(arc
							(start -0.254 0.1778)
							(mid -0.239121 0.213721)
							(end -0.2032 0.2286)
						)
						(arc
							(start 0.2032 0.2286)
							(mid 0.239121 0.213721)
							(end 0.254 0.1778)
						)
						(arc
							(start 0.254 -0.1778)
							(mid 0.239121 -0.213721)
							(end 0.2032 -0.2286)
						)
						(arc
							(start -0.2032 -0.2286)
							(mid -0.239121 -0.213721)
							(end -0.254 -0.1778)
						)
					)
					(width 0)
					(fill yes)
				)
			)
		)
	)
	(footprint ""
		(layer "B.Cu")
		(at 67.183 -27.559 -90)
		(property "Reference" "C48"
			(at 0 0 90)
			(layer "B.SilkS")
			(hide yes)
			(effects
				(font
					(size 1.27 1.27)
				)
				(justify mirror)
			)
		)
		(property "Value" "SCD01U16V2KX-3GP"
			(at -1.1811 -2.7051 270)
			(unlocked yes)
			(layer "B.Fab")
			(hide yes)
			(effects
				(font
					(size 1.016 1.016)
					(thickness 0.1524)
				)
				(justify mirror)
			)
		)
		(property "Device Type" "C402H22"
			(at -1.1811 -4.2291 270)
			(unlocked yes)
			(layer "B.Fab")
			(hide yes)
			(effects
				(font
					(size 1.016 1.016)
					(thickness 0.1524)
				)
				(justify mirror)
			)
		)
		(duplicate_pad_numbers_are_jumpers no)
		(fp_rect
			(start 0.381 0.7366)
			(end -0.381 -0.7366)
			(stroke
				(width 0)
				(type default)
			)
			(fill no)
			(layer "B.CrtYd")
		)
		(fp_rect
			(start 0.381 0.7366)
			(end -0.381 -0.7366)
			(stroke
				(width 0)
				(type default)
			)
			(fill no)
			(layer "B.Fab")
		)
		(pad "1" smd custom
			(at 0 -0.4572 90)
			(size 0.1143 0.1143)
			(layers "B.Cu" "B.Mask" "B.Paste")
			(net "SATA3_TX_DP0")
			(options
				(clearance outline)
				(anchor circle)
			)
			(primitives
				(gr_poly
					(pts
						(arc
							(start -0.254 0.1778)
							(mid -0.239121 0.213721)
							(end -0.2032 0.2286)
						)
						(arc
							(start 0.2032 0.2286)
							(mid 0.239121 0.213721)
							(end 0.254 0.1778)
						)
						(arc
							(start 0.254 -0.1778)
							(mid 0.239121 -0.213721)
							(end 0.2032 -0.2286)
						)
						(arc
							(start -0.2032 -0.2286)
							(mid -0.239121 -0.213721)
							(end -0.254 -0.1778)
						)
					)
					(width 0)
					(fill yes)
				)
			)
		)
		(pad "2" smd custom
			(at 0 0.4572 90)
			(size 0.1143 0.1143)
			(layers "B.Cu" "B.Mask" "B.Paste")
			(net "SATA3_TX_C_DP0")
			(options
				(clearance outline)
				(anchor circle)
			)
			(primitives
				(gr_poly
					(pts
						(arc
							(start -0.254 0.1778)
							(mid -0.239121 0.213721)
							(end -0.2032 0.2286)
						)
						(arc
							(start 0.2032 0.2286)
							(mid 0.239121 0.213721)
							(end 0.254 0.1778)
						)
						(arc
							(start 0.254 -0.1778)
							(mid 0.239121 -0.213721)
							(end 0.2032 -0.2286)
						)
						(arc
							(start -0.2032 -0.2286)
							(mid -0.239121 -0.213721)
							(end -0.254 -0.1778)
						)
					)
					(width 0)
					(fill yes)
				)
			)
		)
	)
	(footprint ""
		(layer "B.Cu")
		(at 113.538 -45.466 180)
		(property "Reference" "C179"
			(at 0 0 0)
			(layer "B.SilkS")
			(hide yes)
			(effects
				(font
					(size 1.27 1.27)
				)
				(justify mirror)
			)
		)
		(property "Value" "SC22U6D3V5MX-2GP"
			(at 0.0762 -6.1214 180)
			(unlocked yes)
			(layer "B.Fab")
			(hide yes)
			(effects
				(font
					(size 1.016 1.016)
					(thickness 0.1524)
				)
				(justify mirror)
			)
		)
		(property "Device Type" "C805H58"
			(at 0.0762 -8.1534 180)
			(unlocked yes)
			(layer "B.Fab")
			(hide yes)
			(effects
				(font
					(size 1.016 1.016)
					(thickness 0.1524)
				)
				(justify mirror)
			)
		)
		(duplicate_pad_numbers_are_jumpers no)
		(fp_line
			(start -0.6096 0)
			(end 0.6096 0)
			(stroke
				(width 0.3048)
				(type default)
			)
			(layer "B.SilkS")
		)
		(fp_poly
			(pts
				(xy 0.9017 1.4351) (xy -0.9017 1.4351) (xy -0.9017 -1.4351) (xy 0.9017 -1.4351)
			)
			(stroke
				(width 0)
				(type default)
			)
			(fill no)
			(layer "B.CrtYd")
		)
		(fp_poly
			(pts
				(xy -0.9017 1.4351) (xy -0.9017 -1.4351) (xy 0.9017 -1.4351) (xy 0.9017 1.4351)
			)
			(stroke
				(width 0)
				(type default)
			)
			(fill no)
			(layer "B.Fab")
		)
		(pad "1" smd rect
			(at 0 -0.8382)
			(size 1.5494 0.9398)
			(layers "B.Cu" "B.Mask" "B.Paste")
			(net "PVCCP")
		)
		(pad "2" smd rect
			(at 0 0.8382)
			(size 1.5494 0.9398)
			(layers "B.Cu" "B.Mask" "B.Paste")
			(net "GND")
		)
	)
	(footprint ""
		(layer "B.Cu")
		(at 16.383 -21.844 180)
		(property "Reference" "R37"
			(at 0 0 0)
			(layer "B.SilkS")
			(hide yes)
			(effects
				(font
					(size 1.27 1.27)
				)
				(justify mirror)
			)
		)
		(property "Value" "0R2J-2-GP"
			(at -1.7907 -1.1176 180)
			(unlocked yes)
			(layer "B.Fab")
			(hide yes)
			(effects
				(font
					(size 1.016 1.016)
					(thickness 0.1524)
				)
				(justify mirror)
			)
		)
		(property "Device Type" "R402H16"
			(at -1.7907 -2.6416 180)
			(unlocked yes)
			(layer "B.Fab")
			(hide yes)
			(effects
				(font
					(size 1.016 1.016)
					(thickness 0.1524)
				)
				(justify mirror)
			)
		)
		(duplicate_pad_numbers_are_jumpers no)
		(fp_rect
			(start 0.381 0.8382)
			(end -0.381 -0.8382)
			(stroke
				(width 0)
				(type default)
			)
			(fill no)
			(layer "B.CrtYd")
		)
		(fp_rect
			(start 0.381 0.8382)
			(end -0.381 -0.8382)
			(stroke
				(width 0)
				(type default)
			)
			(fill no)
			(layer "B.Fab")
		)
		(pad "1" smd custom
			(at 0 -0.4318)
			(size 0.127 0.127)
			(layers "B.Cu" "B.Mask" "B.Paste")
			(net "PWRGD_P1V0_PG")
			(options
				(clearance outline)
				(anchor circle)
			)
			(primitives
				(gr_poly
					(pts
						(arc
							(start -0.2032 0.2794)
							(mid -0.239121 0.264521)
							(end -0.254 0.2286)
						)
						(arc
							(start -0.254 -0.2286)
							(mid -0.239121 -0.264521)
							(end -0.2032 -0.2794)
						)
						(arc
							(start 0.2032 -0.2794)
							(mid 0.239121 -0.264521)
							(end 0.254 -0.2286)
						)
						(arc
							(start 0.254 0.2286)
							(mid 0.239121 0.264521)
							(end 0.2032 0.2794)
						)
					)
					(width 0)
					(fill yes)
				)
			)
		)
		(pad "2" smd custom
			(at 0 0.4318)
			(size 0.127 0.127)
			(layers "B.Cu" "B.Mask" "B.Paste")
			(net "PG_P1V0")
			(options
				(clearance outline)
				(anchor circle)
			)
			(primitives
				(gr_poly
					(pts
						(arc
							(start -0.2032 0.2794)
							(mid -0.239121 0.264521)
							(end -0.254 0.2286)
						)
						(arc
							(start -0.254 -0.2286)
							(mid -0.239121 -0.264521)
							(end -0.2032 -0.2794)
						)
						(arc
							(start 0.2032 -0.2794)
							(mid 0.239121 -0.264521)
							(end 0.254 -0.2286)
						)
						(arc
							(start 0.254 0.2286)
							(mid 0.239121 0.264521)
							(end 0.2032 0.2794)
						)
					)
					(width 0)
					(fill yes)
				)
			)
		)
	)
	(footprint ""
		(layer "B.Cu")
		(at 49.657 -27.9908 -90)
		(property "Reference" "C227"
			(at 0 0 90)
			(layer "B.SilkS")
			(hide yes)
			(effects
				(font
					(size 1.27 1.27)
				)
				(justify mirror)
			)
		)
		(property "Value" "SC1U25V3KX-GP"
			(at 0 -2.8194 270)
			(unlocked yes)
			(layer "B.Fab")
			(hide yes)
			(effects
				(font
					(size 1.016 1.016)
					(thickness 0.1524)
				)
				(justify mirror)
			)
		)
		(property "Device Type" "C603H36"
			(at 0 -4.3434 270)
			(unlocked yes)
			(layer "B.Fab")
			(hide yes)
			(effects
				(font
					(size 1.016 1.016)
					(thickness 0.1524)
				)
				(justify mirror)
			)
		)
		(duplicate_pad_numbers_are_jumpers no)
		(fp_line
			(start 0.4064 0)
			(end -0.4064 0)
			(stroke
				(width 0.2286)
				(type default)
			)
			(layer "B.SilkS")
		)
		(fp_rect
			(start 0.635 1.1811)
			(end -0.635 -1.1811)
			(stroke
				(width 0)
				(type default)
			)
			(fill no)
			(layer "B.CrtYd")
		)
		(fp_rect
			(start 0.635 1.1811)
			(end -0.635 -1.1811)
			(stroke
				(width 0)
				(type default)
			)
			(fill no)
			(layer "B.Fab")
		)
		(pad "1" smd custom
			(at 0 -0.6604 90)
			(size 0.19685 0.19685)
			(layers "B.Cu" "B.Mask" "B.Paste")
			(net "P3V3_VDDA_CLKBUFF")
			(options
				(clearance outline)
				(anchor circle)
			)
			(primitives
				(gr_poly
					(pts
						(arc
							(start 0.508 0.2921)
							(mid 0.478242 0.363942)
							(end 0.4064 0.3937)
						)
						(arc
							(start -0.4064 0.3937)
							(mid -0.478242 0.363942)
							(end -0.508 0.2921)
						)
						(arc
							(start -0.508 -0.2921)
							(mid -0.478242 -0.363942)
							(end -0.4064 -0.3937)
						)
						(arc
							(start 0.4064 -0.3937)
							(mid 0.478242 -0.363942)
							(end 0.508 -0.2921)
						)
					)
					(width 0)
					(fill yes)
				)
			)
		)
		(pad "2" smd custom
			(at 0 0.6604 90)
			(size 0.19685 0.19685)
			(layers "B.Cu" "B.Mask" "B.Paste")
			(net "GND")
			(options
				(clearance outline)
				(anchor circle)
			)
			(primitives
				(gr_poly
					(pts
						(arc
							(start 0.508 0.2921)
							(mid 0.478242 0.363942)
							(end 0.4064 0.3937)
						)
						(arc
							(start -0.4064 0.3937)
							(mid -0.478242 0.363942)
							(end -0.508 0.2921)
						)
						(arc
							(start -0.508 -0.2921)
							(mid -0.478242 -0.363942)
							(end -0.4064 -0.3937)
						)
						(arc
							(start 0.4064 -0.3937)
							(mid 0.478242 -0.363942)
							(end 0.508 -0.2921)
						)
					)
					(width 0)
					(fill yes)
				)
			)
		)
	)
	(footprint ""
		(layer "B.Cu")
		(at 134.366 -45.466 -90)
		(property "Reference" "C144"
			(at 0 0 90)
			(layer "B.SilkS")
			(hide yes)
			(effects
				(font
					(size 1.27 1.27)
				)
				(justify mirror)
			)
		)
		(property "Value" "SCD1U10V2KX-5GP"
			(at -1.1811 -2.7051 270)
			(unlocked yes)
			(layer "B.Fab")
			(hide yes)
			(effects
				(font
					(size 1.016 1.016)
					(thickness 0.1524)
				)
				(justify mirror)
			)
		)
		(property "Device Type" "C402H22"
			(at -1.1811 -4.2291 270)
			(unlocked yes)
			(layer "B.Fab")
			(hide yes)
			(effects
				(font
					(size 1.016 1.016)
					(thickness 0.1524)
				)
				(justify mirror)
			)
		)
		(duplicate_pad_numbers_are_jumpers no)
		(fp_rect
			(start 0.381 0.7366)
			(end -0.381 -0.7366)
			(stroke
				(width 0)
				(type default)
			)
			(fill no)
			(layer "B.CrtYd")
		)
		(fp_rect
			(start 0.381 0.7366)
			(end -0.381 -0.7366)
			(stroke
				(width 0)
				(type default)
			)
			(fill no)
			(layer "B.Fab")
		)
		(pad "1" smd custom
			(at 0 -0.4572 90)
			(size 0.1143 0.1143)
			(layers "B.Cu" "B.Mask" "B.Paste")
			(net "P2V5_STBY")
			(options
				(clearance outline)
				(anchor circle)
			)
			(primitives
				(gr_poly
					(pts
						(arc
							(start -0.254 0.1778)
							(mid -0.239121 0.213721)
							(end -0.2032 0.2286)
						)
						(arc
							(start 0.2032 0.2286)
							(mid 0.239121 0.213721)
							(end 0.254 0.1778)
						)
						(arc
							(start 0.254 -0.1778)
							(mid 0.239121 -0.213721)
							(end 0.2032 -0.2286)
						)
						(arc
							(start -0.2032 -0.2286)
							(mid -0.239121 -0.213721)
							(end -0.254 -0.1778)
						)
					)
					(width 0)
					(fill yes)
				)
			)
		)
		(pad "2" smd custom
			(at 0 0.4572 90)
			(size 0.1143 0.1143)
			(layers "B.Cu" "B.Mask" "B.Paste")
			(net "GND")
			(options
				(clearance outline)
				(anchor circle)
			)
			(primitives
				(gr_poly
					(pts
						(arc
							(start -0.254 0.1778)
							(mid -0.239121 0.213721)
							(end -0.2032 0.2286)
						)
						(arc
							(start 0.2032 0.2286)
							(mid 0.239121 0.213721)
							(end 0.254 0.1778)
						)
						(arc
							(start 0.254 -0.1778)
							(mid 0.239121 -0.213721)
							(end 0.2032 -0.2286)
						)
						(arc
							(start -0.2032 -0.2286)
							(mid -0.239121 -0.213721)
							(end -0.254 -0.1778)
						)
					)
					(width 0)
					(fill yes)
				)
			)
		)
	)
	(footprint ""
		(layer "B.Cu")
		(at 109.982 -31.004002 180)
		(property "Reference" "R360"
			(at 0 0 0)
			(layer "B.SilkS")
			(hide yes)
			(effects
				(font
					(size 1.27 1.27)
				)
				(justify mirror)
			)
		)
		(property "Value" "1KR2F-3-GP"
			(at -0.064008 -3.993896 180)
			(unlocked yes)
			(layer "B.Fab")
			(hide yes)
			(effects
				(font
					(size 1.016 1.016)
					(thickness 0.1524)
				)
				(justify mirror)
			)
		)
		(property "Device Type" "R402H16"
			(at -0.064008 -5.517896 180)
			(unlocked yes)
			(layer "B.Fab")
			(hide yes)
			(effects
				(font
					(size 1.016 1.016)
					(thickness 0.1524)
				)
				(justify mirror)
			)
		)
		(duplicate_pad_numbers_are_jumpers no)
		(fp_rect
			(start 0.381 0.8382)
			(end -0.381 -0.8382)
			(stroke
				(width 0)
				(type default)
			)
			(fill no)
			(layer "B.CrtYd")
		)
		(fp_rect
			(start 0.381 0.8382)
			(end -0.381 -0.8382)
			(stroke
				(width 0)
				(type default)
			)
			(fill no)
			(layer "B.Fab")
		)
		(pad "1" smd custom
			(at 0 -0.4318)
			(size 0.127 0.127)
			(layers "B.Cu" "B.Mask" "B.Paste")
			(net "PV_VDDR")
			(options
				(clearance outline)
				(anchor circle)
			)
			(primitives
				(gr_poly
					(pts
						(arc
							(start -0.2032 0.2794)
							(mid -0.239121 0.264521)
							(end -0.254 0.2286)
						)
						(arc
							(start -0.254 -0.2286)
							(mid -0.239121 -0.264521)
							(end -0.2032 -0.2794)
						)
						(arc
							(start 0.2032 -0.2794)
							(mid 0.239121 -0.264521)
							(end 0.254 -0.2286)
						)
						(arc
							(start 0.254 0.2286)
							(mid 0.239121 0.264521)
							(end 0.2032 0.2794)
						)
					)
					(width 0)
					(fill yes)
				)
			)
		)
		(pad "2" smd custom
			(at 0 0.4318)
			(size 0.127 0.127)
			(layers "B.Cu" "B.Mask" "B.Paste")
			(net "M_DRAM_PWROK")
			(options
				(clearance outline)
				(anchor circle)
			)
			(primitives
				(gr_poly
					(pts
						(arc
							(start -0.2032 0.2794)
							(mid -0.239121 0.264521)
							(end -0.254 0.2286)
						)
						(arc
							(start -0.254 -0.2286)
							(mid -0.239121 -0.264521)
							(end -0.2032 -0.2794)
						)
						(arc
							(start 0.2032 -0.2794)
							(mid 0.239121 -0.264521)
							(end 0.254 -0.2286)
						)
						(arc
							(start 0.254 0.2286)
							(mid 0.239121 0.264521)
							(end 0.2032 0.2794)
						)
					)
					(width 0)
					(fill yes)
				)
			)
		)
	)
	(footprint ""
		(layer "B.Cu")
		(at 67.437 -22.987)
		(property "Reference" "LED16"
			(at 0 0 0)
			(layer "B.SilkS")
			(hide yes)
			(effects
				(font
					(size 1.27 1.27)
				)
				(justify mirror)
			)
		)
		(property "Value" "LED-YG-51-GP"
			(at 0.0381 -2.6162 0)
			(unlocked yes)
			(layer "B.Fab")
			(hide yes)
			(effects
				(font
					(size 1.016 1.016)
					(thickness 0.1524)
				)
				(justify mirror)
			)
		)
		(property "Device Type" "LED1608AKH40"
			(at 0.0381 -4.1402 0)
			(unlocked yes)
			(layer "B.Fab")
			(hide yes)
			(effects
				(font
					(size 1.016 1.016)
					(thickness 0.1524)
				)
				(justify mirror)
			)
		)
		(duplicate_pad_numbers_are_jumpers no)
		(fp_line
			(start 0.5334 1.3081)
			(end -0.5334 1.3081)
			(stroke
				(width 0.254)
				(type default)
			)
			(layer "B.SilkS")
		)
		(fp_rect
			(start 0.6604 1.1811)
			(end -0.6604 -1.1811)
			(stroke
				(width 0)
				(type default)
			)
			(fill no)
			(layer "B.CrtYd")
		)
		(fp_rect
			(start 0.6604 1.1811)
			(end -0.6604 -1.1811)
			(stroke
				(width 0)
				(type default)
			)
			(fill no)
			(layer "B.Fab")
		)
		(pad "A" smd rect
			(at 0 -0.652526 180)
			(size 1.0668 0.8128)
			(layers "B.Cu" "B.Mask" "B.Paste")
			(net "LED_MSATA_DAS_R")
		)
		(pad "K" smd rect
			(at 0 0.652526 180)
			(size 1.0668 0.8128)
			(layers "B.Cu" "B.Mask" "B.Paste")
			(net "MSATA_ACT#")
		)
	)
	(footprint ""
		(layer "B.Cu")
		(at 98.964496 -35.622484 -90)
		(property "Reference" "TP34"
			(at 0 0 90)
			(layer "B.SilkS")
			(hide yes)
			(effects
				(font
					(size 1.27 1.27)
				)
				(justify mirror)
			)
		)
		(property "Value" "TPAD24"
			(at 0 -2.9972 270)
			(unlocked yes)
			(layer "B.Fab")
			(hide yes)
			(effects
				(font
					(size 1.016 1.016)
					(thickness 0.1524)
				)
				(justify mirror)
			)
		)
		(property "Device Type" "TPAD24"
			(at 0 -4.5212 270)
			(unlocked yes)
			(layer "B.Fab")
			(hide yes)
			(effects
				(font
					(size 1.016 1.016)
					(thickness 0.1524)
				)
				(justify mirror)
			)
		)
		(duplicate_pad_numbers_are_jumpers no)
		(fp_poly
			(pts
				(arc
					(start 0 -0.3048)
					(mid 0 0.3048)
					(end 0 -0.3048)
				)
			)
			(stroke
				(width 0)
				(type default)
			)
			(fill no)
			(layer "B.CrtYd")
		)
		(fp_poly
			(pts
				(arc
					(start 0 -0.6096)
					(mid 0 0.6096)
					(end 0 -0.6096)
				)
			)
			(stroke
				(width 0)
				(type default)
			)
			(fill no)
			(layer "B.Fab")
		)
		(pad "1" smd circle
			(at 0 0 90)
			(size 0.6096 0.6096)
			(layers "B.Cu" "B.Mask" "B.Paste")
			(net "TP_CPU_RSVD12")
		)
	)
	(footprint ""
		(layer "B.Cu")
		(at 18.796 -23.241 -90)
		(property "Reference" "PC64"
			(at 0 0 90)
			(layer "B.SilkS")
			(hide yes)
			(effects
				(font
					(size 1.27 1.27)
				)
				(justify mirror)
			)
		)
		(property "Value" "SC1KP50V2KX-1GP"
			(at -1.8923 -1.2065 270)
			(unlocked yes)
			(layer "B.Fab")
			(hide yes)
			(effects
				(font
					(size 1.016 1.016)
					(thickness 0.1524)
				)
				(justify mirror)
			)
		)
		(property "Device Type" "C402H22"
			(at -1.8923 -2.7305 270)
			(unlocked yes)
			(layer "B.Fab")
			(hide yes)
			(effects
				(font
					(size 1.016 1.016)
					(thickness 0.1524)
				)
				(justify mirror)
			)
		)
		(duplicate_pad_numbers_are_jumpers no)
		(fp_rect
			(start 0.381 0.7366)
			(end -0.381 -0.7366)
			(stroke
				(width 0)
				(type default)
			)
			(fill no)
			(layer "B.CrtYd")
		)
		(fp_rect
			(start 0.381 0.7366)
			(end -0.381 -0.7366)
			(stroke
				(width 0)
				(type default)
			)
			(fill no)
			(layer "B.Fab")
		)
		(pad "1" smd custom
			(at 0 -0.4572 90)
			(size 0.1143 0.1143)
			(layers "B.Cu" "B.Mask" "B.Paste")
			(net "AGND_P1V0")
			(options
				(clearance outline)
				(anchor circle)
			)
			(primitives
				(gr_poly
					(pts
						(arc
							(start -0.254 0.1778)
							(mid -0.239121 0.213721)
							(end -0.2032 0.2286)
						)
						(arc
							(start 0.2032 0.2286)
							(mid 0.239121 0.213721)
							(end 0.254 0.1778)
						)
						(arc
							(start 0.254 -0.1778)
							(mid 0.239121 -0.213721)
							(end 0.2032 -0.2286)
						)
						(arc
							(start -0.2032 -0.2286)
							(mid -0.239121 -0.213721)
							(end -0.254 -0.1778)
						)
					)
					(width 0)
					(fill yes)
				)
			)
		)
		(pad "2" smd custom
			(at 0 0.4572 90)
			(size 0.1143 0.1143)
			(layers "B.Cu" "B.Mask" "B.Paste")
			(net "P1V0_ROVP")
			(options
				(clearance outline)
				(anchor circle)
			)
			(primitives
				(gr_poly
					(pts
						(arc
							(start -0.254 0.1778)
							(mid -0.239121 0.213721)
							(end -0.2032 0.2286)
						)
						(arc
							(start 0.2032 0.2286)
							(mid 0.239121 0.213721)
							(end 0.254 0.1778)
						)
						(arc
							(start 0.254 -0.1778)
							(mid 0.239121 -0.213721)
							(end 0.2032 -0.2286)
						)
						(arc
							(start -0.2032 -0.2286)
							(mid -0.239121 -0.213721)
							(end -0.254 -0.1778)
						)
					)
					(width 0)
					(fill yes)
				)
			)
		)
	)
	(footprint ""
		(layer "B.Cu")
		(at 94.1578 -41.91 -90)
		(property "Reference" "TP23"
			(at 0 0 90)
			(layer "B.SilkS")
			(hide yes)
			(effects
				(font
					(size 1.27 1.27)
				)
				(justify mirror)
			)
		)
		(property "Value" "TPAD24"
			(at 0 -2.9972 270)
			(unlocked yes)
			(layer "B.Fab")
			(hide yes)
			(effects
				(font
					(size 1.016 1.016)
					(thickness 0.1524)
				)
				(justify mirror)
			)
		)
		(property "Device Type" "TPAD24"
			(at 0 -4.5212 270)
			(unlocked yes)
			(layer "B.Fab")
			(hide yes)
			(effects
				(font
					(size 1.016 1.016)
					(thickness 0.1524)
				)
				(justify mirror)
			)
		)
		(duplicate_pad_numbers_are_jumpers no)
		(fp_poly
			(pts
				(arc
					(start 0 -0.3048)
					(mid 0 0.3048)
					(end 0 -0.3048)
				)
			)
			(stroke
				(width 0)
				(type default)
			)
			(fill no)
			(layer "B.CrtYd")
		)
		(fp_poly
			(pts
				(arc
					(start 0 -0.6096)
					(mid 0 0.6096)
					(end 0 -0.6096)
				)
			)
			(stroke
				(width 0)
				(type default)
			)
			(fill no)
			(layer "B.Fab")
		)
		(pad "1" smd circle
			(at 0 0 90)
			(size 0.6096 0.6096)
			(layers "B.Cu" "B.Mask" "B.Paste")
			(net "TP_CPU_RSVD2")
		)
	)
	(footprint ""
		(layer "B.Cu")
		(at 94.740984 -17.288002 90)
		(property "Reference" "L9"
			(at 0 0 90)
			(layer "B.SilkS")
			(hide yes)
			(effects
				(font
					(size 1.27 1.27)
				)
				(justify mirror)
			)
		)
		(property "Value" "BLM18PG121SN1D-GP"
			(at 0.0254 -2.8956 90)
			(unlocked yes)
			(layer "B.Fab")
			(hide yes)
			(effects
				(font
					(size 1.016 1.016)
					(thickness 0.1524)
				)
				(justify mirror)
			)
		)
		(property "Device Type" "L1608-UH38"
			(at 0.0254 -4.4196 90)
			(unlocked yes)
			(layer "B.Fab")
			(hide yes)
			(effects
				(font
					(size 1.016 1.016)
					(thickness 0.1524)
				)
				(justify mirror)
			)
		)
		(duplicate_pad_numbers_are_jumpers no)
		(fp_line
			(start 0.4064 0)
			(end -0.4064 0)
			(stroke
				(width 0.2032)
				(type default)
			)
			(layer "B.SilkS")
		)
		(fp_rect
			(start 0.635 1.1811)
			(end -0.635 -1.1811)
			(stroke
				(width 0)
				(type default)
			)
			(fill no)
			(layer "B.CrtYd")
		)
		(fp_rect
			(start 0.635 1.1811)
			(end -0.635 -1.1811)
			(stroke
				(width 0)
				(type default)
			)
			(fill no)
			(layer "B.Fab")
		)
		(pad "1" smd custom
			(at 0 -0.6604 270)
			(size 0.19685 0.19685)
			(layers "B.Cu" "B.Mask" "B.Paste")
			(net "P1V0")
			(options
				(clearance outline)
				(anchor circle)
			)
			(primitives
				(gr_poly
					(pts
						(arc
							(start 0.508 0.2921)
							(mid 0.478242 0.363942)
							(end 0.4064 0.3937)
						)
						(arc
							(start -0.4064 0.3937)
							(mid -0.478242 0.363942)
							(end -0.508 0.2921)
						)
						(arc
							(start -0.508 -0.2921)
							(mid -0.478242 -0.363942)
							(end -0.4064 -0.3937)
						)
						(arc
							(start 0.4064 -0.3937)
							(mid 0.478242 -0.363942)
							(end 0.508 -0.2921)
						)
					)
					(width 0)
					(fill yes)
				)
			)
		)
		(pad "2" smd custom
			(at 0 0.6604 270)
			(size 0.19685 0.19685)
			(layers "B.Cu" "B.Mask" "B.Paste")
			(net "VCCACKDDR1")
			(options
				(clearance outline)
				(anchor circle)
			)
			(primitives
				(gr_poly
					(pts
						(arc
							(start 0.508 0.2921)
							(mid 0.478242 0.363942)
							(end 0.4064 0.3937)
						)
						(arc
							(start -0.4064 0.3937)
							(mid -0.478242 0.363942)
							(end -0.508 0.2921)
						)
						(arc
							(start -0.508 -0.2921)
							(mid -0.478242 -0.363942)
							(end -0.4064 -0.3937)
						)
						(arc
							(start 0.4064 -0.3937)
							(mid 0.478242 -0.363942)
							(end 0.508 -0.2921)
						)
					)
					(width 0)
					(fill yes)
				)
			)
		)
	)
	(footprint ""
		(layer "B.Cu")
		(at 102.489 -51.451002 180)
		(property "Reference" "C129"
			(at 0 0 0)
			(layer "B.SilkS")
			(hide yes)
			(effects
				(font
					(size 1.27 1.27)
				)
				(justify mirror)
			)
		)
		(property "Value" "SC1U10V2KX-1GP"
			(at -1.1811 -2.7051 180)
			(unlocked yes)
			(layer "B.Fab")
			(hide yes)
			(effects
				(font
					(size 1.016 1.016)
					(thickness 0.1524)
				)
				(justify mirror)
			)
		)
		(property "Device Type" "C402H22"
			(at -1.1811 -4.2291 180)
			(unlocked yes)
			(layer "B.Fab")
			(hide yes)
			(effects
				(font
					(size 1.016 1.016)
					(thickness 0.1524)
				)
				(justify mirror)
			)
		)
		(duplicate_pad_numbers_are_jumpers no)
		(fp_rect
			(start 0.381 0.7366)
			(end -0.381 -0.7366)
			(stroke
				(width 0)
				(type default)
			)
			(fill no)
			(layer "B.CrtYd")
		)
		(fp_rect
			(start 0.381 0.7366)
			(end -0.381 -0.7366)
			(stroke
				(width 0)
				(type default)
			)
			(fill no)
			(layer "B.Fab")
		)
		(pad "1" smd custom
			(at 0 -0.4572)
			(size 0.1143 0.1143)
			(layers "B.Cu" "B.Mask" "B.Paste")
			(net "PV_VDDR")
			(options
				(clearance outline)
				(anchor circle)
			)
			(primitives
				(gr_poly
					(pts
						(arc
							(start -0.254 0.1778)
							(mid -0.239121 0.213721)
							(end -0.2032 0.2286)
						)
						(arc
							(start 0.2032 0.2286)
							(mid 0.239121 0.213721)
							(end 0.254 0.1778)
						)
						(arc
							(start 0.254 -0.1778)
							(mid 0.239121 -0.213721)
							(end 0.2032 -0.2286)
						)
						(arc
							(start -0.2032 -0.2286)
							(mid -0.239121 -0.213721)
							(end -0.254 -0.1778)
						)
					)
					(width 0)
					(fill yes)
				)
			)
		)
		(pad "2" smd custom
			(at 0 0.4572)
			(size 0.1143 0.1143)
			(layers "B.Cu" "B.Mask" "B.Paste")
			(net "GND")
			(options
				(clearance outline)
				(anchor circle)
			)
			(primitives
				(gr_poly
					(pts
						(arc
							(start -0.254 0.1778)
							(mid -0.239121 0.213721)
							(end -0.2032 0.2286)
						)
						(arc
							(start 0.2032 0.2286)
							(mid 0.239121 0.213721)
							(end 0.254 0.1778)
						)
						(arc
							(start 0.254 -0.1778)
							(mid 0.239121 -0.213721)
							(end 0.2032 -0.2286)
						)
						(arc
							(start -0.2032 -0.2286)
							(mid -0.239121 -0.213721)
							(end -0.254 -0.1778)
						)
					)
					(width 0)
					(fill yes)
				)
			)
		)
	)
	(footprint ""
		(layer "B.Cu")
		(at 60.833 -13.335 180)
		(property "Reference" "R382"
			(at 0 0 0)
			(layer "B.SilkS")
			(hide yes)
			(effects
				(font
					(size 1.27 1.27)
				)
				(justify mirror)
			)
		)
		(property "Value" "0R2J-2-GP"
			(at -0.064008 -3.993896 180)
			(unlocked yes)
			(layer "B.Fab")
			(hide yes)
			(effects
				(font
					(size 1.016 1.016)
					(thickness 0.1524)
				)
				(justify mirror)
			)
		)
		(property "Device Type" "R402H16"
			(at -0.064008 -5.517896 180)
			(unlocked yes)
			(layer "B.Fab")
			(hide yes)
			(effects
				(font
					(size 1.016 1.016)
					(thickness 0.1524)
				)
				(justify mirror)
			)
		)
		(duplicate_pad_numbers_are_jumpers no)
		(fp_rect
			(start 0.381 0.8382)
			(end -0.381 -0.8382)
			(stroke
				(width 0)
				(type default)
			)
			(fill no)
			(layer "B.CrtYd")
		)
		(fp_rect
			(start 0.381 0.8382)
			(end -0.381 -0.8382)
			(stroke
				(width 0)
				(type default)
			)
			(fill no)
			(layer "B.Fab")
		)
		(pad "1" smd custom
			(at 0 -0.4318)
			(size 0.127 0.127)
			(layers "B.Cu" "B.Mask" "B.Paste")
			(net "PCIE1_RESET#")
			(options
				(clearance outline)
				(anchor circle)
			)
			(primitives
				(gr_poly
					(pts
						(arc
							(start -0.2032 0.2794)
							(mid -0.239121 0.264521)
							(end -0.254 0.2286)
						)
						(arc
							(start -0.254 -0.2286)
							(mid -0.239121 -0.264521)
							(end -0.2032 -0.2794)
						)
						(arc
							(start 0.2032 -0.2794)
							(mid 0.239121 -0.264521)
							(end 0.254 -0.2286)
						)
						(arc
							(start 0.254 0.2286)
							(mid 0.239121 0.264521)
							(end 0.2032 0.2794)
						)
					)
					(width 0)
					(fill yes)
				)
			)
		)
		(pad "2" smd custom
			(at 0 0.4318)
			(size 0.127 0.127)
			(layers "B.Cu" "B.Mask" "B.Paste")
			(net "PMU_BUF_PLTRST#")
			(options
				(clearance outline)
				(anchor circle)
			)
			(primitives
				(gr_poly
					(pts
						(arc
							(start -0.2032 0.2794)
							(mid -0.239121 0.264521)
							(end -0.254 0.2286)
						)
						(arc
							(start -0.254 -0.2286)
							(mid -0.239121 -0.264521)
							(end -0.2032 -0.2794)
						)
						(arc
							(start 0.2032 -0.2794)
							(mid 0.239121 -0.264521)
							(end 0.254 -0.2286)
						)
						(arc
							(start 0.254 0.2286)
							(mid 0.239121 0.264521)
							(end 0.2032 0.2794)
						)
					)
					(width 0)
					(fill yes)
				)
			)
		)
	)
	(footprint ""
		(layer "B.Cu")
		(at 86.60384 -38.2016 90)
		(property "Reference" "R331"
			(at 0 0 90)
			(layer "B.SilkS")
			(hide yes)
			(effects
				(font
					(size 1.27 1.27)
				)
				(justify mirror)
			)
		)
		(property "Value" "1MR3F-GP"
			(at 0.0254 -2.5146 90)
			(unlocked yes)
			(layer "B.Fab")
			(hide yes)
			(effects
				(font
					(size 1.016 1.016)
					(thickness 0.1524)
				)
				(justify mirror)
			)
		)
		(property "Device Type" "R603H22"
			(at 0.0254 -4.0386 90)
			(unlocked yes)
			(layer "B.Fab")
			(hide yes)
			(effects
				(font
					(size 1.016 1.016)
					(thickness 0.1524)
				)
				(justify mirror)
			)
		)
		(duplicate_pad_numbers_are_jumpers no)
		(fp_line
			(start 0.2032 0)
			(end 0.4191 0)
			(stroke
				(width 0.2032)
				(type default)
			)
			(layer "B.SilkS")
		)
		(fp_line
			(start -0.4318 0)
			(end -0.2032 0)
			(stroke
				(width 0.2032)
				(type default)
			)
			(layer "B.SilkS")
		)
		(fp_rect
			(start 0.635 1.1811)
			(end -0.635 -1.1811)
			(stroke
				(width 0)
				(type default)
			)
			(fill no)
			(layer "B.CrtYd")
		)
		(fp_rect
			(start 0.635 1.1811)
			(end -0.635 -1.1811)
			(stroke
				(width 0)
				(type default)
			)
			(fill no)
			(layer "B.Fab")
		)
		(pad "1" smd custom
			(at 0 -0.6604 270)
			(size 0.19685 0.19685)
			(layers "B.Cu" "B.Mask" "B.Paste")
			(net "PU_INTRUDER#")
			(options
				(clearance outline)
				(anchor circle)
			)
			(primitives
				(gr_poly
					(pts
						(arc
							(start 0.508 0.2921)
							(mid 0.478242 0.363942)
							(end 0.4064 0.3937)
						)
						(arc
							(start -0.4064 0.3937)
							(mid -0.478242 0.363942)
							(end -0.508 0.2921)
						)
						(arc
							(start -0.508 -0.2921)
							(mid -0.478242 -0.363942)
							(end -0.4064 -0.3937)
						)
						(arc
							(start 0.4064 -0.3937)
							(mid 0.478242 -0.363942)
							(end 0.508 -0.2921)
						)
					)
					(width 0)
					(fill yes)
				)
			)
		)
		(pad "2" smd custom
			(at 0 0.6604 270)
			(size 0.19685 0.19685)
			(layers "B.Cu" "B.Mask" "B.Paste")
			(net "P3V3_RTC")
			(options
				(clearance outline)
				(anchor circle)
			)
			(primitives
				(gr_poly
					(pts
						(arc
							(start 0.508 0.2921)
							(mid 0.478242 0.363942)
							(end 0.4064 0.3937)
						)
						(arc
							(start -0.4064 0.3937)
							(mid -0.478242 0.363942)
							(end -0.508 0.2921)
						)
						(arc
							(start -0.508 -0.2921)
							(mid -0.478242 -0.363942)
							(end -0.4064 -0.3937)
						)
						(arc
							(start 0.4064 -0.3937)
							(mid 0.478242 -0.363942)
							(end 0.508 -0.2921)
						)
					)
					(width 0)
					(fill yes)
				)
			)
		)
	)
	(footprint ""
		(layer "B.Cu")
		(at 139.065 -30.353 -90)
		(property "Reference" "R482"
			(at 0 0 90)
			(layer "B.SilkS")
			(hide yes)
			(effects
				(font
					(size 1.27 1.27)
				)
				(justify mirror)
			)
		)
		(property "Value" "0R2J-2-GP"
			(at -1.7907 -1.1176 270)
			(unlocked yes)
			(layer "B.Fab")
			(hide yes)
			(effects
				(font
					(size 1.016 1.016)
					(thickness 0.1524)
				)
				(justify mirror)
			)
		)
		(property "Device Type" "R402H16"
			(at -1.7907 -2.6416 270)
			(unlocked yes)
			(layer "B.Fab")
			(hide yes)
			(effects
				(font
					(size 1.016 1.016)
					(thickness 0.1524)
				)
				(justify mirror)
			)
		)
		(duplicate_pad_numbers_are_jumpers no)
		(fp_rect
			(start 0.381 0.8382)
			(end -0.381 -0.8382)
			(stroke
				(width 0)
				(type default)
			)
			(fill no)
			(layer "B.CrtYd")
		)
		(fp_rect
			(start 0.381 0.8382)
			(end -0.381 -0.8382)
			(stroke
				(width 0)
				(type default)
			)
			(fill no)
			(layer "B.Fab")
		)
		(pad "1" smd custom
			(at 0 -0.4318 90)
			(size 0.127 0.127)
			(layers "B.Cu" "B.Mask" "B.Paste")
			(net "PMU_SLP_S45#")
			(options
				(clearance outline)
				(anchor circle)
			)
			(primitives
				(gr_poly
					(pts
						(arc
							(start -0.2032 0.2794)
							(mid -0.239121 0.264521)
							(end -0.254 0.2286)
						)
						(arc
							(start -0.254 -0.2286)
							(mid -0.239121 -0.264521)
							(end -0.2032 -0.2794)
						)
						(arc
							(start 0.2032 -0.2794)
							(mid 0.239121 -0.264521)
							(end 0.254 -0.2286)
						)
						(arc
							(start 0.254 0.2286)
							(mid 0.239121 0.264521)
							(end 0.2032 0.2794)
						)
					)
					(width 0)
					(fill yes)
				)
			)
		)
		(pad "2" smd custom
			(at 0 0.4318 90)
			(size 0.127 0.127)
			(layers "B.Cu" "B.Mask" "B.Paste")
			(net "PMU_SLP_R_S45#")
			(options
				(clearance outline)
				(anchor circle)
			)
			(primitives
				(gr_poly
					(pts
						(arc
							(start -0.2032 0.2794)
							(mid -0.239121 0.264521)
							(end -0.254 0.2286)
						)
						(arc
							(start -0.254 -0.2286)
							(mid -0.239121 -0.264521)
							(end -0.2032 -0.2794)
						)
						(arc
							(start 0.2032 -0.2794)
							(mid 0.239121 -0.264521)
							(end 0.254 -0.2286)
						)
						(arc
							(start 0.254 0.2286)
							(mid 0.239121 0.264521)
							(end 0.2032 0.2794)
						)
					)
					(width 0)
					(fill yes)
				)
			)
		)
	)
	(footprint ""
		(layer "B.Cu")
		(at 94.4118 -39.73576 -90)
		(property "Reference" "TP31"
			(at 0 0 90)
			(layer "B.SilkS")
			(hide yes)
			(effects
				(font
					(size 1.27 1.27)
				)
				(justify mirror)
			)
		)
		(property "Value" "TPAD24"
			(at 0 -2.9972 270)
			(unlocked yes)
			(layer "B.Fab")
			(hide yes)
			(effects
				(font
					(size 1.016 1.016)
					(thickness 0.1524)
				)
				(justify mirror)
			)
		)
		(property "Device Type" "TPAD24"
			(at 0 -4.5212 270)
			(unlocked yes)
			(layer "B.Fab")
			(hide yes)
			(effects
				(font
					(size 1.016 1.016)
					(thickness 0.1524)
				)
				(justify mirror)
			)
		)
		(duplicate_pad_numbers_are_jumpers no)
		(fp_poly
			(pts
				(arc
					(start 0 -0.3048)
					(mid 0 0.3048)
					(end 0 -0.3048)
				)
			)
			(stroke
				(width 0)
				(type default)
			)
			(fill no)
			(layer "B.CrtYd")
		)
		(fp_poly
			(pts
				(arc
					(start 0 -0.6096)
					(mid 0 0.6096)
					(end 0 -0.6096)
				)
			)
			(stroke
				(width 0)
				(type default)
			)
			(fill no)
			(layer "B.Fab")
		)
		(pad "1" smd circle
			(at 0 0 90)
			(size 0.6096 0.6096)
			(layers "B.Cu" "B.Mask" "B.Paste")
			(net "TP_CPU_RSVD8")
		)
	)
	(footprint ""
		(layer "B.Cu")
		(at 163.322 -72.39 90)
		(property "Reference" "C109"
			(at 0 0 90)
			(layer "B.SilkS")
			(hide yes)
			(effects
				(font
					(size 1.27 1.27)
				)
				(justify mirror)
			)
		)
		(property "Value" "SCD1U16V2KX-3GP"
			(at -1.1811 -2.7051 90)
			(unlocked yes)
			(layer "B.Fab")
			(hide yes)
			(effects
				(font
					(size 1.016 1.016)
					(thickness 0.1524)
				)
				(justify mirror)
			)
		)
		(property "Device Type" "C402H22"
			(at -1.1811 -4.2291 90)
			(unlocked yes)
			(layer "B.Fab")
			(hide yes)
			(effects
				(font
					(size 1.016 1.016)
					(thickness 0.1524)
				)
				(justify mirror)
			)
		)
		(duplicate_pad_numbers_are_jumpers no)
		(fp_rect
			(start 0.381 0.7366)
			(end -0.381 -0.7366)
			(stroke
				(width 0)
				(type default)
			)
			(fill no)
			(layer "B.CrtYd")
		)
		(fp_rect
			(start 0.381 0.7366)
			(end -0.381 -0.7366)
			(stroke
				(width 0)
				(type default)
			)
			(fill no)
			(layer "B.Fab")
		)
		(pad "1" smd custom
			(at 0 -0.4572 270)
			(size 0.1143 0.1143)
			(layers "B.Cu" "B.Mask" "B.Paste")
			(net "DDR3_M_A_VREF_CA")
			(options
				(clearance outline)
				(anchor circle)
			)
			(primitives
				(gr_poly
					(pts
						(arc
							(start -0.254 0.1778)
							(mid -0.239121 0.213721)
							(end -0.2032 0.2286)
						)
						(arc
							(start 0.2032 0.2286)
							(mid 0.239121 0.213721)
							(end 0.254 0.1778)
						)
						(arc
							(start 0.254 -0.1778)
							(mid 0.239121 -0.213721)
							(end 0.2032 -0.2286)
						)
						(arc
							(start -0.2032 -0.2286)
							(mid -0.239121 -0.213721)
							(end -0.254 -0.1778)
						)
					)
					(width 0)
					(fill yes)
				)
			)
		)
		(pad "2" smd custom
			(at 0 0.4572 270)
			(size 0.1143 0.1143)
			(layers "B.Cu" "B.Mask" "B.Paste")
			(net "GND")
			(options
				(clearance outline)
				(anchor circle)
			)
			(primitives
				(gr_poly
					(pts
						(arc
							(start -0.254 0.1778)
							(mid -0.239121 0.213721)
							(end -0.2032 0.2286)
						)
						(arc
							(start 0.2032 0.2286)
							(mid 0.239121 0.213721)
							(end 0.254 0.1778)
						)
						(arc
							(start 0.254 -0.1778)
							(mid 0.239121 -0.213721)
							(end 0.2032 -0.2286)
						)
						(arc
							(start -0.2032 -0.2286)
							(mid -0.239121 -0.213721)
							(end -0.254 -0.1778)
						)
					)
					(width 0)
					(fill yes)
				)
			)
		)
	)
	(footprint ""
		(layer "B.Cu")
		(at 88.138 -15.113)
		(property "Reference" "PC201"
			(at 0 0 0)
			(layer "B.SilkS")
			(hide yes)
			(effects
				(font
					(size 1.27 1.27)
				)
				(justify mirror)
			)
		)
		(property "Value" "SC10U6D3V5KX-4GP"
			(at 0.0762 -6.1214 0)
			(unlocked yes)
			(layer "B.Fab")
			(hide yes)
			(effects
				(font
					(size 1.016 1.016)
					(thickness 0.1524)
				)
				(justify mirror)
			)
		)
		(property "Device Type" "C805H58"
			(at 0.0762 -8.1534 0)
			(unlocked yes)
			(layer "B.Fab")
			(hide yes)
			(effects
				(font
					(size 1.016 1.016)
					(thickness 0.1524)
				)
				(justify mirror)
			)
		)
		(duplicate_pad_numbers_are_jumpers no)
		(fp_line
			(start -0.6096 0)
			(end 0.6096 0)
			(stroke
				(width 0.3048)
				(type default)
			)
			(layer "B.SilkS")
		)
		(fp_poly
			(pts
				(xy 0.9017 1.4351) (xy -0.9017 1.4351) (xy -0.9017 -1.4351) (xy 0.9017 -1.4351)
			)
			(stroke
				(width 0)
				(type default)
			)
			(fill no)
			(layer "B.CrtYd")
		)
		(fp_poly
			(pts
				(xy -0.9017 1.4351) (xy -0.9017 -1.4351) (xy 0.9017 -1.4351) (xy 0.9017 1.4351)
			)
			(stroke
				(width 0)
				(type default)
			)
			(fill no)
			(layer "B.Fab")
		)
		(pad "1" smd rect
			(at 0 -0.8382 180)
			(size 1.5494 0.9398)
			(layers "B.Cu" "B.Mask" "B.Paste")
			(net "TPS74801_1V35_OUT")
		)
		(pad "2" smd rect
			(at 0 0.8382 180)
			(size 1.5494 0.9398)
			(layers "B.Cu" "B.Mask" "B.Paste")
			(net "GND")
		)
	)
	(footprint ""
		(layer "B.Cu")
		(at 110.744 -50.816002 90)
		(property "Reference" "C132"
			(at 0 0 90)
			(layer "B.SilkS")
			(hide yes)
			(effects
				(font
					(size 1.27 1.27)
				)
				(justify mirror)
			)
		)
		(property "Value" "SC1U10V2KX-1GP"
			(at -1.1811 -2.7051 90)
			(unlocked yes)
			(layer "B.Fab")
			(hide yes)
			(effects
				(font
					(size 1.016 1.016)
					(thickness 0.1524)
				)
				(justify mirror)
			)
		)
		(property "Device Type" "C402H22"
			(at -1.1811 -4.2291 90)
			(unlocked yes)
			(layer "B.Fab")
			(hide yes)
			(effects
				(font
					(size 1.016 1.016)
					(thickness 0.1524)
				)
				(justify mirror)
			)
		)
		(duplicate_pad_numbers_are_jumpers no)
		(fp_rect
			(start 0.381 0.7366)
			(end -0.381 -0.7366)
			(stroke
				(width 0)
				(type default)
			)
			(fill no)
			(layer "B.CrtYd")
		)
		(fp_rect
			(start 0.381 0.7366)
			(end -0.381 -0.7366)
			(stroke
				(width 0)
				(type default)
			)
			(fill no)
			(layer "B.Fab")
		)
		(pad "1" smd custom
			(at 0 -0.4572 270)
			(size 0.1143 0.1143)
			(layers "B.Cu" "B.Mask" "B.Paste")
			(net "PV_VDDR")
			(options
				(clearance outline)
				(anchor circle)
			)
			(primitives
				(gr_poly
					(pts
						(arc
							(start -0.254 0.1778)
							(mid -0.239121 0.213721)
							(end -0.2032 0.2286)
						)
						(arc
							(start 0.2032 0.2286)
							(mid 0.239121 0.213721)
							(end 0.254 0.1778)
						)
						(arc
							(start 0.254 -0.1778)
							(mid 0.239121 -0.213721)
							(end 0.2032 -0.2286)
						)
						(arc
							(start -0.2032 -0.2286)
							(mid -0.239121 -0.213721)
							(end -0.254 -0.1778)
						)
					)
					(width 0)
					(fill yes)
				)
			)
		)
		(pad "2" smd custom
			(at 0 0.4572 270)
			(size 0.1143 0.1143)
			(layers "B.Cu" "B.Mask" "B.Paste")
			(net "GND")
			(options
				(clearance outline)
				(anchor circle)
			)
			(primitives
				(gr_poly
					(pts
						(arc
							(start -0.254 0.1778)
							(mid -0.239121 0.213721)
							(end -0.2032 0.2286)
						)
						(arc
							(start 0.2032 0.2286)
							(mid 0.239121 0.213721)
							(end 0.254 0.1778)
						)
						(arc
							(start 0.254 -0.1778)
							(mid 0.239121 -0.213721)
							(end 0.2032 -0.2286)
						)
						(arc
							(start -0.2032 -0.2286)
							(mid -0.239121 -0.213721)
							(end -0.254 -0.1778)
						)
					)
					(width 0)
					(fill yes)
				)
			)
		)
	)
	(footprint ""
		(layer "B.Cu")
		(at 74.168 -44.196 90)
		(property "Reference" "R314"
			(at 0 0 90)
			(layer "B.SilkS")
			(hide yes)
			(effects
				(font
					(size 1.27 1.27)
				)
				(justify mirror)
			)
		)
		(property "Value" "10KR2F-2-GP"
			(at -0.064008 -3.993896 90)
			(unlocked yes)
			(layer "B.Fab")
			(hide yes)
			(effects
				(font
					(size 1.016 1.016)
					(thickness 0.1524)
				)
				(justify mirror)
			)
		)
		(property "Device Type" "R402H16"
			(at -0.064008 -5.517896 90)
			(unlocked yes)
			(layer "B.Fab")
			(hide yes)
			(effects
				(font
					(size 1.016 1.016)
					(thickness 0.1524)
				)
				(justify mirror)
			)
		)
		(duplicate_pad_numbers_are_jumpers no)
		(fp_rect
			(start 0.381 0.8382)
			(end -0.381 -0.8382)
			(stroke
				(width 0)
				(type default)
			)
			(fill no)
			(layer "B.CrtYd")
		)
		(fp_rect
			(start 0.381 0.8382)
			(end -0.381 -0.8382)
			(stroke
				(width 0)
				(type default)
			)
			(fill no)
			(layer "B.Fab")
		)
		(pad "1" smd custom
			(at 0 -0.4318 270)
			(size 0.127 0.127)
			(layers "B.Cu" "B.Mask" "B.Paste")
			(net "P3V3")
			(options
				(clearance outline)
				(anchor circle)
			)
			(primitives
				(gr_poly
					(pts
						(arc
							(start -0.2032 0.2794)
							(mid -0.239121 0.264521)
							(end -0.254 0.2286)
						)
						(arc
							(start -0.254 -0.2286)
							(mid -0.239121 -0.264521)
							(end -0.2032 -0.2794)
						)
						(arc
							(start 0.2032 -0.2794)
							(mid 0.239121 -0.264521)
							(end 0.254 -0.2286)
						)
						(arc
							(start 0.254 0.2286)
							(mid 0.239121 0.264521)
							(end 0.2032 0.2794)
						)
					)
					(width 0)
					(fill yes)
				)
			)
		)
		(pad "2" smd custom
			(at 0 0.4318 270)
			(size 0.127 0.127)
			(layers "B.Cu" "B.Mask" "B.Paste")
			(net "LPC_CPU_FRAME#")
			(options
				(clearance outline)
				(anchor circle)
			)
			(primitives
				(gr_poly
					(pts
						(arc
							(start -0.2032 0.2794)
							(mid -0.239121 0.264521)
							(end -0.254 0.2286)
						)
						(arc
							(start -0.254 -0.2286)
							(mid -0.239121 -0.264521)
							(end -0.2032 -0.2794)
						)
						(arc
							(start 0.2032 -0.2794)
							(mid 0.239121 -0.264521)
							(end 0.254 -0.2286)
						)
						(arc
							(start 0.254 0.2286)
							(mid 0.239121 0.264521)
							(end 0.2032 0.2794)
						)
					)
					(width 0)
					(fill yes)
				)
			)
		)
	)
	(footprint ""
		(layer "B.Cu")
		(at 76.708 -61.8744)
		(property "Reference" "C86"
			(at 0 0 0)
			(layer "B.SilkS")
			(hide yes)
			(effects
				(font
					(size 1.27 1.27)
				)
				(justify mirror)
			)
		)
		(property "Value" "SCD1U16V2KX-3GP"
			(at -1.1811 -2.7051 0)
			(unlocked yes)
			(layer "B.Fab")
			(hide yes)
			(effects
				(font
					(size 1.016 1.016)
					(thickness 0.1524)
				)
				(justify mirror)
			)
		)
		(property "Device Type" "C402H22"
			(at -1.1811 -4.2291 0)
			(unlocked yes)
			(layer "B.Fab")
			(hide yes)
			(effects
				(font
					(size 1.016 1.016)
					(thickness 0.1524)
				)
				(justify mirror)
			)
		)
		(duplicate_pad_numbers_are_jumpers no)
		(fp_rect
			(start 0.381 0.7366)
			(end -0.381 -0.7366)
			(stroke
				(width 0)
				(type default)
			)
			(fill no)
			(layer "B.CrtYd")
		)
		(fp_rect
			(start 0.381 0.7366)
			(end -0.381 -0.7366)
			(stroke
				(width 0)
				(type default)
			)
			(fill no)
			(layer "B.Fab")
		)
		(pad "1" smd custom
			(at 0 -0.4572 180)
			(size 0.1143 0.1143)
			(layers "B.Cu" "B.Mask" "B.Paste")
			(net "PVNN_SENSE")
			(options
				(clearance outline)
				(anchor circle)
			)
			(primitives
				(gr_poly
					(pts
						(arc
							(start -0.254 0.1778)
							(mid -0.239121 0.213721)
							(end -0.2032 0.2286)
						)
						(arc
							(start 0.2032 0.2286)
							(mid 0.239121 0.213721)
							(end 0.254 0.1778)
						)
						(arc
							(start 0.254 -0.1778)
							(mid 0.239121 -0.213721)
							(end 0.2032 -0.2286)
						)
						(arc
							(start -0.2032 -0.2286)
							(mid -0.239121 -0.213721)
							(end -0.254 -0.1778)
						)
					)
					(width 0)
					(fill yes)
				)
			)
		)
		(pad "2" smd custom
			(at 0 0.4572 180)
			(size 0.1143 0.1143)
			(layers "B.Cu" "B.Mask" "B.Paste")
			(net "GND")
			(options
				(clearance outline)
				(anchor circle)
			)
			(primitives
				(gr_poly
					(pts
						(arc
							(start -0.254 0.1778)
							(mid -0.239121 0.213721)
							(end -0.2032 0.2286)
						)
						(arc
							(start 0.2032 0.2286)
							(mid 0.239121 0.213721)
							(end 0.254 0.1778)
						)
						(arc
							(start 0.254 -0.1778)
							(mid 0.239121 -0.213721)
							(end 0.2032 -0.2286)
						)
						(arc
							(start -0.2032 -0.2286)
							(mid -0.239121 -0.213721)
							(end -0.254 -0.1778)
						)
					)
					(width 0)
					(fill yes)
				)
			)
		)
	)
	(footprint ""
		(layer "B.Cu")
		(at 96.06788 -43.69816)
		(property "Reference" "C124"
			(at 0 0 0)
			(layer "B.SilkS")
			(hide yes)
			(effects
				(font
					(size 1.27 1.27)
				)
				(justify mirror)
			)
		)
		(property "Value" "SC1U10V2KX-1GP"
			(at -1.1811 -2.7051 0)
			(unlocked yes)
			(layer "B.Fab")
			(hide yes)
			(effects
				(font
					(size 1.016 1.016)
					(thickness 0.1524)
				)
				(justify mirror)
			)
		)
		(property "Device Type" "C402H22"
			(at -1.1811 -4.2291 0)
			(unlocked yes)
			(layer "B.Fab")
			(hide yes)
			(effects
				(font
					(size 1.016 1.016)
					(thickness 0.1524)
				)
				(justify mirror)
			)
		)
		(duplicate_pad_numbers_are_jumpers no)
		(fp_rect
			(start 0.381 0.7366)
			(end -0.381 -0.7366)
			(stroke
				(width 0)
				(type default)
			)
			(fill no)
			(layer "B.CrtYd")
		)
		(fp_rect
			(start 0.381 0.7366)
			(end -0.381 -0.7366)
			(stroke
				(width 0)
				(type default)
			)
			(fill no)
			(layer "B.Fab")
		)
		(pad "1" smd custom
			(at 0 -0.4572 180)
			(size 0.1143 0.1143)
			(layers "B.Cu" "B.Mask" "B.Paste")
			(net "VCCA_PLLDDR0_AVN")
			(options
				(clearance outline)
				(anchor circle)
			)
			(primitives
				(gr_poly
					(pts
						(arc
							(start -0.254 0.1778)
							(mid -0.239121 0.213721)
							(end -0.2032 0.2286)
						)
						(arc
							(start 0.2032 0.2286)
							(mid 0.239121 0.213721)
							(end 0.254 0.1778)
						)
						(arc
							(start 0.254 -0.1778)
							(mid 0.239121 -0.213721)
							(end 0.2032 -0.2286)
						)
						(arc
							(start -0.2032 -0.2286)
							(mid -0.239121 -0.213721)
							(end -0.254 -0.1778)
						)
					)
					(width 0)
					(fill yes)
				)
			)
		)
		(pad "2" smd custom
			(at 0 0.4572 180)
			(size 0.1143 0.1143)
			(layers "B.Cu" "B.Mask" "B.Paste")
			(net "GND")
			(options
				(clearance outline)
				(anchor circle)
			)
			(primitives
				(gr_poly
					(pts
						(arc
							(start -0.254 0.1778)
							(mid -0.239121 0.213721)
							(end -0.2032 0.2286)
						)
						(arc
							(start 0.2032 0.2286)
							(mid 0.239121 0.213721)
							(end 0.254 0.1778)
						)
						(arc
							(start 0.254 -0.1778)
							(mid 0.239121 -0.213721)
							(end 0.2032 -0.2286)
						)
						(arc
							(start -0.2032 -0.2286)
							(mid -0.239121 -0.213721)
							(end -0.254 -0.1778)
						)
					)
					(width 0)
					(fill yes)
				)
			)
		)
	)
	(footprint ""
		(layer "B.Cu")
		(at 97.6376 -39.7256 180)
		(property "Reference" "TP30"
			(at 0 0 0)
			(layer "B.SilkS")
			(hide yes)
			(effects
				(font
					(size 1.27 1.27)
				)
				(justify mirror)
			)
		)
		(property "Value" "TPAD24"
			(at 0 -2.9972 180)
			(unlocked yes)
			(layer "B.Fab")
			(hide yes)
			(effects
				(font
					(size 1.016 1.016)
					(thickness 0.1524)
				)
				(justify mirror)
			)
		)
		(property "Device Type" "TPAD24"
			(at 0 -4.5212 180)
			(unlocked yes)
			(layer "B.Fab")
			(hide yes)
			(effects
				(font
					(size 1.016 1.016)
					(thickness 0.1524)
				)
				(justify mirror)
			)
		)
		(duplicate_pad_numbers_are_jumpers no)
		(fp_poly
			(pts
				(arc
					(start -0.3048 0)
					(mid 0.3048 0)
					(end -0.3048 0)
				)
			)
			(stroke
				(width 0)
				(type default)
			)
			(fill no)
			(layer "B.CrtYd")
		)
		(fp_poly
			(pts
				(arc
					(start -0.6096 0)
					(mid 0.6096 0)
					(end -0.6096 0)
				)
			)
			(stroke
				(width 0)
				(type default)
			)
			(fill no)
			(layer "B.Fab")
		)
		(pad "1" smd circle
			(at 0 0)
			(size 0.6096 0.6096)
			(layers "B.Cu" "B.Mask" "B.Paste")
			(net "VCCRAMCPUSI0GT_MOD3_1P03")
		)
	)
	(footprint ""
		(layer "B.Cu")
		(at 74.93 -50.673 -90)
		(property "Reference" "R38"
			(at 0 0 90)
			(layer "B.SilkS")
			(hide yes)
			(effects
				(font
					(size 1.27 1.27)
				)
				(justify mirror)
			)
		)
		(property "Value" "51R2F-2-GP"
			(at -0.064008 -3.993896 270)
			(unlocked yes)
			(layer "B.Fab")
			(hide yes)
			(effects
				(font
					(size 1.016 1.016)
					(thickness 0.1524)
				)
				(justify mirror)
			)
		)
		(property "Device Type" "R402H16"
			(at -0.064008 -5.517896 270)
			(unlocked yes)
			(layer "B.Fab")
			(hide yes)
			(effects
				(font
					(size 1.016 1.016)
					(thickness 0.1524)
				)
				(justify mirror)
			)
		)
		(duplicate_pad_numbers_are_jumpers no)
		(fp_rect
			(start 0.381 0.8382)
			(end -0.381 -0.8382)
			(stroke
				(width 0)
				(type default)
			)
			(fill no)
			(layer "B.CrtYd")
		)
		(fp_rect
			(start 0.381 0.8382)
			(end -0.381 -0.8382)
			(stroke
				(width 0)
				(type default)
			)
			(fill no)
			(layer "B.Fab")
		)
		(pad "1" smd custom
			(at 0 -0.4318 90)
			(size 0.127 0.127)
			(layers "B.Cu" "B.Mask" "B.Paste")
			(net "CTBTRIGOUT")
			(options
				(clearance outline)
				(anchor circle)
			)
			(primitives
				(gr_poly
					(pts
						(arc
							(start -0.2032 0.2794)
							(mid -0.239121 0.264521)
							(end -0.254 0.2286)
						)
						(arc
							(start -0.254 -0.2286)
							(mid -0.239121 -0.264521)
							(end -0.2032 -0.2794)
						)
						(arc
							(start 0.2032 -0.2794)
							(mid 0.239121 -0.264521)
							(end 0.254 -0.2286)
						)
						(arc
							(start 0.254 0.2286)
							(mid 0.239121 0.264521)
							(end 0.2032 0.2794)
						)
					)
					(width 0)
					(fill yes)
				)
			)
		)
		(pad "2" smd custom
			(at 0 0.4318 90)
			(size 0.127 0.127)
			(layers "B.Cu" "B.Mask" "B.Paste")
			(net "P1V0")
			(options
				(clearance outline)
				(anchor circle)
			)
			(primitives
				(gr_poly
					(pts
						(arc
							(start -0.2032 0.2794)
							(mid -0.239121 0.264521)
							(end -0.254 0.2286)
						)
						(arc
							(start -0.254 -0.2286)
							(mid -0.239121 -0.264521)
							(end -0.2032 -0.2794)
						)
						(arc
							(start 0.2032 -0.2794)
							(mid 0.239121 -0.264521)
							(end 0.254 -0.2286)
						)
						(arc
							(start 0.254 0.2286)
							(mid 0.239121 0.264521)
							(end 0.2032 0.2794)
						)
					)
					(width 0)
					(fill yes)
				)
			)
		)
	)
	(footprint ""
		(layer "B.Cu")
		(at 201.2696 -32.8422 90)
		(property "Reference" "LED6"
			(at 0 0 90)
			(layer "B.SilkS")
			(hide yes)
			(effects
				(font
					(size 1.27 1.27)
				)
				(justify mirror)
			)
		)
		(property "Value" "LED-YG-51-GP"
			(at 0.0381 -2.6162 90)
			(unlocked yes)
			(layer "B.Fab")
			(hide yes)
			(effects
				(font
					(size 1.016 1.016)
					(thickness 0.1524)
				)
				(justify mirror)
			)
		)
		(property "Device Type" "LED1608AKH40"
			(at 0.0381 -4.1402 90)
			(unlocked yes)
			(layer "B.Fab")
			(hide yes)
			(effects
				(font
					(size 1.016 1.016)
					(thickness 0.1524)
				)
				(justify mirror)
			)
		)
		(duplicate_pad_numbers_are_jumpers no)
		(fp_line
			(start 0.5334 1.3081)
			(end -0.5334 1.3081)
			(stroke
				(width 0.254)
				(type default)
			)
			(layer "B.SilkS")
		)
		(fp_rect
			(start 0.6604 1.1811)
			(end -0.6604 -1.1811)
			(stroke
				(width 0)
				(type default)
			)
			(fill no)
			(layer "B.CrtYd")
		)
		(fp_rect
			(start 0.6604 1.1811)
			(end -0.6604 -1.1811)
			(stroke
				(width 0)
				(type default)
			)
			(fill no)
			(layer "B.Fab")
		)
		(pad "A" smd rect
			(at 0 -0.652526 270)
			(size 1.0668 0.8128)
			(layers "B.Cu" "B.Mask" "B.Paste")
			(net "PORT80_R_BIT1")
		)
		(pad "K" smd rect
			(at 0 0.652526 270)
			(size 1.0668 0.8128)
			(layers "B.Cu" "B.Mask" "B.Paste")
			(net "PORT80_BIT1")
		)
	)
	(footprint ""
		(layer "B.Cu")
		(at 74.168 -41.656 90)
		(property "Reference" "R317"
			(at 0 0 90)
			(layer "B.SilkS")
			(hide yes)
			(effects
				(font
					(size 1.27 1.27)
				)
				(justify mirror)
			)
		)
		(property "Value" "1KR2F-3-GP"
			(at -0.064008 -3.993896 90)
			(unlocked yes)
			(layer "B.Fab")
			(hide yes)
			(effects
				(font
					(size 1.016 1.016)
					(thickness 0.1524)
				)
				(justify mirror)
			)
		)
		(property "Device Type" "R402H16"
			(at -0.064008 -5.517896 90)
			(unlocked yes)
			(layer "B.Fab")
			(hide yes)
			(effects
				(font
					(size 1.016 1.016)
					(thickness 0.1524)
				)
				(justify mirror)
			)
		)
		(duplicate_pad_numbers_are_jumpers no)
		(fp_rect
			(start 0.381 0.8382)
			(end -0.381 -0.8382)
			(stroke
				(width 0)
				(type default)
			)
			(fill no)
			(layer "B.CrtYd")
		)
		(fp_rect
			(start 0.381 0.8382)
			(end -0.381 -0.8382)
			(stroke
				(width 0)
				(type default)
			)
			(fill no)
			(layer "B.Fab")
		)
		(pad "1" smd custom
			(at 0 -0.4318 270)
			(size 0.127 0.127)
			(layers "B.Cu" "B.Mask" "B.Paste")
			(net "BD_ID_1")
			(options
				(clearance outline)
				(anchor circle)
			)
			(primitives
				(gr_poly
					(pts
						(arc
							(start -0.2032 0.2794)
							(mid -0.239121 0.264521)
							(end -0.254 0.2286)
						)
						(arc
							(start -0.254 -0.2286)
							(mid -0.239121 -0.264521)
							(end -0.2032 -0.2794)
						)
						(arc
							(start 0.2032 -0.2794)
							(mid 0.239121 -0.264521)
							(end 0.254 -0.2286)
						)
						(arc
							(start 0.254 0.2286)
							(mid 0.239121 0.264521)
							(end 0.2032 0.2794)
						)
					)
					(width 0)
					(fill yes)
				)
			)
		)
		(pad "2" smd custom
			(at 0 0.4318 270)
			(size 0.127 0.127)
			(layers "B.Cu" "B.Mask" "B.Paste")
			(net "GND")
			(options
				(clearance outline)
				(anchor circle)
			)
			(primitives
				(gr_poly
					(pts
						(arc
							(start -0.2032 0.2794)
							(mid -0.239121 0.264521)
							(end -0.254 0.2286)
						)
						(arc
							(start -0.254 -0.2286)
							(mid -0.239121 -0.264521)
							(end -0.2032 -0.2794)
						)
						(arc
							(start 0.2032 -0.2794)
							(mid 0.239121 -0.264521)
							(end 0.254 -0.2286)
						)
						(arc
							(start 0.254 0.2286)
							(mid 0.239121 0.264521)
							(end 0.2032 0.2794)
						)
					)
					(width 0)
					(fill yes)
				)
			)
		)
	)
	(footprint ""
		(layer "B.Cu")
		(at 68.58 -25.146 180)
		(property "Reference" "PG5"
			(at 0 0 0)
			(layer "B.SilkS")
			(hide yes)
			(effects
				(font
					(size 1.27 1.27)
				)
				(justify mirror)
			)
		)
		(property "Value" "COPPER-CLOSE-GP-U"
			(at -0.0762 -2.8702 180)
			(unlocked yes)
			(layer "B.Fab")
			(hide yes)
			(effects
				(font
					(size 1.016 1.016)
					(thickness 0.1524)
				)
				(justify mirror)
			)
		)
		(property "Device Type" "CON2C-U"
			(at -0.0762 -4.3942 180)
			(unlocked yes)
			(layer "B.Fab")
			(hide yes)
			(effects
				(font
					(size 1.016 1.016)
					(thickness 0.1524)
				)
				(justify mirror)
			)
		)
		(duplicate_pad_numbers_are_jumpers no)
		(fp_rect
			(start 0.9398 0.9652)
			(end -0.9398 -0.9652)
			(stroke
				(width 0)
				(type default)
			)
			(fill no)
			(layer "B.CrtYd")
		)
		(fp_rect
			(start 0.9398 0.9652)
			(end -0.9398 -0.9652)
			(stroke
				(width 0)
				(type default)
			)
			(fill no)
			(layer "B.Fab")
		)
		(pad "1" smd custom
			(at 0 -0.5334)
			(size 0.17145 0.17145)
			(layers "B.Cu" "B.Mask" "B.Paste")
			(net "AGND_P1V8_STBY")
			(options
				(clearance outline)
				(anchor circle)
			)
			(primitives
				(gr_poly
					(pts
						(xy -0.127 -0.3429) (xy -0.127 -0.1651) (xy -0.635 0.3429) (xy 0.635 0.3429) (xy 0.127 -0.1651)
						(xy 0.127 -0.3429)
					)
					(width 0)
					(fill yes)
				)
			)
		)
		(pad "2" smd custom
			(at 0 0.5334)
			(size 0.17145 0.17145)
			(layers "B.Cu" "B.Mask" "B.Paste")
			(net "GND")
			(options
				(clearance outline)
				(anchor circle)
			)
			(primitives
				(gr_poly
					(pts
						(xy -0.635 -0.3429) (xy -0.127 0.1651) (xy -0.127 0.3429) (xy 0.127 0.3429) (xy 0.127 0.1651)
						(xy 0.635 -0.3429)
					)
					(width 0)
					(fill yes)
				)
			)
		)
	)
	(footprint ""
		(layer "B.Cu")
		(at 168.021 -12.600178 180)
		(property "Reference" "C297"
			(at 0 0 0)
			(layer "B.SilkS")
			(hide yes)
			(effects
				(font
					(size 1.27 1.27)
				)
				(justify mirror)
			)
		)
		(property "Value" "SC1U10V2KX-1GP"
			(at -1.8923 -1.2065 180)
			(unlocked yes)
			(layer "B.Fab")
			(hide yes)
			(effects
				(font
					(size 1.016 1.016)
					(thickness 0.1524)
				)
				(justify mirror)
			)
		)
		(property "Device Type" "C402H22"
			(at -1.8923 -2.7305 180)
			(unlocked yes)
			(layer "B.Fab")
			(hide yes)
			(effects
				(font
					(size 1.016 1.016)
					(thickness 0.1524)
				)
				(justify mirror)
			)
		)
		(duplicate_pad_numbers_are_jumpers no)
		(fp_rect
			(start 0.381 0.7366)
			(end -0.381 -0.7366)
			(stroke
				(width 0)
				(type default)
			)
			(fill no)
			(layer "B.CrtYd")
		)
		(fp_rect
			(start 0.381 0.7366)
			(end -0.381 -0.7366)
			(stroke
				(width 0)
				(type default)
			)
			(fill no)
			(layer "B.Fab")
		)
		(pad "1" smd custom
			(at 0 -0.4572)
			(size 0.1143 0.1143)
			(layers "B.Cu" "B.Mask" "B.Paste")
			(net "PV_VDDR")
			(options
				(clearance outline)
				(anchor circle)
			)
			(primitives
				(gr_poly
					(pts
						(arc
							(start -0.254 0.1778)
							(mid -0.239121 0.213721)
							(end -0.2032 0.2286)
						)
						(arc
							(start 0.2032 0.2286)
							(mid 0.239121 0.213721)
							(end 0.254 0.1778)
						)
						(arc
							(start 0.254 -0.1778)
							(mid 0.239121 -0.213721)
							(end 0.2032 -0.2286)
						)
						(arc
							(start -0.2032 -0.2286)
							(mid -0.239121 -0.213721)
							(end -0.254 -0.1778)
						)
					)
					(width 0)
					(fill yes)
				)
			)
		)
		(pad "2" smd custom
			(at 0 0.4572)
			(size 0.1143 0.1143)
			(layers "B.Cu" "B.Mask" "B.Paste")
			(net "GND")
			(options
				(clearance outline)
				(anchor circle)
			)
			(primitives
				(gr_poly
					(pts
						(arc
							(start -0.254 0.1778)
							(mid -0.239121 0.213721)
							(end -0.2032 0.2286)
						)
						(arc
							(start 0.2032 0.2286)
							(mid 0.239121 0.213721)
							(end 0.254 0.1778)
						)
						(arc
							(start 0.254 -0.1778)
							(mid 0.239121 -0.213721)
							(end 0.2032 -0.2286)
						)
						(arc
							(start -0.2032 -0.2286)
							(mid -0.239121 -0.213721)
							(end -0.254 -0.1778)
						)
					)
					(width 0)
					(fill yes)
				)
			)
		)
	)
	(footprint ""
		(layer "B.Cu")
		(at 82.266028 -18.197322 180)
		(property "Reference" "PU16"
			(at 0 0 0)
			(layer "B.SilkS")
			(hide yes)
			(effects
				(font
					(size 1.27 1.27)
				)
				(justify mirror)
			)
		)
		(property "Value" "TPS74801RGW-GP"
			(at 4.7244 -6.223 180)
			(unlocked yes)
			(layer "B.Fab")
			(hide yes)
			(effects
				(font
					(size 1.016 1.016)
					(thickness 0.1524)
				)
				(justify mirror)
			)
		)
		(property "Device Type" "QFN20-1G3D15H40"
			(at 4.7244 -7.747 180)
			(unlocked yes)
			(layer "B.Fab")
			(hide yes)
			(effects
				(font
					(size 1.016 1.016)
					(thickness 0.1524)
				)
				(justify mirror)
			)
		)
		(duplicate_pad_numbers_are_jumpers no)
		(fp_poly
			(pts
				(xy -1.3208 -2.884932) (xy -1.941068 -3.5052) (xy -0.700786 -3.5052)
			)
			(stroke
				(width 0)
				(type default)
			)
			(fill yes)
			(layer "B.SilkS")
		)
		(fp_rect
			(start 2.8829 2.8829)
			(end -2.8829 -2.8829)
			(stroke
				(width 0)
				(type default)
			)
			(fill no)
			(layer "B.CrtYd")
		)
		(fp_rect
			(start 2.8829 2.8829)
			(end -2.8829 -2.8829)
			(stroke
				(width 0)
				(type default)
			)
			(fill no)
			(layer "B.Fab")
		)
		(pad "1" smd rect
			(at -1.299972 -2.347722)
			(size 0.3556 0.8128)
			(layers "B.Cu" "B.Mask" "B.Paste")
			(net "TPS74801_1V35_OUT")
		)
		(pad "2" smd rect
			(at -0.649986 -2.347722)
			(size 0.3556 0.8128)
			(layers "B.Cu" "B.Mask" "B.Paste")
			(net "GND")
		)
		(pad "3" smd rect
			(at 0 -2.347722)
			(size 0.3556 0.8128)
			(layers "B.Cu" "B.Mask" "B.Paste")
			(net "GND")
		)
		(pad "4" smd rect
			(at 0.649986 -2.347722)
			(size 0.3556 0.8128)
			(layers "B.Cu" "B.Mask" "B.Paste")
			(net "GND")
		)
		(pad "5" smd rect
			(at 1.299972 -2.347722)
			(size 0.3556 0.8128)
			(layers "B.Cu" "B.Mask" "B.Paste")
			(net "TPS74801_P1V35_IN")
		)
		(pad "6" smd rect
			(at 2.347722 -1.299972)
			(size 0.8128 0.3556)
			(layers "B.Cu" "B.Mask" "B.Paste")
			(net "TPS74801_P1V35_IN")
		)
		(pad "7" smd rect
			(at 2.347722 -0.649986)
			(size 0.8128 0.3556)
			(layers "B.Cu" "B.Mask" "B.Paste")
			(net "TPS74801_P1V35_IN")
		)
		(pad "8" smd rect
			(at 2.347722 0)
			(size 0.8128 0.3556)
			(layers "B.Cu" "B.Mask" "B.Paste")
			(net "TPS74801_P1V35_IN")
		)
		(pad "9" smd rect
			(at 2.347722 0.649986)
			(size 0.8128 0.3556)
			(layers "B.Cu" "B.Mask" "B.Paste")
			(net "PWRGD_P1V35_PG")
		)
		(pad "10" smd rect
			(at 2.347722 1.299972)
			(size 0.8128 0.3556)
			(layers "B.Cu" "B.Mask" "B.Paste")
			(net "TPS74801_1V35_BIAS")
		)
		(pad "11" smd rect
			(at 1.299972 2.347722)
			(size 0.3556 0.8128)
			(layers "B.Cu" "B.Mask" "B.Paste")
			(net "TPS74801_1V35_EN")
		)
		(pad "12" smd rect
			(at 0.649986 2.347722)
			(size 0.3556 0.8128)
			(layers "B.Cu" "B.Mask" "B.Paste")
			(net "GND")
		)
		(pad "13" smd rect
			(at 0 2.347722)
			(size 0.3556 0.8128)
			(layers "B.Cu" "B.Mask" "B.Paste")
			(net "GND")
		)
		(pad "14" smd rect
			(at -0.649986 2.347722)
			(size 0.3556 0.8128)
			(layers "B.Cu" "B.Mask" "B.Paste")
			(net "GND")
		)
		(pad "15" smd rect
			(at -1.299972 2.347722)
			(size 0.3556 0.8128)
			(layers "B.Cu" "B.Mask" "B.Paste")
			(net "TPS74801_1V35_SS")
		)
		(pad "16" smd rect
			(at -2.347722 1.299972)
			(size 0.8128 0.3556)
			(layers "B.Cu" "B.Mask" "B.Paste")
			(net "TPS74801_1V35_FB")
		)
		(pad "17" smd rect
			(at -2.347722 0.649986)
			(size 0.8128 0.3556)
			(layers "B.Cu" "B.Mask" "B.Paste")
			(net "GND")
		)
		(pad "18" smd rect
			(at -2.347722 0)
			(size 0.8128 0.3556)
			(layers "B.Cu" "B.Mask" "B.Paste")
			(net "TPS74801_1V35_OUT")
		)
		(pad "19" smd rect
			(at -2.347722 -0.649986)
			(size 0.8128 0.3556)
			(layers "B.Cu" "B.Mask" "B.Paste")
			(net "TPS74801_1V35_OUT")
		)
		(pad "20" smd rect
			(at -2.347722 -1.299972)
			(size 0.8128 0.3556)
			(layers "B.Cu" "B.Mask" "B.Paste")
			(net "TPS74801_1V35_OUT")
		)
		(pad "21" smd rect
			(at 0 0)
			(size 3.2512 3.2512)
			(layers "B.Cu" "B.Mask" "B.Paste")
			(net "GND")
		)
	)
	(footprint ""
		(layer "B.Cu")
		(at 112.395 -29.099002 90)
		(property "Reference" "C228"
			(at 0 0 90)
			(layer "B.SilkS")
			(hide yes)
			(effects
				(font
					(size 1.27 1.27)
				)
				(justify mirror)
			)
		)
		(property "Value" "SC1U10V2KX-1GP"
			(at -1.1811 -2.7051 90)
			(unlocked yes)
			(layer "B.Fab")
			(hide yes)
			(effects
				(font
					(size 1.016 1.016)
					(thickness 0.1524)
				)
				(justify mirror)
			)
		)
		(property "Device Type" "C402H22"
			(at -1.1811 -4.2291 90)
			(unlocked yes)
			(layer "B.Fab")
			(hide yes)
			(effects
				(font
					(size 1.016 1.016)
					(thickness 0.1524)
				)
				(justify mirror)
			)
		)
		(duplicate_pad_numbers_are_jumpers no)
		(fp_rect
			(start 0.381 0.7366)
			(end -0.381 -0.7366)
			(stroke
				(width 0)
				(type default)
			)
			(fill no)
			(layer "B.CrtYd")
		)
		(fp_rect
			(start 0.381 0.7366)
			(end -0.381 -0.7366)
			(stroke
				(width 0)
				(type default)
			)
			(fill no)
			(layer "B.Fab")
		)
		(pad "1" smd custom
			(at 0 -0.4572 270)
			(size 0.1143 0.1143)
			(layers "B.Cu" "B.Mask" "B.Paste")
			(net "PV_VDDR")
			(options
				(clearance outline)
				(anchor circle)
			)
			(primitives
				(gr_poly
					(pts
						(arc
							(start -0.254 0.1778)
							(mid -0.239121 0.213721)
							(end -0.2032 0.2286)
						)
						(arc
							(start 0.2032 0.2286)
							(mid 0.239121 0.213721)
							(end 0.254 0.1778)
						)
						(arc
							(start 0.254 -0.1778)
							(mid 0.239121 -0.213721)
							(end 0.2032 -0.2286)
						)
						(arc
							(start -0.2032 -0.2286)
							(mid -0.239121 -0.213721)
							(end -0.254 -0.1778)
						)
					)
					(width 0)
					(fill yes)
				)
			)
		)
		(pad "2" smd custom
			(at 0 0.4572 270)
			(size 0.1143 0.1143)
			(layers "B.Cu" "B.Mask" "B.Paste")
			(net "GND")
			(options
				(clearance outline)
				(anchor circle)
			)
			(primitives
				(gr_poly
					(pts
						(arc
							(start -0.254 0.1778)
							(mid -0.239121 0.213721)
							(end -0.2032 0.2286)
						)
						(arc
							(start 0.2032 0.2286)
							(mid 0.239121 0.213721)
							(end 0.254 0.1778)
						)
						(arc
							(start 0.254 -0.1778)
							(mid 0.239121 -0.213721)
							(end 0.2032 -0.2286)
						)
						(arc
							(start -0.2032 -0.2286)
							(mid -0.239121 -0.213721)
							(end -0.254 -0.1778)
						)
					)
					(width 0)
					(fill yes)
				)
			)
		)
	)
	(footprint ""
		(layer "B.Cu")
		(at 102.362 -67.31)
		(property "Reference" "PR6"
			(at 0 0 0)
			(layer "B.SilkS")
			(hide yes)
			(effects
				(font
					(size 1.27 1.27)
				)
				(justify mirror)
			)
		)
		(property "Value" "200KR2F-L-GP"
			(at -0.064008 -3.993896 0)
			(unlocked yes)
			(layer "B.Fab")
			(hide yes)
			(effects
				(font
					(size 1.016 1.016)
					(thickness 0.1524)
				)
				(justify mirror)
			)
		)
		(property "Device Type" "R402H16"
			(at -0.064008 -5.517896 0)
			(unlocked yes)
			(layer "B.Fab")
			(hide yes)
			(effects
				(font
					(size 1.016 1.016)
					(thickness 0.1524)
				)
				(justify mirror)
			)
		)
		(duplicate_pad_numbers_are_jumpers no)
		(fp_rect
			(start 0.381 0.8382)
			(end -0.381 -0.8382)
			(stroke
				(width 0)
				(type default)
			)
			(fill no)
			(layer "B.CrtYd")
		)
		(fp_rect
			(start 0.381 0.8382)
			(end -0.381 -0.8382)
			(stroke
				(width 0)
				(type default)
			)
			(fill no)
			(layer "B.Fab")
		)
		(pad "1" smd custom
			(at 0 -0.4318 180)
			(size 0.127 0.127)
			(layers "B.Cu" "B.Mask" "B.Paste")
			(net "VR_P1V1_VFBR")
			(options
				(clearance outline)
				(anchor circle)
			)
			(primitives
				(gr_poly
					(pts
						(arc
							(start -0.2032 0.2794)
							(mid -0.239121 0.264521)
							(end -0.254 0.2286)
						)
						(arc
							(start -0.254 -0.2286)
							(mid -0.239121 -0.264521)
							(end -0.2032 -0.2794)
						)
						(arc
							(start 0.2032 -0.2794)
							(mid 0.239121 -0.264521)
							(end 0.254 -0.2286)
						)
						(arc
							(start 0.254 0.2286)
							(mid 0.239121 0.264521)
							(end 0.2032 0.2794)
						)
					)
					(width 0)
					(fill yes)
				)
			)
		)
		(pad "2" smd custom
			(at 0 0.4318 180)
			(size 0.127 0.127)
			(layers "B.Cu" "B.Mask" "B.Paste")
			(net "VR_P1V1_VFB")
			(options
				(clearance outline)
				(anchor circle)
			)
			(primitives
				(gr_poly
					(pts
						(arc
							(start -0.2032 0.2794)
							(mid -0.239121 0.264521)
							(end -0.254 0.2286)
						)
						(arc
							(start -0.254 -0.2286)
							(mid -0.239121 -0.264521)
							(end -0.2032 -0.2794)
						)
						(arc
							(start 0.2032 -0.2794)
							(mid 0.239121 -0.264521)
							(end 0.254 -0.2286)
						)
						(arc
							(start 0.254 0.2286)
							(mid 0.239121 0.264521)
							(end 0.2032 0.2794)
						)
					)
					(width 0)
					(fill yes)
				)
			)
		)
	)
	(footprint ""
		(layer "B.Cu")
		(at 92.71 -30.099 90)
		(property "Reference" "C225"
			(at 0 0 90)
			(layer "B.SilkS")
			(hide yes)
			(effects
				(font
					(size 1.27 1.27)
				)
				(justify mirror)
			)
		)
		(property "Value" "SC1U10V2KX-1GP"
			(at -1.1811 -2.7051 90)
			(unlocked yes)
			(layer "B.Fab")
			(hide yes)
			(effects
				(font
					(size 1.016 1.016)
					(thickness 0.1524)
				)
				(justify mirror)
			)
		)
		(property "Device Type" "C402H22"
			(at -1.1811 -4.2291 90)
			(unlocked yes)
			(layer "B.Fab")
			(hide yes)
			(effects
				(font
					(size 1.016 1.016)
					(thickness 0.1524)
				)
				(justify mirror)
			)
		)
		(duplicate_pad_numbers_are_jumpers no)
		(fp_rect
			(start 0.381 0.7366)
			(end -0.381 -0.7366)
			(stroke
				(width 0)
				(type default)
			)
			(fill no)
			(layer "B.CrtYd")
		)
		(fp_rect
			(start 0.381 0.7366)
			(end -0.381 -0.7366)
			(stroke
				(width 0)
				(type default)
			)
			(fill no)
			(layer "B.Fab")
		)
		(pad "1" smd custom
			(at 0 -0.4572 270)
			(size 0.1143 0.1143)
			(layers "B.Cu" "B.Mask" "B.Paste")
			(net "P1V0")
			(options
				(clearance outline)
				(anchor circle)
			)
			(primitives
				(gr_poly
					(pts
						(arc
							(start -0.254 0.1778)
							(mid -0.239121 0.213721)
							(end -0.2032 0.2286)
						)
						(arc
							(start 0.2032 0.2286)
							(mid 0.239121 0.213721)
							(end 0.254 0.1778)
						)
						(arc
							(start 0.254 -0.1778)
							(mid 0.239121 -0.213721)
							(end 0.2032 -0.2286)
						)
						(arc
							(start -0.2032 -0.2286)
							(mid -0.239121 -0.213721)
							(end -0.254 -0.1778)
						)
					)
					(width 0)
					(fill yes)
				)
			)
		)
		(pad "2" smd custom
			(at 0 0.4572 270)
			(size 0.1143 0.1143)
			(layers "B.Cu" "B.Mask" "B.Paste")
			(net "GND")
			(options
				(clearance outline)
				(anchor circle)
			)
			(primitives
				(gr_poly
					(pts
						(arc
							(start -0.254 0.1778)
							(mid -0.239121 0.213721)
							(end -0.2032 0.2286)
						)
						(arc
							(start 0.2032 0.2286)
							(mid 0.239121 0.213721)
							(end 0.254 0.1778)
						)
						(arc
							(start 0.254 -0.1778)
							(mid 0.239121 -0.213721)
							(end 0.2032 -0.2286)
						)
						(arc
							(start -0.2032 -0.2286)
							(mid -0.239121 -0.213721)
							(end -0.254 -0.1778)
						)
					)
					(width 0)
					(fill yes)
				)
			)
		)
	)
	(footprint ""
		(layer "B.Cu")
		(at 94.869 -27.702002 180)
		(property "Reference" "TP52"
			(at 0 0 0)
			(layer "B.SilkS")
			(hide yes)
			(effects
				(font
					(size 1.27 1.27)
				)
				(justify mirror)
			)
		)
		(property "Value" "TPAD24"
			(at 0 -2.9972 180)
			(unlocked yes)
			(layer "B.Fab")
			(hide yes)
			(effects
				(font
					(size 1.016 1.016)
					(thickness 0.1524)
				)
				(justify mirror)
			)
		)
		(property "Device Type" "TPAD24"
			(at 0 -4.5212 180)
			(unlocked yes)
			(layer "B.Fab")
			(hide yes)
			(effects
				(font
					(size 1.016 1.016)
					(thickness 0.1524)
				)
				(justify mirror)
			)
		)
		(duplicate_pad_numbers_are_jumpers no)
		(fp_poly
			(pts
				(arc
					(start -0.3048 0)
					(mid 0.3048 0)
					(end -0.3048 0)
				)
			)
			(stroke
				(width 0)
				(type default)
			)
			(fill no)
			(layer "B.CrtYd")
		)
		(fp_poly
			(pts
				(arc
					(start -0.6096 0)
					(mid 0.6096 0)
					(end -0.6096 0)
				)
			)
			(stroke
				(width 0)
				(type default)
			)
			(fill no)
			(layer "B.Fab")
		)
		(pad "1" smd circle
			(at 0 0)
			(size 0.6096 0.6096)
			(layers "B.Cu" "B.Mask" "B.Paste")
			(net "TP_CPU_RSVD16")
		)
	)
	(footprint ""
		(layer "B.Cu")
		(at 133.223 -23.622 -90)
		(property "Reference" "R48"
			(at 0 0 90)
			(layer "B.SilkS")
			(hide yes)
			(effects
				(font
					(size 1.27 1.27)
				)
				(justify mirror)
			)
		)
		(property "Value" "0R2J-2-GP"
			(at -0.064008 -3.993896 270)
			(unlocked yes)
			(layer "B.Fab")
			(hide yes)
			(effects
				(font
					(size 1.016 1.016)
					(thickness 0.1524)
				)
				(justify mirror)
			)
		)
		(property "Device Type" "R402H16"
			(at -0.064008 -5.517896 270)
			(unlocked yes)
			(layer "B.Fab")
			(hide yes)
			(effects
				(font
					(size 1.016 1.016)
					(thickness 0.1524)
				)
				(justify mirror)
			)
		)
		(duplicate_pad_numbers_are_jumpers no)
		(fp_rect
			(start 0.381 0.8382)
			(end -0.381 -0.8382)
			(stroke
				(width 0)
				(type default)
			)
			(fill no)
			(layer "B.CrtYd")
		)
		(fp_rect
			(start 0.381 0.8382)
			(end -0.381 -0.8382)
			(stroke
				(width 0)
				(type default)
			)
			(fill no)
			(layer "B.Fab")
		)
		(pad "1" smd custom
			(at 0 -0.4318 90)
			(size 0.127 0.127)
			(layers "B.Cu" "B.Mask" "B.Paste")
			(net "BIOS_POST_COMPLETE_R")
			(options
				(clearance outline)
				(anchor circle)
			)
			(primitives
				(gr_poly
					(pts
						(arc
							(start -0.2032 0.2794)
							(mid -0.239121 0.264521)
							(end -0.254 0.2286)
						)
						(arc
							(start -0.254 -0.2286)
							(mid -0.239121 -0.264521)
							(end -0.2032 -0.2794)
						)
						(arc
							(start 0.2032 -0.2794)
							(mid 0.239121 -0.264521)
							(end 0.254 -0.2286)
						)
						(arc
							(start 0.254 0.2286)
							(mid 0.239121 0.264521)
							(end 0.2032 0.2794)
						)
					)
					(width 0)
					(fill yes)
				)
			)
		)
		(pad "2" smd custom
			(at 0 0.4318 90)
			(size 0.127 0.127)
			(layers "B.Cu" "B.Mask" "B.Paste")
			(net "BIOS_POST_CMPLT#")
			(options
				(clearance outline)
				(anchor circle)
			)
			(primitives
				(gr_poly
					(pts
						(arc
							(start -0.2032 0.2794)
							(mid -0.239121 0.264521)
							(end -0.254 0.2286)
						)
						(arc
							(start -0.254 -0.2286)
							(mid -0.239121 -0.264521)
							(end -0.2032 -0.2794)
						)
						(arc
							(start 0.2032 -0.2794)
							(mid 0.239121 -0.264521)
							(end 0.254 -0.2286)
						)
						(arc
							(start 0.254 0.2286)
							(mid 0.239121 0.264521)
							(end 0.2032 0.2794)
						)
					)
					(width 0)
					(fill yes)
				)
			)
		)
	)
	(footprint ""
		(layer "B.Cu")
		(at 95.25 -31.385002 -90)
		(property "Reference" "TP47"
			(at 0 0 90)
			(layer "B.SilkS")
			(hide yes)
			(effects
				(font
					(size 1.27 1.27)
				)
				(justify mirror)
			)
		)
		(property "Value" "TPAD24"
			(at 0 -2.9972 270)
			(unlocked yes)
			(layer "B.Fab")
			(hide yes)
			(effects
				(font
					(size 1.016 1.016)
					(thickness 0.1524)
				)
				(justify mirror)
			)
		)
		(property "Device Type" "TPAD24"
			(at 0 -4.5212 270)
			(unlocked yes)
			(layer "B.Fab")
			(hide yes)
			(effects
				(font
					(size 1.016 1.016)
					(thickness 0.1524)
				)
				(justify mirror)
			)
		)
		(duplicate_pad_numbers_are_jumpers no)
		(fp_poly
			(pts
				(arc
					(start 0 -0.3048)
					(mid 0 0.3048)
					(end 0 -0.3048)
				)
			)
			(stroke
				(width 0)
				(type default)
			)
			(fill no)
			(layer "B.CrtYd")
		)
		(fp_poly
			(pts
				(arc
					(start 0 -0.6096)
					(mid 0 0.6096)
					(end 0 -0.6096)
				)
			)
			(stroke
				(width 0)
				(type default)
			)
			(fill no)
			(layer "B.Fab")
		)
		(pad "1" smd circle
			(at 0 0 90)
			(size 0.6096 0.6096)
			(layers "B.Cu" "B.Mask" "B.Paste")
			(net "TP_CPU_RSVD14")
		)
	)
	(footprint ""
		(layer "B.Cu")
		(at 31.496 -53.594)
		(property "Reference" "PR178"
			(at 0 0 0)
			(layer "B.SilkS")
			(hide yes)
			(effects
				(font
					(size 1.27 1.27)
				)
				(justify mirror)
			)
		)
		(property "Value" "0R2J-2-GP"
			(at -1.7907 -1.1176 0)
			(unlocked yes)
			(layer "B.Fab")
			(hide yes)
			(effects
				(font
					(size 1.016 1.016)
					(thickness 0.1524)
				)
				(justify mirror)
			)
		)
		(property "Device Type" "R402H16"
			(at -1.7907 -2.6416 0)
			(unlocked yes)
			(layer "B.Fab")
			(hide yes)
			(effects
				(font
					(size 1.016 1.016)
					(thickness 0.1524)
				)
				(justify mirror)
			)
		)
		(duplicate_pad_numbers_are_jumpers no)
		(fp_rect
			(start 0.381 0.8382)
			(end -0.381 -0.8382)
			(stroke
				(width 0)
				(type default)
			)
			(fill no)
			(layer "B.CrtYd")
		)
		(fp_rect
			(start 0.381 0.8382)
			(end -0.381 -0.8382)
			(stroke
				(width 0)
				(type default)
			)
			(fill no)
			(layer "B.Fab")
		)
		(pad "1" smd custom
			(at 0 -0.4318 180)
			(size 0.127 0.127)
			(layers "B.Cu" "B.Mask" "B.Paste")
			(net "P3V3_STBY")
			(options
				(clearance outline)
				(anchor circle)
			)
			(primitives
				(gr_poly
					(pts
						(arc
							(start -0.2032 0.2794)
							(mid -0.239121 0.264521)
							(end -0.254 0.2286)
						)
						(arc
							(start -0.254 -0.2286)
							(mid -0.239121 -0.264521)
							(end -0.2032 -0.2794)
						)
						(arc
							(start 0.2032 -0.2794)
							(mid 0.239121 -0.264521)
							(end 0.254 -0.2286)
						)
						(arc
							(start 0.254 0.2286)
							(mid 0.239121 0.264521)
							(end 0.2032 0.2794)
						)
					)
					(width 0)
					(fill yes)
				)
			)
		)
		(pad "2" smd custom
			(at 0 0.4318 180)
			(size 0.127 0.127)
			(layers "B.Cu" "B.Mask" "B.Paste")
			(net "P1V5_STBY_BIAS")
			(options
				(clearance outline)
				(anchor circle)
			)
			(primitives
				(gr_poly
					(pts
						(arc
							(start -0.2032 0.2794)
							(mid -0.239121 0.264521)
							(end -0.254 0.2286)
						)
						(arc
							(start -0.254 -0.2286)
							(mid -0.239121 -0.264521)
							(end -0.2032 -0.2794)
						)
						(arc
							(start 0.2032 -0.2794)
							(mid 0.239121 -0.264521)
							(end 0.254 -0.2286)
						)
						(arc
							(start 0.254 0.2286)
							(mid 0.239121 0.264521)
							(end 0.2032 0.2794)
						)
					)
					(width 0)
					(fill yes)
				)
			)
		)
	)
	(footprint ""
		(layer "B.Cu")
		(at 185.039 -14.986 90)
		(property "Reference" "PC207"
			(at 0 0 90)
			(layer "B.SilkS")
			(hide yes)
			(effects
				(font
					(size 1.27 1.27)
				)
				(justify mirror)
			)
		)
		(property "Value" "SC10U6D3V3MX-GP"
			(at 0 -2.8194 90)
			(unlocked yes)
			(layer "B.Fab")
			(hide yes)
			(effects
				(font
					(size 1.016 1.016)
					(thickness 0.1524)
				)
				(justify mirror)
			)
		)
		(property "Device Type" "C603H38"
			(at 0 -4.3434 90)
			(unlocked yes)
			(layer "B.Fab")
			(hide yes)
			(effects
				(font
					(size 1.016 1.016)
					(thickness 0.1524)
				)
				(justify mirror)
			)
		)
		(duplicate_pad_numbers_are_jumpers no)
		(fp_line
			(start 0.4064 0)
			(end -0.4064 0)
			(stroke
				(width 0.2286)
				(type default)
			)
			(layer "B.SilkS")
		)
		(fp_rect
			(start 0.635 1.1811)
			(end -0.635 -1.1811)
			(stroke
				(width 0)
				(type default)
			)
			(fill no)
			(layer "B.CrtYd")
		)
		(fp_rect
			(start 0.635 1.1811)
			(end -0.635 -1.1811)
			(stroke
				(width 0)
				(type default)
			)
			(fill no)
			(layer "B.Fab")
		)
		(pad "1" smd custom
			(at 0 -0.6604 270)
			(size 0.19685 0.19685)
			(layers "B.Cu" "B.Mask" "B.Paste")
			(net "GND")
			(options
				(clearance outline)
				(anchor circle)
			)
			(primitives
				(gr_poly
					(pts
						(arc
							(start 0.508 0.2921)
							(mid 0.478242 0.363942)
							(end 0.4064 0.3937)
						)
						(arc
							(start -0.4064 0.3937)
							(mid -0.478242 0.363942)
							(end -0.508 0.2921)
						)
						(arc
							(start -0.508 -0.2921)
							(mid -0.478242 -0.363942)
							(end -0.4064 -0.3937)
						)
						(arc
							(start 0.4064 -0.3937)
							(mid 0.478242 -0.363942)
							(end 0.508 -0.2921)
						)
					)
					(width 0)
					(fill yes)
				)
			)
		)
		(pad "2" smd custom
			(at 0 0.6604 270)
			(size 0.19685 0.19685)
			(layers "B.Cu" "B.Mask" "B.Paste")
			(net "PV_VTT_DDR_B")
			(options
				(clearance outline)
				(anchor circle)
			)
			(primitives
				(gr_poly
					(pts
						(arc
							(start 0.508 0.2921)
							(mid 0.478242 0.363942)
							(end 0.4064 0.3937)
						)
						(arc
							(start -0.4064 0.3937)
							(mid -0.478242 0.363942)
							(end -0.508 0.2921)
						)
						(arc
							(start -0.508 -0.2921)
							(mid -0.478242 -0.363942)
							(end -0.4064 -0.3937)
						)
						(arc
							(start 0.4064 -0.3937)
							(mid 0.478242 -0.363942)
							(end 0.508 -0.2921)
						)
					)
					(width 0)
					(fill yes)
				)
			)
		)
	)
	(footprint ""
		(layer "B.Cu")
		(at 22.5552 -56.261 180)
		(property "Reference" "PC65"
			(at 0 0 0)
			(layer "B.SilkS")
			(hide yes)
			(effects
				(font
					(size 1.27 1.27)
				)
				(justify mirror)
			)
		)
		(property "Value" "SC1U16V3KX-5GP"
			(at 0.0254 -2.0193 180)
			(unlocked yes)
			(layer "B.Fab")
			(hide yes)
			(effects
				(font
					(size 1.016 1.016)
					(thickness 0.1524)
				)
				(justify mirror)
			)
		)
		(property "Device Type" "C603H36"
			(at 0.0254 -3.5433 180)
			(unlocked yes)
			(layer "B.Fab")
			(hide yes)
			(effects
				(font
					(size 1.016 1.016)
					(thickness 0.1524)
				)
				(justify mirror)
			)
		)
		(duplicate_pad_numbers_are_jumpers no)
		(fp_line
			(start 0.4064 0)
			(end -0.4064 0)
			(stroke
				(width 0.2286)
				(type default)
			)
			(layer "B.SilkS")
		)
		(fp_rect
			(start 0.635 1.1811)
			(end -0.635 -1.1811)
			(stroke
				(width 0)
				(type default)
			)
			(fill no)
			(layer "B.CrtYd")
		)
		(fp_rect
			(start 0.635 1.1811)
			(end -0.635 -1.1811)
			(stroke
				(width 0)
				(type default)
			)
			(fill no)
			(layer "B.Fab")
		)
		(pad "1" smd custom
			(at 0 -0.6604)
			(size 0.19685 0.19685)
			(layers "B.Cu" "B.Mask" "B.Paste")
			(net "VR_PVCCP_PVNN_VDD")
			(options
				(clearance outline)
				(anchor circle)
			)
			(primitives
				(gr_poly
					(pts
						(arc
							(start 0.508 0.2921)
							(mid 0.478242 0.363942)
							(end 0.4064 0.3937)
						)
						(arc
							(start -0.4064 0.3937)
							(mid -0.478242 0.363942)
							(end -0.508 0.2921)
						)
						(arc
							(start -0.508 -0.2921)
							(mid -0.478242 -0.363942)
							(end -0.4064 -0.3937)
						)
						(arc
							(start 0.4064 -0.3937)
							(mid 0.478242 -0.363942)
							(end 0.508 -0.2921)
						)
					)
					(width 0)
					(fill yes)
				)
			)
		)
		(pad "2" smd custom
			(at 0 0.6604)
			(size 0.19685 0.19685)
			(layers "B.Cu" "B.Mask" "B.Paste")
			(net "GND")
			(options
				(clearance outline)
				(anchor circle)
			)
			(primitives
				(gr_poly
					(pts
						(arc
							(start 0.508 0.2921)
							(mid 0.478242 0.363942)
							(end 0.4064 0.3937)
						)
						(arc
							(start -0.4064 0.3937)
							(mid -0.478242 0.363942)
							(end -0.508 0.2921)
						)
						(arc
							(start -0.508 -0.2921)
							(mid -0.478242 -0.363942)
							(end -0.4064 -0.3937)
						)
						(arc
							(start 0.4064 -0.3937)
							(mid 0.478242 -0.363942)
							(end 0.508 -0.2921)
						)
					)
					(width 0)
					(fill yes)
				)
			)
		)
	)
	(footprint ""
		(layer "B.Cu")
		(at 110.236 -13.335)
		(property "Reference" "R467"
			(at 0 0 0)
			(layer "B.SilkS")
			(hide yes)
			(effects
				(font
					(size 1.27 1.27)
				)
				(justify mirror)
			)
		)
		(property "Value" "4K7R2F-GP"
			(at -1.7907 -1.1176 0)
			(unlocked yes)
			(layer "B.Fab")
			(hide yes)
			(effects
				(font
					(size 1.016 1.016)
					(thickness 0.1524)
				)
				(justify mirror)
			)
		)
		(property "Device Type" "R402H16"
			(at -1.7907 -2.6416 0)
			(unlocked yes)
			(layer "B.Fab")
			(hide yes)
			(effects
				(font
					(size 1.016 1.016)
					(thickness 0.1524)
				)
				(justify mirror)
			)
		)
		(duplicate_pad_numbers_are_jumpers no)
		(fp_rect
			(start 0.381 0.8382)
			(end -0.381 -0.8382)
			(stroke
				(width 0)
				(type default)
			)
			(fill no)
			(layer "B.CrtYd")
		)
		(fp_rect
			(start 0.381 0.8382)
			(end -0.381 -0.8382)
			(stroke
				(width 0)
				(type default)
			)
			(fill no)
			(layer "B.Fab")
		)
		(pad "1" smd custom
			(at 0 -0.4318 180)
			(size 0.127 0.127)
			(layers "B.Cu" "B.Mask" "B.Paste")
			(net "P3V3")
			(options
				(clearance outline)
				(anchor circle)
			)
			(primitives
				(gr_poly
					(pts
						(arc
							(start -0.2032 0.2794)
							(mid -0.239121 0.264521)
							(end -0.254 0.2286)
						)
						(arc
							(start -0.254 -0.2286)
							(mid -0.239121 -0.264521)
							(end -0.2032 -0.2794)
						)
						(arc
							(start 0.2032 -0.2794)
							(mid 0.239121 -0.264521)
							(end 0.254 -0.2286)
						)
						(arc
							(start 0.254 0.2286)
							(mid 0.239121 0.264521)
							(end 0.2032 0.2794)
						)
					)
					(width 0)
					(fill yes)
				)
			)
		)
		(pad "2" smd custom
			(at 0 0.4318 180)
			(size 0.127 0.127)
			(layers "B.Cu" "B.Mask" "B.Paste")
			(net "IRQ_CPU_SERIAL")
			(options
				(clearance outline)
				(anchor circle)
			)
			(primitives
				(gr_poly
					(pts
						(arc
							(start -0.2032 0.2794)
							(mid -0.239121 0.264521)
							(end -0.254 0.2286)
						)
						(arc
							(start -0.254 -0.2286)
							(mid -0.239121 -0.264521)
							(end -0.2032 -0.2794)
						)
						(arc
							(start 0.2032 -0.2794)
							(mid 0.239121 -0.264521)
							(end 0.254 -0.2286)
						)
						(arc
							(start 0.254 0.2286)
							(mid 0.239121 0.264521)
							(end 0.2032 0.2794)
						)
					)
					(width 0)
					(fill yes)
				)
			)
		)
	)
	(footprint ""
		(layer "B.Cu")
		(at 22.479 -12.7)
		(property "Reference" "C284"
			(at 0 0 0)
			(layer "B.SilkS")
			(hide yes)
			(effects
				(font
					(size 1.27 1.27)
				)
				(justify mirror)
			)
		)
		(property "Value" "SCD1U16V2KX-3GP"
			(at -1.1811 -2.7051 0)
			(unlocked yes)
			(layer "B.Fab")
			(hide yes)
			(effects
				(font
					(size 1.016 1.016)
					(thickness 0.1524)
				)
				(justify mirror)
			)
		)
		(property "Device Type" "C402H22"
			(at -1.1811 -4.2291 0)
			(unlocked yes)
			(layer "B.Fab")
			(hide yes)
			(effects
				(font
					(size 1.016 1.016)
					(thickness 0.1524)
				)
				(justify mirror)
			)
		)
		(duplicate_pad_numbers_are_jumpers no)
		(fp_rect
			(start 0.381 0.7366)
			(end -0.381 -0.7366)
			(stroke
				(width 0)
				(type default)
			)
			(fill no)
			(layer "B.CrtYd")
		)
		(fp_rect
			(start 0.381 0.7366)
			(end -0.381 -0.7366)
			(stroke
				(width 0)
				(type default)
			)
			(fill no)
			(layer "B.Fab")
		)
		(pad "1" smd custom
			(at 0 -0.4572 180)
			(size 0.1143 0.1143)
			(layers "B.Cu" "B.Mask" "B.Paste")
			(net "P2E_CPU_ETH10G_C_TX_DP10")
			(options
				(clearance outline)
				(anchor circle)
			)
			(primitives
				(gr_poly
					(pts
						(arc
							(start -0.254 0.1778)
							(mid -0.239121 0.213721)
							(end -0.2032 0.2286)
						)
						(arc
							(start 0.2032 0.2286)
							(mid 0.239121 0.213721)
							(end 0.254 0.1778)
						)
						(arc
							(start 0.254 -0.1778)
							(mid 0.239121 -0.213721)
							(end 0.2032 -0.2286)
						)
						(arc
							(start -0.2032 -0.2286)
							(mid -0.239121 -0.213721)
							(end -0.254 -0.1778)
						)
					)
					(width 0)
					(fill yes)
				)
			)
		)
		(pad "2" smd custom
			(at 0 0.4572 180)
			(size 0.1143 0.1143)
			(layers "B.Cu" "B.Mask" "B.Paste")
			(net "P2E_CPU_ETH10G_TX_DP10")
			(options
				(clearance outline)
				(anchor circle)
			)
			(primitives
				(gr_poly
					(pts
						(arc
							(start -0.254 0.1778)
							(mid -0.239121 0.213721)
							(end -0.2032 0.2286)
						)
						(arc
							(start 0.2032 0.2286)
							(mid 0.239121 0.213721)
							(end 0.254 0.1778)
						)
						(arc
							(start 0.254 -0.1778)
							(mid 0.239121 -0.213721)
							(end 0.2032 -0.2286)
						)
						(arc
							(start -0.2032 -0.2286)
							(mid -0.239121 -0.213721)
							(end -0.254 -0.1778)
						)
					)
					(width 0)
					(fill yes)
				)
			)
		)
	)
	(footprint ""
		(layer "B.Cu")
		(at 74.041 -28.702 90)
		(property "Reference" "R456"
			(at 0 0 90)
			(layer "B.SilkS")
			(hide yes)
			(effects
				(font
					(size 1.27 1.27)
				)
				(justify mirror)
			)
		)
		(property "Value" "10KR2F-2-GP"
			(at -1.7907 -1.1176 90)
			(unlocked yes)
			(layer "B.Fab")
			(hide yes)
			(effects
				(font
					(size 1.016 1.016)
					(thickness 0.1524)
				)
				(justify mirror)
			)
		)
		(property "Device Type" "R402H16"
			(at -1.7907 -2.6416 90)
			(unlocked yes)
			(layer "B.Fab")
			(hide yes)
			(effects
				(font
					(size 1.016 1.016)
					(thickness 0.1524)
				)
				(justify mirror)
			)
		)
		(duplicate_pad_numbers_are_jumpers no)
		(fp_rect
			(start 0.381 0.8382)
			(end -0.381 -0.8382)
			(stroke
				(width 0)
				(type default)
			)
			(fill no)
			(layer "B.CrtYd")
		)
		(fp_rect
			(start 0.381 0.8382)
			(end -0.381 -0.8382)
			(stroke
				(width 0)
				(type default)
			)
			(fill no)
			(layer "B.Fab")
		)
		(pad "1" smd custom
			(at 0 -0.4318 270)
			(size 0.127 0.127)
			(layers "B.Cu" "B.Mask" "B.Paste")
			(net "P3V3_CPU")
			(options
				(clearance outline)
				(anchor circle)
			)
			(primitives
				(gr_poly
					(pts
						(arc
							(start -0.2032 0.2794)
							(mid -0.239121 0.264521)
							(end -0.254 0.2286)
						)
						(arc
							(start -0.254 -0.2286)
							(mid -0.239121 -0.264521)
							(end -0.2032 -0.2794)
						)
						(arc
							(start 0.2032 -0.2794)
							(mid 0.239121 -0.264521)
							(end 0.254 -0.2286)
						)
						(arc
							(start 0.254 0.2286)
							(mid 0.239121 0.264521)
							(end 0.2032 0.2794)
						)
					)
					(width 0)
					(fill yes)
				)
			)
		)
		(pad "2" smd custom
			(at 0 0.4318 270)
			(size 0.127 0.127)
			(layers "B.Cu" "B.Mask" "B.Paste")
			(net "REV_CPU_FPGA_IO1")
			(options
				(clearance outline)
				(anchor circle)
			)
			(primitives
				(gr_poly
					(pts
						(arc
							(start -0.2032 0.2794)
							(mid -0.239121 0.264521)
							(end -0.254 0.2286)
						)
						(arc
							(start -0.254 -0.2286)
							(mid -0.239121 -0.264521)
							(end -0.2032 -0.2794)
						)
						(arc
							(start 0.2032 -0.2794)
							(mid 0.239121 -0.264521)
							(end 0.254 -0.2286)
						)
						(arc
							(start 0.254 0.2286)
							(mid 0.239121 0.264521)
							(end 0.2032 0.2794)
						)
					)
					(width 0)
					(fill yes)
				)
			)
		)
	)
	(footprint ""
		(layer "B.Cu")
		(at 98.933 -53.467 -90)
		(property "Reference" "C125"
			(at 0 0 90)
			(layer "B.SilkS")
			(hide yes)
			(effects
				(font
					(size 1.27 1.27)
				)
				(justify mirror)
			)
		)
		(property "Value" "SCD1U16V2KX-L-GP"
			(at -1.1811 -2.7051 270)
			(unlocked yes)
			(layer "B.Fab")
			(hide yes)
			(effects
				(font
					(size 1.016 1.016)
					(thickness 0.1524)
				)
				(justify mirror)
			)
		)
		(property "Device Type" "C402H22"
			(at -1.1811 -4.2291 270)
			(unlocked yes)
			(layer "B.Fab")
			(hide yes)
			(effects
				(font
					(size 1.016 1.016)
					(thickness 0.1524)
				)
				(justify mirror)
			)
		)
		(duplicate_pad_numbers_are_jumpers no)
		(fp_rect
			(start 0.381 0.7366)
			(end -0.381 -0.7366)
			(stroke
				(width 0)
				(type default)
			)
			(fill no)
			(layer "B.CrtYd")
		)
		(fp_rect
			(start 0.381 0.7366)
			(end -0.381 -0.7366)
			(stroke
				(width 0)
				(type default)
			)
			(fill no)
			(layer "B.Fab")
		)
		(pad "1" smd custom
			(at 0 -0.4572 90)
			(size 0.1143 0.1143)
			(layers "B.Cu" "B.Mask" "B.Paste")
			(net "M_A_VREF")
			(options
				(clearance outline)
				(anchor circle)
			)
			(primitives
				(gr_poly
					(pts
						(arc
							(start -0.254 0.1778)
							(mid -0.239121 0.213721)
							(end -0.2032 0.2286)
						)
						(arc
							(start 0.2032 0.2286)
							(mid 0.239121 0.213721)
							(end 0.254 0.1778)
						)
						(arc
							(start 0.254 -0.1778)
							(mid 0.239121 -0.213721)
							(end 0.2032 -0.2286)
						)
						(arc
							(start -0.2032 -0.2286)
							(mid -0.239121 -0.213721)
							(end -0.254 -0.1778)
						)
					)
					(width 0)
					(fill yes)
				)
			)
		)
		(pad "2" smd custom
			(at 0 0.4572 90)
			(size 0.1143 0.1143)
			(layers "B.Cu" "B.Mask" "B.Paste")
			(net "GND")
			(options
				(clearance outline)
				(anchor circle)
			)
			(primitives
				(gr_poly
					(pts
						(arc
							(start -0.254 0.1778)
							(mid -0.239121 0.213721)
							(end -0.2032 0.2286)
						)
						(arc
							(start 0.2032 0.2286)
							(mid 0.239121 0.213721)
							(end 0.254 0.1778)
						)
						(arc
							(start 0.254 -0.1778)
							(mid 0.239121 -0.213721)
							(end 0.2032 -0.2286)
						)
						(arc
							(start -0.2032 -0.2286)
							(mid -0.239121 -0.213721)
							(end -0.254 -0.1778)
						)
					)
					(width 0)
					(fill yes)
				)
			)
		)
	)
	(footprint ""
		(layer "B.Cu")
		(at 156.4386 -12.828778 180)
		(property "Reference" "C364"
			(at 0 0 0)
			(layer "B.SilkS")
			(hide yes)
			(effects
				(font
					(size 1.27 1.27)
				)
				(justify mirror)
			)
		)
		(property "Value" "SC47U6D3V5MX-1-GP"
			(at 0 -4.9022 180)
			(unlocked yes)
			(layer "B.Fab")
			(hide yes)
			(effects
				(font
					(size 1.016 1.016)
					(thickness 0.1524)
				)
				(justify mirror)
			)
		)
		(property "Device Type" "C805H54"
			(at 0 -6.8072 180)
			(unlocked yes)
			(layer "B.Fab")
			(hide yes)
			(effects
				(font
					(size 1.016 1.016)
					(thickness 0.1524)
				)
				(justify mirror)
			)
		)
		(duplicate_pad_numbers_are_jumpers no)
		(fp_line
			(start -0.6096 0)
			(end 0.6096 0)
			(stroke
				(width 0.3048)
				(type default)
			)
			(layer "B.SilkS")
		)
		(fp_poly
			(pts
				(xy 0.9017 1.4351) (xy -0.9017 1.4351) (xy -0.9017 -1.4351) (xy 0.9017 -1.4351)
			)
			(stroke
				(width 0)
				(type default)
			)
			(fill no)
			(layer "B.CrtYd")
		)
		(fp_poly
			(pts
				(xy -0.9017 1.4351) (xy -0.9017 -1.4351) (xy 0.9017 -1.4351) (xy 0.9017 1.4351)
			)
			(stroke
				(width 0)
				(type default)
			)
			(fill no)
			(layer "B.Fab")
		)
		(pad "1" smd rect
			(at 0 -0.8382)
			(size 1.5494 0.9398)
			(layers "B.Cu" "B.Mask" "B.Paste")
			(net "PV_VDDR")
		)
		(pad "2" smd rect
			(at 0 0.8382)
			(size 1.5494 0.9398)
			(layers "B.Cu" "B.Mask" "B.Paste")
			(net "GND")
		)
	)
	(footprint ""
		(layer "B.Cu")
		(at 120.777 -68.7578)
		(property "Reference" "R236"
			(at 0 0 0)
			(layer "B.SilkS")
			(hide yes)
			(effects
				(font
					(size 1.27 1.27)
				)
				(justify mirror)
			)
		)
		(property "Value" "0R2J-2-GP"
			(at -0.064008 -3.993896 0)
			(unlocked yes)
			(layer "B.Fab")
			(hide yes)
			(effects
				(font
					(size 1.016 1.016)
					(thickness 0.1524)
				)
				(justify mirror)
			)
		)
		(property "Device Type" "R402H16"
			(at -0.064008 -5.517896 0)
			(unlocked yes)
			(layer "B.Fab")
			(hide yes)
			(effects
				(font
					(size 1.016 1.016)
					(thickness 0.1524)
				)
				(justify mirror)
			)
		)
		(duplicate_pad_numbers_are_jumpers no)
		(fp_rect
			(start 0.381 0.8382)
			(end -0.381 -0.8382)
			(stroke
				(width 0)
				(type default)
			)
			(fill no)
			(layer "B.CrtYd")
		)
		(fp_rect
			(start 0.381 0.8382)
			(end -0.381 -0.8382)
			(stroke
				(width 0)
				(type default)
			)
			(fill no)
			(layer "B.Fab")
		)
		(pad "1" smd custom
			(at 0 -0.4318 180)
			(size 0.127 0.127)
			(layers "B.Cu" "B.Mask" "B.Paste")
			(net "SMB_M_A0_R_CLK")
			(options
				(clearance outline)
				(anchor circle)
			)
			(primitives
				(gr_poly
					(pts
						(arc
							(start -0.2032 0.2794)
							(mid -0.239121 0.264521)
							(end -0.254 0.2286)
						)
						(arc
							(start -0.254 -0.2286)
							(mid -0.239121 -0.264521)
							(end -0.2032 -0.2794)
						)
						(arc
							(start 0.2032 -0.2794)
							(mid 0.239121 -0.264521)
							(end 0.254 -0.2286)
						)
						(arc
							(start 0.254 0.2286)
							(mid 0.239121 0.264521)
							(end 0.2032 0.2794)
						)
					)
					(width 0)
					(fill yes)
				)
			)
		)
		(pad "2" smd custom
			(at 0 0.4318 180)
			(size 0.127 0.127)
			(layers "B.Cu" "B.Mask" "B.Paste")
			(net "SMB_HOST_LV_CLK")
			(options
				(clearance outline)
				(anchor circle)
			)
			(primitives
				(gr_poly
					(pts
						(arc
							(start -0.2032 0.2794)
							(mid -0.239121 0.264521)
							(end -0.254 0.2286)
						)
						(arc
							(start -0.254 -0.2286)
							(mid -0.239121 -0.264521)
							(end -0.2032 -0.2794)
						)
						(arc
							(start 0.2032 -0.2794)
							(mid 0.239121 -0.264521)
							(end 0.254 -0.2286)
						)
						(arc
							(start 0.254 0.2286)
							(mid 0.239121 0.264521)
							(end 0.2032 0.2794)
						)
					)
					(width 0)
					(fill yes)
				)
			)
		)
	)
	(footprint ""
		(layer "B.Cu")
		(at 92.329 -13.462)
		(property "Reference" "R340"
			(at 0 0 0)
			(layer "B.SilkS")
			(hide yes)
			(effects
				(font
					(size 1.27 1.27)
				)
				(justify mirror)
			)
		)
		(property "Value" "0R2J-2-GP"
			(at -0.064008 -3.993896 0)
			(unlocked yes)
			(layer "B.Fab")
			(hide yes)
			(effects
				(font
					(size 1.016 1.016)
					(thickness 0.1524)
				)
				(justify mirror)
			)
		)
		(property "Device Type" "R402H16"
			(at -0.064008 -5.517896 0)
			(unlocked yes)
			(layer "B.Fab")
			(hide yes)
			(effects
				(font
					(size 1.016 1.016)
					(thickness 0.1524)
				)
				(justify mirror)
			)
		)
		(duplicate_pad_numbers_are_jumpers no)
		(fp_rect
			(start 0.381 0.8382)
			(end -0.381 -0.8382)
			(stroke
				(width 0)
				(type default)
			)
			(fill no)
			(layer "B.CrtYd")
		)
		(fp_rect
			(start 0.381 0.8382)
			(end -0.381 -0.8382)
			(stroke
				(width 0)
				(type default)
			)
			(fill no)
			(layer "B.Fab")
		)
		(pad "1" smd custom
			(at 0 -0.4318 180)
			(size 0.127 0.127)
			(layers "B.Cu" "B.Mask" "B.Paste")
			(net "BMC_PWRBTN#")
			(options
				(clearance outline)
				(anchor circle)
			)
			(primitives
				(gr_poly
					(pts
						(arc
							(start -0.2032 0.2794)
							(mid -0.239121 0.264521)
							(end -0.254 0.2286)
						)
						(arc
							(start -0.254 -0.2286)
							(mid -0.239121 -0.264521)
							(end -0.2032 -0.2794)
						)
						(arc
							(start 0.2032 -0.2794)
							(mid 0.239121 -0.264521)
							(end 0.254 -0.2286)
						)
						(arc
							(start 0.254 0.2286)
							(mid 0.239121 0.264521)
							(end 0.2032 0.2794)
						)
					)
					(width 0)
					(fill yes)
				)
			)
		)
		(pad "2" smd custom
			(at 0 0.4318 180)
			(size 0.127 0.127)
			(layers "B.Cu" "B.Mask" "B.Paste")
			(net "PWR_BTN#")
			(options
				(clearance outline)
				(anchor circle)
			)
			(primitives
				(gr_poly
					(pts
						(arc
							(start -0.2032 0.2794)
							(mid -0.239121 0.264521)
							(end -0.254 0.2286)
						)
						(arc
							(start -0.254 -0.2286)
							(mid -0.239121 -0.264521)
							(end -0.2032 -0.2794)
						)
						(arc
							(start 0.2032 -0.2794)
							(mid 0.239121 -0.264521)
							(end 0.254 -0.2286)
						)
						(arc
							(start 0.254 0.2286)
							(mid 0.239121 0.264521)
							(end 0.2032 0.2794)
						)
					)
					(width 0)
					(fill yes)
				)
			)
		)
	)
	(footprint ""
		(layer "B.Cu")
		(at 112.395 -28.337002 90)
		(property "Reference" "C230"
			(at 0 0 90)
			(layer "B.SilkS")
			(hide yes)
			(effects
				(font
					(size 1.27 1.27)
				)
				(justify mirror)
			)
		)
		(property "Value" "SCD1U16V2KX-3GP"
			(at -1.1811 -2.7051 90)
			(unlocked yes)
			(layer "B.Fab")
			(hide yes)
			(effects
				(font
					(size 1.016 1.016)
					(thickness 0.1524)
				)
				(justify mirror)
			)
		)
		(property "Device Type" "C402H22"
			(at -1.1811 -4.2291 90)
			(unlocked yes)
			(layer "B.Fab")
			(hide yes)
			(effects
				(font
					(size 1.016 1.016)
					(thickness 0.1524)
				)
				(justify mirror)
			)
		)
		(duplicate_pad_numbers_are_jumpers no)
		(fp_rect
			(start 0.381 0.7366)
			(end -0.381 -0.7366)
			(stroke
				(width 0)
				(type default)
			)
			(fill no)
			(layer "B.CrtYd")
		)
		(fp_rect
			(start 0.381 0.7366)
			(end -0.381 -0.7366)
			(stroke
				(width 0)
				(type default)
			)
			(fill no)
			(layer "B.Fab")
		)
		(pad "1" smd custom
			(at 0 -0.4572 270)
			(size 0.1143 0.1143)
			(layers "B.Cu" "B.Mask" "B.Paste")
			(net "PV_VDDR")
			(options
				(clearance outline)
				(anchor circle)
			)
			(primitives
				(gr_poly
					(pts
						(arc
							(start -0.254 0.1778)
							(mid -0.239121 0.213721)
							(end -0.2032 0.2286)
						)
						(arc
							(start 0.2032 0.2286)
							(mid 0.239121 0.213721)
							(end 0.254 0.1778)
						)
						(arc
							(start 0.254 -0.1778)
							(mid 0.239121 -0.213721)
							(end 0.2032 -0.2286)
						)
						(arc
							(start -0.2032 -0.2286)
							(mid -0.239121 -0.213721)
							(end -0.254 -0.1778)
						)
					)
					(width 0)
					(fill yes)
				)
			)
		)
		(pad "2" smd custom
			(at 0 0.4572 270)
			(size 0.1143 0.1143)
			(layers "B.Cu" "B.Mask" "B.Paste")
			(net "GND")
			(options
				(clearance outline)
				(anchor circle)
			)
			(primitives
				(gr_poly
					(pts
						(arc
							(start -0.254 0.1778)
							(mid -0.239121 0.213721)
							(end -0.2032 0.2286)
						)
						(arc
							(start 0.2032 0.2286)
							(mid 0.239121 0.213721)
							(end 0.254 0.1778)
						)
						(arc
							(start 0.254 -0.1778)
							(mid 0.239121 -0.213721)
							(end 0.2032 -0.2286)
						)
						(arc
							(start -0.2032 -0.2286)
							(mid -0.239121 -0.213721)
							(end -0.254 -0.1778)
						)
					)
					(width 0)
					(fill yes)
				)
			)
		)
	)
	(footprint ""
		(layer "B.Cu")
		(at 37.719 -22.733 -90)
		(property "Reference" "R354"
			(at 0 0 90)
			(layer "B.SilkS")
			(hide yes)
			(effects
				(font
					(size 1.27 1.27)
				)
				(justify mirror)
			)
		)
		(property "Value" "33R2F-3-GP"
			(at -0.064008 -3.993896 270)
			(unlocked yes)
			(layer "B.Fab")
			(hide yes)
			(effects
				(font
					(size 1.016 1.016)
					(thickness 0.1524)
				)
				(justify mirror)
			)
		)
		(property "Device Type" "R402H16"
			(at -0.064008 -5.517896 270)
			(unlocked yes)
			(layer "B.Fab")
			(hide yes)
			(effects
				(font
					(size 1.016 1.016)
					(thickness 0.1524)
				)
				(justify mirror)
			)
		)
		(duplicate_pad_numbers_are_jumpers no)
		(fp_rect
			(start 0.381 0.8382)
			(end -0.381 -0.8382)
			(stroke
				(width 0)
				(type default)
			)
			(fill no)
			(layer "B.CrtYd")
		)
		(fp_rect
			(start 0.381 0.8382)
			(end -0.381 -0.8382)
			(stroke
				(width 0)
				(type default)
			)
			(fill no)
			(layer "B.Fab")
		)
		(pad "1" smd custom
			(at 0 -0.4318 90)
			(size 0.127 0.127)
			(layers "B.Cu" "B.Mask" "B.Paste")
			(net "CLK_100M_CLKBUFF_NGFF_R_DN")
			(options
				(clearance outline)
				(anchor circle)
			)
			(primitives
				(gr_poly
					(pts
						(arc
							(start -0.2032 0.2794)
							(mid -0.239121 0.264521)
							(end -0.254 0.2286)
						)
						(arc
							(start -0.254 -0.2286)
							(mid -0.239121 -0.264521)
							(end -0.2032 -0.2794)
						)
						(arc
							(start 0.2032 -0.2794)
							(mid 0.239121 -0.264521)
							(end 0.254 -0.2286)
						)
						(arc
							(start 0.254 0.2286)
							(mid 0.239121 0.264521)
							(end 0.2032 0.2794)
						)
					)
					(width 0)
					(fill yes)
				)
			)
		)
		(pad "2" smd custom
			(at 0 0.4318 90)
			(size 0.127 0.127)
			(layers "B.Cu" "B.Mask" "B.Paste")
			(net "CLK_100M_CLKBUFF_NGFF_DN")
			(options
				(clearance outline)
				(anchor circle)
			)
			(primitives
				(gr_poly
					(pts
						(arc
							(start -0.2032 0.2794)
							(mid -0.239121 0.264521)
							(end -0.254 0.2286)
						)
						(arc
							(start -0.254 -0.2286)
							(mid -0.239121 -0.264521)
							(end -0.2032 -0.2794)
						)
						(arc
							(start 0.2032 -0.2794)
							(mid 0.239121 -0.264521)
							(end 0.254 -0.2286)
						)
						(arc
							(start 0.254 0.2286)
							(mid 0.239121 0.264521)
							(end 0.2032 0.2794)
						)
					)
					(width 0)
					(fill yes)
				)
			)
		)
	)
	(footprint ""
		(layer "B.Cu")
		(at 41.8846 -27.5336 180)
		(property "Reference" "R328"
			(at 0 0 0)
			(layer "B.SilkS")
			(hide yes)
			(effects
				(font
					(size 1.27 1.27)
				)
				(justify mirror)
			)
		)
		(property "Value" "33R2F-3-GP"
			(at -0.064008 -3.993896 180)
			(unlocked yes)
			(layer "B.Fab")
			(hide yes)
			(effects
				(font
					(size 1.016 1.016)
					(thickness 0.1524)
				)
				(justify mirror)
			)
		)
		(property "Device Type" "R402H16"
			(at -0.064008 -5.517896 180)
			(unlocked yes)
			(layer "B.Fab")
			(hide yes)
			(effects
				(font
					(size 1.016 1.016)
					(thickness 0.1524)
				)
				(justify mirror)
			)
		)
		(duplicate_pad_numbers_are_jumpers no)
		(fp_rect
			(start 0.381 0.8382)
			(end -0.381 -0.8382)
			(stroke
				(width 0)
				(type default)
			)
			(fill no)
			(layer "B.CrtYd")
		)
		(fp_rect
			(start 0.381 0.8382)
			(end -0.381 -0.8382)
			(stroke
				(width 0)
				(type default)
			)
			(fill no)
			(layer "B.Fab")
		)
		(pad "1" smd custom
			(at 0 -0.4318)
			(size 0.127 0.127)
			(layers "B.Cu" "B.Mask" "B.Paste")
			(net "CLK_100M_CLKBUFF_PCIE_R_DN")
			(options
				(clearance outline)
				(anchor circle)
			)
			(primitives
				(gr_poly
					(pts
						(arc
							(start -0.2032 0.2794)
							(mid -0.239121 0.264521)
							(end -0.254 0.2286)
						)
						(arc
							(start -0.254 -0.2286)
							(mid -0.239121 -0.264521)
							(end -0.2032 -0.2794)
						)
						(arc
							(start 0.2032 -0.2794)
							(mid 0.239121 -0.264521)
							(end 0.254 -0.2286)
						)
						(arc
							(start 0.254 0.2286)
							(mid 0.239121 0.264521)
							(end 0.2032 0.2794)
						)
					)
					(width 0)
					(fill yes)
				)
			)
		)
		(pad "2" smd custom
			(at 0 0.4318)
			(size 0.127 0.127)
			(layers "B.Cu" "B.Mask" "B.Paste")
			(net "CLK_100M_CLKBUFF_PCIE_DN")
			(options
				(clearance outline)
				(anchor circle)
			)
			(primitives
				(gr_poly
					(pts
						(arc
							(start -0.2032 0.2794)
							(mid -0.239121 0.264521)
							(end -0.254 0.2286)
						)
						(arc
							(start -0.254 -0.2286)
							(mid -0.239121 -0.264521)
							(end -0.2032 -0.2794)
						)
						(arc
							(start 0.2032 -0.2794)
							(mid 0.239121 -0.264521)
							(end 0.254 -0.2286)
						)
						(arc
							(start 0.254 0.2286)
							(mid 0.239121 0.264521)
							(end 0.2032 0.2794)
						)
					)
					(width 0)
					(fill yes)
				)
			)
		)
	)
	(footprint ""
		(layer "B.Cu")
		(at 99.06 -41.5544)
		(property "Reference" "C169"
			(at 0 0 0)
			(layer "B.SilkS")
			(hide yes)
			(effects
				(font
					(size 1.27 1.27)
				)
				(justify mirror)
			)
		)
		(property "Value" "SC1U10V2KX-1GP"
			(at -1.1811 -2.7051 0)
			(unlocked yes)
			(layer "B.Fab")
			(hide yes)
			(effects
				(font
					(size 1.016 1.016)
					(thickness 0.1524)
				)
				(justify mirror)
			)
		)
		(property "Device Type" "C402H22"
			(at -1.1811 -4.2291 0)
			(unlocked yes)
			(layer "B.Fab")
			(hide yes)
			(effects
				(font
					(size 1.016 1.016)
					(thickness 0.1524)
				)
				(justify mirror)
			)
		)
		(duplicate_pad_numbers_are_jumpers no)
		(fp_rect
			(start 0.381 0.7366)
			(end -0.381 -0.7366)
			(stroke
				(width 0)
				(type default)
			)
			(fill no)
			(layer "B.CrtYd")
		)
		(fp_rect
			(start 0.381 0.7366)
			(end -0.381 -0.7366)
			(stroke
				(width 0)
				(type default)
			)
			(fill no)
			(layer "B.Fab")
		)
		(pad "1" smd custom
			(at 0 -0.4572 180)
			(size 0.1143 0.1143)
			(layers "B.Cu" "B.Mask" "B.Paste")
			(net "PVNN")
			(options
				(clearance outline)
				(anchor circle)
			)
			(primitives
				(gr_poly
					(pts
						(arc
							(start -0.254 0.1778)
							(mid -0.239121 0.213721)
							(end -0.2032 0.2286)
						)
						(arc
							(start 0.2032 0.2286)
							(mid 0.239121 0.213721)
							(end 0.254 0.1778)
						)
						(arc
							(start 0.254 -0.1778)
							(mid 0.239121 -0.213721)
							(end 0.2032 -0.2286)
						)
						(arc
							(start -0.2032 -0.2286)
							(mid -0.239121 -0.213721)
							(end -0.254 -0.1778)
						)
					)
					(width 0)
					(fill yes)
				)
			)
		)
		(pad "2" smd custom
			(at 0 0.4572 180)
			(size 0.1143 0.1143)
			(layers "B.Cu" "B.Mask" "B.Paste")
			(net "GND")
			(options
				(clearance outline)
				(anchor circle)
			)
			(primitives
				(gr_poly
					(pts
						(arc
							(start -0.254 0.1778)
							(mid -0.239121 0.213721)
							(end -0.2032 0.2286)
						)
						(arc
							(start 0.2032 0.2286)
							(mid 0.239121 0.213721)
							(end 0.254 0.1778)
						)
						(arc
							(start 0.254 -0.1778)
							(mid 0.239121 -0.213721)
							(end 0.2032 -0.2286)
						)
						(arc
							(start -0.2032 -0.2286)
							(mid -0.239121 -0.213721)
							(end -0.254 -0.1778)
						)
					)
					(width 0)
					(fill yes)
				)
			)
		)
	)
	(footprint ""
		(layer "B.Cu")
		(at 18.5928 -60.6298 90)
		(property "Reference" "PR14"
			(at 0 0 90)
			(layer "B.SilkS")
			(hide yes)
			(effects
				(font
					(size 1.27 1.27)
				)
				(justify mirror)
			)
		)
		(property "Value" "1K5R2F-2-GP"
			(at -1.7907 -1.1176 90)
			(unlocked yes)
			(layer "B.Fab")
			(hide yes)
			(effects
				(font
					(size 1.016 1.016)
					(thickness 0.1524)
				)
				(justify mirror)
			)
		)
		(property "Device Type" "R402H16"
			(at -1.7907 -2.6416 90)
			(unlocked yes)
			(layer "B.Fab")
			(hide yes)
			(effects
				(font
					(size 1.016 1.016)
					(thickness 0.1524)
				)
				(justify mirror)
			)
		)
		(duplicate_pad_numbers_are_jumpers no)
		(fp_rect
			(start 0.381 0.8382)
			(end -0.381 -0.8382)
			(stroke
				(width 0)
				(type default)
			)
			(fill no)
			(layer "B.CrtYd")
		)
		(fp_rect
			(start 0.381 0.8382)
			(end -0.381 -0.8382)
			(stroke
				(width 0)
				(type default)
			)
			(fill no)
			(layer "B.Fab")
		)
		(pad "1" smd custom
			(at 0 -0.4318 270)
			(size 0.127 0.127)
			(layers "B.Cu" "B.Mask" "B.Paste")
			(net "VR_PVNN_COMP_RC")
			(options
				(clearance outline)
				(anchor circle)
			)
			(primitives
				(gr_poly
					(pts
						(arc
							(start -0.2032 0.2794)
							(mid -0.239121 0.264521)
							(end -0.254 0.2286)
						)
						(arc
							(start -0.254 -0.2286)
							(mid -0.239121 -0.264521)
							(end -0.2032 -0.2794)
						)
						(arc
							(start 0.2032 -0.2794)
							(mid 0.239121 -0.264521)
							(end 0.254 -0.2286)
						)
						(arc
							(start 0.254 0.2286)
							(mid 0.239121 0.264521)
							(end 0.2032 0.2794)
						)
					)
					(width 0)
					(fill yes)
				)
			)
		)
		(pad "2" smd custom
			(at 0 0.4318 270)
			(size 0.127 0.127)
			(layers "B.Cu" "B.Mask" "B.Paste")
			(net "VR_PVNN_FB")
			(options
				(clearance outline)
				(anchor circle)
			)
			(primitives
				(gr_poly
					(pts
						(arc
							(start -0.2032 0.2794)
							(mid -0.239121 0.264521)
							(end -0.254 0.2286)
						)
						(arc
							(start -0.254 -0.2286)
							(mid -0.239121 -0.264521)
							(end -0.2032 -0.2794)
						)
						(arc
							(start 0.2032 -0.2794)
							(mid 0.239121 -0.264521)
							(end 0.254 -0.2286)
						)
						(arc
							(start 0.254 0.2286)
							(mid 0.239121 0.264521)
							(end 0.2032 0.2794)
						)
					)
					(width 0)
					(fill yes)
				)
			)
		)
	)
	(footprint ""
		(layer "B.Cu")
		(at 103.3018 -44.720002 90)
		(property "Reference" "C153"
			(at 0 0 90)
			(layer "B.SilkS")
			(hide yes)
			(effects
				(font
					(size 1.27 1.27)
				)
				(justify mirror)
			)
		)
		(property "Value" "SC1U10V2KX-1GP"
			(at -1.1811 -2.7051 90)
			(unlocked yes)
			(layer "B.Fab")
			(hide yes)
			(effects
				(font
					(size 1.016 1.016)
					(thickness 0.1524)
				)
				(justify mirror)
			)
		)
		(property "Device Type" "C402H22"
			(at -1.1811 -4.2291 90)
			(unlocked yes)
			(layer "B.Fab")
			(hide yes)
			(effects
				(font
					(size 1.016 1.016)
					(thickness 0.1524)
				)
				(justify mirror)
			)
		)
		(duplicate_pad_numbers_are_jumpers no)
		(fp_rect
			(start 0.381 0.7366)
			(end -0.381 -0.7366)
			(stroke
				(width 0)
				(type default)
			)
			(fill no)
			(layer "B.CrtYd")
		)
		(fp_rect
			(start 0.381 0.7366)
			(end -0.381 -0.7366)
			(stroke
				(width 0)
				(type default)
			)
			(fill no)
			(layer "B.Fab")
		)
		(pad "1" smd custom
			(at 0 -0.4572 270)
			(size 0.1143 0.1143)
			(layers "B.Cu" "B.Mask" "B.Paste")
			(net "P1V0")
			(options
				(clearance outline)
				(anchor circle)
			)
			(primitives
				(gr_poly
					(pts
						(arc
							(start -0.254 0.1778)
							(mid -0.239121 0.213721)
							(end -0.2032 0.2286)
						)
						(arc
							(start 0.2032 0.2286)
							(mid 0.239121 0.213721)
							(end 0.254 0.1778)
						)
						(arc
							(start 0.254 -0.1778)
							(mid 0.239121 -0.213721)
							(end 0.2032 -0.2286)
						)
						(arc
							(start -0.2032 -0.2286)
							(mid -0.239121 -0.213721)
							(end -0.254 -0.1778)
						)
					)
					(width 0)
					(fill yes)
				)
			)
		)
		(pad "2" smd custom
			(at 0 0.4572 270)
			(size 0.1143 0.1143)
			(layers "B.Cu" "B.Mask" "B.Paste")
			(net "GND")
			(options
				(clearance outline)
				(anchor circle)
			)
			(primitives
				(gr_poly
					(pts
						(arc
							(start -0.254 0.1778)
							(mid -0.239121 0.213721)
							(end -0.2032 0.2286)
						)
						(arc
							(start 0.2032 0.2286)
							(mid 0.239121 0.213721)
							(end 0.254 0.1778)
						)
						(arc
							(start 0.254 -0.1778)
							(mid 0.239121 -0.213721)
							(end 0.2032 -0.2286)
						)
						(arc
							(start -0.2032 -0.2286)
							(mid -0.239121 -0.213721)
							(end -0.254 -0.1778)
						)
					)
					(width 0)
					(fill yes)
				)
			)
		)
	)
	(footprint ""
		(layer "B.Cu")
		(at 103.251 -34.814002 90)
		(property "Reference" "C210"
			(at 0 0 90)
			(layer "B.SilkS")
			(hide yes)
			(effects
				(font
					(size 1.27 1.27)
				)
				(justify mirror)
			)
		)
		(property "Value" "SC2D2U10V2KX-GP"
			(at -1.1811 -2.7051 90)
			(unlocked yes)
			(layer "B.Fab")
			(hide yes)
			(effects
				(font
					(size 1.016 1.016)
					(thickness 0.1524)
				)
				(justify mirror)
			)
		)
		(property "Device Type" "C402H22"
			(at -1.1811 -4.2291 90)
			(unlocked yes)
			(layer "B.Fab")
			(hide yes)
			(effects
				(font
					(size 1.016 1.016)
					(thickness 0.1524)
				)
				(justify mirror)
			)
		)
		(duplicate_pad_numbers_are_jumpers no)
		(fp_rect
			(start 0.381 0.7366)
			(end -0.381 -0.7366)
			(stroke
				(width 0)
				(type default)
			)
			(fill no)
			(layer "B.CrtYd")
		)
		(fp_rect
			(start 0.381 0.7366)
			(end -0.381 -0.7366)
			(stroke
				(width 0)
				(type default)
			)
			(fill no)
			(layer "B.Fab")
		)
		(pad "1" smd custom
			(at 0 -0.4572 270)
			(size 0.1143 0.1143)
			(layers "B.Cu" "B.Mask" "B.Paste")
			(net "P1V0")
			(options
				(clearance outline)
				(anchor circle)
			)
			(primitives
				(gr_poly
					(pts
						(arc
							(start -0.254 0.1778)
							(mid -0.239121 0.213721)
							(end -0.2032 0.2286)
						)
						(arc
							(start 0.2032 0.2286)
							(mid 0.239121 0.213721)
							(end 0.254 0.1778)
						)
						(arc
							(start 0.254 -0.1778)
							(mid 0.239121 -0.213721)
							(end 0.2032 -0.2286)
						)
						(arc
							(start -0.2032 -0.2286)
							(mid -0.239121 -0.213721)
							(end -0.254 -0.1778)
						)
					)
					(width 0)
					(fill yes)
				)
			)
		)
		(pad "2" smd custom
			(at 0 0.4572 270)
			(size 0.1143 0.1143)
			(layers "B.Cu" "B.Mask" "B.Paste")
			(net "GND")
			(options
				(clearance outline)
				(anchor circle)
			)
			(primitives
				(gr_poly
					(pts
						(arc
							(start -0.254 0.1778)
							(mid -0.239121 0.213721)
							(end -0.2032 0.2286)
						)
						(arc
							(start 0.2032 0.2286)
							(mid 0.239121 0.213721)
							(end 0.254 0.1778)
						)
						(arc
							(start 0.254 -0.1778)
							(mid 0.239121 -0.213721)
							(end 0.2032 -0.2286)
						)
						(arc
							(start -0.2032 -0.2286)
							(mid -0.239121 -0.213721)
							(end -0.254 -0.1778)
						)
					)
					(width 0)
					(fill yes)
				)
			)
		)
	)
	(footprint ""
		(layer "B.Cu")
		(at 38.735 -41.148 -90)
		(property "Reference" "R14"
			(at 0 0 90)
			(layer "B.SilkS")
			(hide yes)
			(effects
				(font
					(size 1.27 1.27)
				)
				(justify mirror)
			)
		)
		(property "Value" "1KR2F-3-GP"
			(at -0.064008 -3.993896 270)
			(unlocked yes)
			(layer "B.Fab")
			(hide yes)
			(effects
				(font
					(size 1.016 1.016)
					(thickness 0.1524)
				)
				(justify mirror)
			)
		)
		(property "Device Type" "R402H16"
			(at -0.064008 -5.517896 270)
			(unlocked yes)
			(layer "B.Fab")
			(hide yes)
			(effects
				(font
					(size 1.016 1.016)
					(thickness 0.1524)
				)
				(justify mirror)
			)
		)
		(duplicate_pad_numbers_are_jumpers no)
		(fp_rect
			(start 0.381 0.8382)
			(end -0.381 -0.8382)
			(stroke
				(width 0)
				(type default)
			)
			(fill no)
			(layer "B.CrtYd")
		)
		(fp_rect
			(start 0.381 0.8382)
			(end -0.381 -0.8382)
			(stroke
				(width 0)
				(type default)
			)
			(fill no)
			(layer "B.Fab")
		)
		(pad "1" smd custom
			(at 0 -0.4318 90)
			(size 0.127 0.127)
			(layers "B.Cu" "B.Mask" "B.Paste")
			(net "P3V3")
			(options
				(clearance outline)
				(anchor circle)
			)
			(primitives
				(gr_poly
					(pts
						(arc
							(start -0.2032 0.2794)
							(mid -0.239121 0.264521)
							(end -0.254 0.2286)
						)
						(arc
							(start -0.254 -0.2286)
							(mid -0.239121 -0.264521)
							(end -0.2032 -0.2794)
						)
						(arc
							(start 0.2032 -0.2794)
							(mid 0.239121 -0.264521)
							(end 0.254 -0.2286)
						)
						(arc
							(start 0.254 0.2286)
							(mid 0.239121 0.264521)
							(end 0.2032 0.2794)
						)
					)
					(width 0)
					(fill yes)
				)
			)
		)
		(pad "2" smd custom
			(at 0 0.4318 90)
			(size 0.127 0.127)
			(layers "B.Cu" "B.Mask" "B.Paste")
			(net "CORE_PWROK")
			(options
				(clearance outline)
				(anchor circle)
			)
			(primitives
				(gr_poly
					(pts
						(arc
							(start -0.2032 0.2794)
							(mid -0.239121 0.264521)
							(end -0.254 0.2286)
						)
						(arc
							(start -0.254 -0.2286)
							(mid -0.239121 -0.264521)
							(end -0.2032 -0.2794)
						)
						(arc
							(start 0.2032 -0.2794)
							(mid 0.239121 -0.264521)
							(end 0.254 -0.2286)
						)
						(arc
							(start 0.254 0.2286)
							(mid 0.239121 0.264521)
							(end 0.2032 0.2794)
						)
					)
					(width 0)
					(fill yes)
				)
			)
		)
	)
	(footprint ""
		(layer "B.Cu")
		(at 159.999934 -5.790692)
		(property "Reference" "DIMM3"
			(at 0 0 0)
			(layer "B.SilkS")
			(hide yes)
			(effects
				(font
					(size 1.27 1.27)
				)
				(justify mirror)
			)
		)
		(property "Value" "DDR3-204P-142-COLAY-1-GP-U"
			(at 41.312338 -16.676878 0)
			(unlocked yes)
			(layer "B.Fab")
			(hide yes)
			(effects
				(font
					(size 1.016 1.016)
					(thickness 0.1524)
				)
				(justify mirror)
			)
		)
		(property "Device Type" "AS0A626-J8R6-7H-COLAY-1"
			(at 41.312338 -18.200878 0)
			(unlocked yes)
			(layer "B.Fab")
			(hide yes)
			(effects
				(font
					(size 1.016 1.016)
					(thickness 0.1524)
				)
				(justify mirror)
			)
		)
		(duplicate_pad_numbers_are_jumpers no)
		(fp_line
			(start -39.9542 -14.5542)
			(end -39.9542 -9.4488)
			(stroke
				(width 0.1524)
				(type default)
			)
			(layer "B.SilkS")
		)
		(fp_line
			(start -39.9542 -9.4488)
			(end -37.7571 -9.4488)
			(stroke
				(width 0.1524)
				(type default)
			)
			(layer "B.SilkS")
		)
		(fp_line
			(start -38.630606 -23.749)
			(end -38.630606 -14.5542)
			(stroke
				(width 0.1524)
				(type default)
			)
			(layer "B.SilkS")
		)
		(fp_line
			(start -38.630606 -14.5542)
			(end -39.9542 -14.5542)
			(stroke
				(width 0.1524)
				(type default)
			)
			(layer "B.SilkS")
		)
		(fp_line
			(start -37.7571 -9.4488)
			(end -37.7571 -1.7526)
			(stroke
				(width 0.1524)
				(type default)
			)
			(layer "B.SilkS")
		)
		(fp_line
			(start -37.7571 -1.7526)
			(end -37.2491 -1.7526)
			(stroke
				(width 0.1524)
				(type default)
			)
			(layer "B.SilkS")
		)
		(fp_line
			(start -37.2491 -1.7526)
			(end -37.2491 0.254)
			(stroke
				(width 0.1524)
				(type default)
			)
			(layer "B.SilkS")
		)
		(fp_line
			(start -37.2491 0.254)
			(end -36.2585 0.254)
			(stroke
				(width 0.1524)
				(type default)
			)
			(layer "B.SilkS")
		)
		(fp_line
			(start -36.2585 0.254)
			(end -36.2585 5.2578)
			(stroke
				(width 0.1524)
				(type default)
			)
			(layer "B.SilkS")
		)
		(fp_line
			(start -36.2585 5.2578)
			(end 36.2585 5.2578)
			(stroke
				(width 0.1524)
				(type default)
			)
			(layer "B.SilkS")
		)
		(fp_line
			(start -32.0675 -5.9055)
			(end -31.5595 -5.3975)
			(stroke
				(width 0.1524)
				(type default)
			)
			(layer "B.SilkS")
		)
		(fp_line
			(start -31.8516 -23.749)
			(end -38.630606 -23.749)
			(stroke
				(width 0.1524)
				(type default)
			)
			(layer "B.SilkS")
		)
		(fp_line
			(start -31.8516 -21.3614)
			(end -31.8516 -23.749)
			(stroke
				(width 0.1524)
				(type default)
			)
			(layer "B.SilkS")
		)
		(fp_line
			(start -31.5595 -6.4135)
			(end -31.5595 -5.3975)
			(stroke
				(width 0.1524)
				(type default)
			)
			(layer "B.SilkS")
		)
		(fp_line
			(start -31.5595 -5.3975)
			(end -31.0515 -5.9055)
			(stroke
				(width 0.1524)
				(type default)
			)
			(layer "B.SilkS")
		)
		(fp_line
			(start -31.3436 -21.3614)
			(end -31.8516 -21.3614)
			(stroke
				(width 0.1524)
				(type default)
			)
			(layer "B.SilkS")
		)
		(fp_line
			(start -31.3436 -14.5542)
			(end -31.3436 -21.3614)
			(stroke
				(width 0.1524)
				(type default)
			)
			(layer "B.SilkS")
		)
		(fp_line
			(start -31.3436 -9.4488)
			(end -30.7975 -9.4488)
			(stroke
				(width 0.1524)
				(type default)
			)
			(layer "B.SilkS")
		)
		(fp_line
			(start -31.3436 -5.2578)
			(end -31.3436 -9.4488)
			(stroke
				(width 0.1524)
				(type default)
			)
			(layer "B.SilkS")
		)
		(fp_line
			(start -31.0515 -5.9055)
			(end -32.0675 -5.9055)
			(stroke
				(width 0.1524)
				(type default)
			)
			(layer "B.SilkS")
		)
		(fp_line
			(start -30.7975 -14.5542)
			(end -31.3436 -14.5542)
			(stroke
				(width 0.1524)
				(type default)
			)
			(layer "B.SilkS")
		)
		(fp_line
			(start -30.7975 -9.4488)
			(end -30.7975 -14.5542)
			(stroke
				(width 0.1524)
				(type default)
			)
			(layer "B.SilkS")
		)
		(fp_line
			(start 30.7975 -14.5542)
			(end 30.7975 -9.4488)
			(stroke
				(width 0.1524)
				(type default)
			)
			(layer "B.SilkS")
		)
		(fp_line
			(start 30.7975 -9.4488)
			(end 31.3436 -9.4488)
			(stroke
				(width 0.1524)
				(type default)
			)
			(layer "B.SilkS")
		)
		(fp_line
			(start 31.3436 -21.3614)
			(end 31.3436 -14.5542)
			(stroke
				(width 0.1524)
				(type default)
			)
			(layer "B.SilkS")
		)
		(fp_line
			(start 31.3436 -14.5542)
			(end 30.7975 -14.5542)
			(stroke
				(width 0.1524)
				(type default)
			)
			(layer "B.SilkS")
		)
		(fp_line
			(start 31.3436 -9.4488)
			(end 31.3436 -5.2578)
			(stroke
				(width 0.1524)
				(type default)
			)
			(layer "B.SilkS")
		)
		(fp_line
			(start 31.3436 -5.2578)
			(end -31.3436 -5.2578)
			(stroke
				(width 0.1524)
				(type default)
			)
			(layer "B.SilkS")
		)
		(fp_line
			(start 31.581598 5.608828)
			(end 32.089598 5.100828)
			(stroke
				(width 0.1524)
				(type default)
			)
			(layer "B.SilkS")
		)
		(fp_line
			(start 31.8516 -23.749)
			(end 31.8516 -21.3614)
			(stroke
				(width 0.1524)
				(type default)
			)
			(layer "B.SilkS")
		)
		(fp_line
			(start 31.8516 -21.3614)
			(end 31.3436 -21.3614)
			(stroke
				(width 0.1524)
				(type default)
			)
			(layer "B.SilkS")
		)
		(fp_line
			(start 32.089598 5.100828)
			(end 32.597598 5.608828)
			(stroke
				(width 0.1524)
				(type default)
			)
			(layer "B.SilkS")
		)
		(fp_line
			(start 32.089598 6.116828)
			(end 32.089598 5.100828)
			(stroke
				(width 0.1524)
				(type default)
			)
			(layer "B.SilkS")
		)
		(fp_line
			(start 32.597598 5.608828)
			(end 31.581598 5.608828)
			(stroke
				(width 0.1524)
				(type default)
			)
			(layer "B.SilkS")
		)
		(fp_line
			(start 36.2585 0.254)
			(end 37.2491 0.254)
			(stroke
				(width 0.1524)
				(type default)
			)
			(layer "B.SilkS")
		)
		(fp_line
			(start 36.2585 5.2578)
			(end 36.2585 0.254)
			(stroke
				(width 0.1524)
				(type default)
			)
			(layer "B.SilkS")
		)
		(fp_line
			(start 37.2491 -1.7526)
			(end 37.7571 -1.7526)
			(stroke
				(width 0.1524)
				(type default)
			)
			(layer "B.SilkS")
		)
		(fp_line
			(start 37.2491 0.254)
			(end 37.2491 -1.7526)
			(stroke
				(width 0.1524)
				(type default)
			)
			(layer "B.SilkS")
		)
		(fp_line
			(start 37.7571 -9.4488)
			(end 39.9542 -9.4488)
			(stroke
				(width 0.1524)
				(type default)
			)
			(layer "B.SilkS")
		)
		(fp_line
			(start 37.7571 -1.7526)
			(end 37.7571 -9.4488)
			(stroke
				(width 0.1524)
				(type default)
			)
			(layer "B.SilkS")
		)
		(fp_line
			(start 38.630606 -23.749)
			(end 31.8516 -23.749)
			(stroke
				(width 0.1524)
				(type default)
			)
			(layer "B.SilkS")
		)
		(fp_line
			(start 38.630606 -14.5542)
			(end 38.630606 -23.749)
			(stroke
				(width 0.1524)
				(type default)
			)
			(layer "B.SilkS")
		)
		(fp_line
			(start 39.9542 -14.5542)
			(end 38.630606 -14.5542)
			(stroke
				(width 0.1524)
				(type default)
			)
			(layer "B.SilkS")
		)
		(fp_line
			(start 39.9542 -9.4488)
			(end 39.9542 -14.5542)
			(stroke
				(width 0.1524)
				(type default)
			)
			(layer "B.SilkS")
		)
		(fp_poly
			(pts
				(xy 32.536384 -2.995168) (xy 32.536384 2.995168) (xy -32.295084 2.995168) (xy -32.295084 -2.995168)
			)
			(stroke
				(width 0)
				(type default)
			)
			(fill yes)
			(layer "B.SilkS")
		)
		(fp_poly
			(pts
				(xy 36.2585 5.2578) (xy 36.2585 0.254) (xy 37.2491 0.254) (xy 37.2491 -1.7526) (xy 37.7571 -1.7526)
				(xy 37.7571 -9.4488) (xy 39.9542 -9.4488) (xy 39.9542 -14.5542) (xy 38.630606 -14.5542) (xy 38.630606 -23.749)
				(xy 31.8516 -23.749) (xy 31.8516 -21.3614) (xy 31.3436 -21.3614) (xy 31.3436 -14.5542) (xy 30.7975 -14.5542)
				(xy 30.7975 -9.4488) (xy 31.3436 -9.4488) (xy 31.3436 -5.2578) (xy -31.3436 -5.2578) (xy -31.3436 -9.4488)
				(xy -30.7975 -9.4488) (xy -30.7975 -14.5542) (xy -31.3436 -14.5542) (xy -31.3436 -21.3614) (xy -31.8516 -21.3614)
				(xy -31.8516 -23.749) (xy -38.630606 -23.749) (xy -38.630606 -14.5542) (xy -39.9542 -14.5542) (xy -39.9542 -9.4488)
				(xy -37.7571 -9.4488) (xy -37.7571 -1.7526) (xy -37.2491 -1.7526) (xy -37.2491 0.254) (xy -36.2585 0.254)
				(xy -36.2585 5.2578)
			)
			(stroke
				(width 0)
				(type default)
			)
			(fill no)
			(layer "B.CrtYd")
		)
		(fp_poly
			(pts
				(xy 36.2585 5.2578) (xy 36.2585 0.254) (xy 37.2491 0.254) (xy 37.2491 -1.7526) (xy 37.7571 -1.7526)
				(xy 37.7571 -9.4488) (xy 39.9542 -9.4488) (xy 39.9542 -14.5542) (xy 38.630606 -14.5542) (xy 38.630606 -23.749)
				(xy 31.8516 -23.749) (xy 31.8516 -21.3614) (xy 31.3436 -21.3614) (xy 31.3436 -14.5542) (xy 30.7975 -14.5542)
				(xy 30.7975 -9.4488) (xy 31.3436 -9.4488) (xy 31.3436 -5.2578) (xy -31.3436 -5.2578) (xy -31.3436 -9.4488)
				(xy -30.7975 -9.4488) (xy -30.7975 -14.5542) (xy -31.3436 -14.5542) (xy -31.3436 -21.3614) (xy -31.8516 -21.3614)
				(xy -31.8516 -23.749) (xy -38.630606 -23.749) (xy -38.630606 -14.5542) (xy -39.9542 -14.5542) (xy -39.9542 -9.4488)
				(xy -37.7571 -9.4488) (xy -37.7571 -1.7526) (xy -37.2491 -1.7526) (xy -37.2491 0.254) (xy -36.2585 0.254)
				(xy -36.2585 5.2578)
			)
			(stroke
				(width 0)
				(type default)
			)
			(fill no)
			(layer "B.Fab")
		)
		(fp_text user "1"
			(at -30.586934 -7.957058 0)
			(unlocked yes)
			(layer "B.SilkS")
			(effects
				(font
					(size 0.635 0.635)
					(thickness 0.1524)
				)
				(justify left mirror)
			)
		)
		(fp_text user "204"
			(at 34.437066 4.615942 0)
			(unlocked yes)
			(layer "B.SilkS")
			(effects
				(font
					(size 0.635 0.635)
					(thickness 0.1524)
				)
				(justify left mirror)
			)
		)
		(pad "" np_thru_hole circle
			(at -33.399984 0 180)
			(size 0.254 0.254)
			(drill 1.6002)
			(layers "*.Cu" "*.Mask")
			(clearance 1.0287)
			(thermal_gap 1.0287)
		)
		(pad "" np_thru_hole circle
			(at 33.399984 0 180)
			(size 0.254 0.254)
			(drill 1.1176)
			(layers "*.Cu" "*.Mask")
			(clearance 0.7874)
			(thermal_gap 0.7874)
		)
		(pad "1" smd custom
			(at -31.649924 -4.100068 180)
			(size 0.1143 0.1143)
			(layers "B.Cu" "B.Mask" "B.Paste")
			(net "DDR3_M_B_VREF_DQ0")
			(options
				(clearance outline)
				(anchor circle)
			)
			(primitives
				(gr_poly
					(pts
						(xy 0 -0.9017) (xy -0.03175 -0.89916) (xy -0.0635 -0.889) (xy -0.09144 -0.87376) (xy -0.11684 -0.85344)
						(xy -0.13716 -0.82804) (xy -0.1524 -0.8001) (xy -0.16256 -0.76835) (xy -0.1651 -0.7366) (xy -0.1651 -0.44958)
						(xy -0.17272 -0.44196) (xy -0.19812 -0.4064) (xy -0.2032 -0.39624) (xy -0.20701 -0.38735) (xy -0.21209 -0.37719)
						(xy -0.2159 -0.36703) (xy -0.21844 -0.35687) (xy -0.22225 -0.34544) (xy -0.22352 -0.33528) (xy -0.22606 -0.32512)
						(xy -0.22733 -0.31369) (xy -0.22733 -0.30353) (xy -0.2286 -0.2921) (xy -0.22733 -0.28067) (xy -0.22733 -0.27051)
						(xy -0.22606 -0.25908) (xy -0.22352 -0.24892) (xy -0.22225 -0.23876) (xy -0.21844 -0.22733) (xy -0.2159 -0.21717)
						(xy -0.21209 -0.20701) (xy -0.20701 -0.19685) (xy -0.2032 -0.18796) (xy -0.19812 -0.1778) (xy -0.17272 -0.14224)
						(xy -0.1651 -0.13462) (xy -0.1651 0.7366) (xy -0.16256 0.76835) (xy -0.1524 0.8001) (xy -0.13716 0.82804)
						(xy -0.11684 0.85344) (xy -0.09144 0.87376) (xy -0.0635 0.889) (xy -0.03175 0.89916) (xy 0 0.9017)
						(xy 0.03175 0.89916) (xy 0.0635 0.889) (xy 0.09144 0.87376) (xy 0.11684 0.85344) (xy 0.13716 0.82804)
						(xy 0.1524 0.8001) (xy 0.16256 0.76835) (xy 0.1651 0.7366) (xy 0.1651 -0.13462) (xy 0.17272 -0.14224)
						(xy 0.19812 -0.1778) (xy 0.2032 -0.18796) (xy 0.20701 -0.19685) (xy 0.21209 -0.20701) (xy 0.2159 -0.21717)
						(xy 0.21844 -0.22733) (xy 0.22225 -0.23876) (xy 0.22352 -0.24892) (xy 0.22606 -0.25908) (xy 0.22733 -0.27051)
						(xy 0.22733 -0.28067) (xy 0.2286 -0.2921) (xy 0.22733 -0.30353) (xy 0.22733 -0.31369) (xy 0.22606 -0.32512)
						(xy 0.22352 -0.33528) (xy 0.22225 -0.34544) (xy 0.21844 -0.35687) (xy 0.2159 -0.36703) (xy 0.21209 -0.37719)
						(xy 0.20701 -0.38735) (xy 0.2032 -0.39624) (xy 0.19812 -0.4064) (xy 0.17272 -0.44196) (xy 0.1651 -0.44958)
						(xy 0.1651 -0.7366) (xy 0.16256 -0.76835) (xy 0.1524 -0.8001) (xy 0.13716 -0.82804) (xy 0.11684 -0.85344)
						(xy 0.09144 -0.87376) (xy 0.0635 -0.889) (xy 0.03175 -0.89916)
					)
					(width 0)
					(fill yes)
				)
			)
		)
		(pad "2" smd custom
			(at -31.34995 4.100068 180)
			(size 0.1143 0.1143)
			(layers "B.Cu" "B.Mask" "B.Paste")
			(net "GND")
			(options
				(clearance outline)
				(anchor circle)
			)
			(primitives
				(gr_poly
					(pts
						(xy 0 -0.9017) (xy -0.03175 -0.89916) (xy -0.0635 -0.889) (xy -0.09144 -0.87376) (xy -0.11684 -0.85344)
						(xy -0.13716 -0.82804) (xy -0.1524 -0.8001) (xy -0.16256 -0.76835) (xy -0.1651 -0.7366) (xy -0.1651 0.13462)
						(xy -0.17272 0.14224) (xy -0.19812 0.1778) (xy -0.2032 0.18796) (xy -0.20701 0.19685) (xy -0.21209 0.20701)
						(xy -0.2159 0.21717) (xy -0.21844 0.22733) (xy -0.22225 0.23876) (xy -0.22352 0.24892) (xy -0.22606 0.25908)
						(xy -0.22733 0.27051) (xy -0.22733 0.28067) (xy -0.2286 0.2921) (xy -0.22733 0.30353) (xy -0.22733 0.31369)
						(xy -0.22606 0.32512) (xy -0.22352 0.33528) (xy -0.22225 0.34544) (xy -0.21844 0.35687) (xy -0.2159 0.36703)
						(xy -0.21209 0.37719) (xy -0.20701 0.38735) (xy -0.2032 0.39624) (xy -0.19812 0.4064) (xy -0.17272 0.44196)
						(xy -0.1651 0.44958) (xy -0.1651 0.7366) (xy -0.16256 0.76835) (xy -0.1524 0.8001) (xy -0.13716 0.82804)
						(xy -0.11684 0.85344) (xy -0.09144 0.87376) (xy -0.0635 0.889) (xy -0.03175 0.89916) (xy 0 0.9017)
						(xy 0.03175 0.89916) (xy 0.0635 0.889) (xy 0.09144 0.87376) (xy 0.11684 0.85344) (xy 0.13716 0.82804)
						(xy 0.1524 0.8001) (xy 0.16256 0.76835) (xy 0.1651 0.7366) (xy 0.1651 0.44958) (xy 0.17272 0.44196)
						(xy 0.19812 0.4064) (xy 0.2032 0.39624) (xy 0.20701 0.38735) (xy 0.21209 0.37719) (xy 0.2159 0.36703)
						(xy 0.21844 0.35687) (xy 0.22225 0.34544) (xy 0.22352 0.33528) (xy 0.22606 0.32512) (xy 0.22733 0.31369)
						(xy 0.22733 0.30353) (xy 0.2286 0.2921) (xy 0.22733 0.28067) (xy 0.22733 0.27051) (xy 0.22606 0.25908)
						(xy 0.22352 0.24892) (xy 0.22225 0.23876) (xy 0.21844 0.22733) (xy 0.2159 0.21717) (xy 0.21209 0.20701)
						(xy 0.20701 0.19685) (xy 0.2032 0.18796) (xy 0.19812 0.1778) (xy 0.17272 0.14224) (xy 0.1651 0.13462)
						(xy 0.1651 -0.7366) (xy 0.16256 -0.76835) (xy 0.1524 -0.8001) (xy 0.13716 -0.82804) (xy 0.11684 -0.85344)
						(xy 0.09144 -0.87376) (xy 0.0635 -0.889) (xy 0.03175 -0.89916)
					)
					(width 0)
					(fill yes)
				)
			)
		)
		(pad "3" smd custom
			(at -31.049976 -4.100068 180)
			(size 0.1143 0.1143)
			(layers "B.Cu" "B.Mask" "B.Paste")
			(net "GND")
			(options
				(clearance outline)
				(anchor circle)
			)
			(primitives
				(gr_poly
					(pts
						(xy 0 -0.9017) (xy -0.03175 -0.89916) (xy -0.0635 -0.889) (xy -0.09144 -0.87376) (xy -0.11684 -0.85344)
						(xy -0.13716 -0.82804) (xy -0.1524 -0.8001) (xy -0.16256 -0.76835) (xy -0.1651 -0.7366) (xy -0.1651 -0.19685)
						(xy -0.17272 -0.18923) (xy -0.17907 -0.18034) (xy -0.18669 -0.17145) (xy -0.19177 -0.16256) (xy -0.19812 -0.15367)
						(xy -0.20828 -0.13335) (xy -0.21971 -0.10287) (xy -0.22225 -0.09271) (xy -0.22479 -0.08128) (xy -0.22606 -0.07112)
						(xy -0.2286 -0.05969) (xy -0.2286 -0.01651) (xy -0.22606 -0.00508) (xy -0.22479 0.00508) (xy -0.22225 0.01651)
						(xy -0.21971 0.02667) (xy -0.20828 0.05715) (xy -0.19812 0.07747) (xy -0.19177 0.08636) (xy -0.18669 0.09525)
						(xy -0.17907 0.10414) (xy -0.17272 0.11303) (xy -0.1651 0.12065) (xy -0.1651 0.7366) (xy -0.16256 0.76835)
						(xy -0.1524 0.8001) (xy -0.13716 0.82804) (xy -0.11684 0.85344) (xy -0.09144 0.87376) (xy -0.0635 0.889)
						(xy -0.03175 0.89916) (xy 0 0.9017) (xy 0.03175 0.89916) (xy 0.0635 0.889) (xy 0.09144 0.87376)
						(xy 0.11684 0.85344) (xy 0.13716 0.82804) (xy 0.1524 0.8001) (xy 0.16256 0.76835) (xy 0.1651 0.7366)
						(xy 0.1651 0.11938) (xy 0.17272 0.11176) (xy 0.19812 0.0762) (xy 0.2032 0.06604) (xy 0.20701 0.05715)
						(xy 0.21209 0.04699) (xy 0.2159 0.03683) (xy 0.21844 0.02667) (xy 0.22225 0.01524) (xy 0.22352 0.00508)
						(xy 0.22606 -0.00508) (xy 0.22733 -0.01651) (xy 0.22733 -0.02667) (xy 0.2286 -0.0381) (xy 0.22733 -0.04953)
						(xy 0.22733 -0.05969) (xy 0.22606 -0.07112) (xy 0.22352 -0.08128) (xy 0.22225 -0.09144) (xy 0.21844 -0.10287)
						(xy 0.2159 -0.11303) (xy 0.21209 -0.12319) (xy 0.20701 -0.13335) (xy 0.2032 -0.14224) (xy 0.19812 -0.1524)
						(xy 0.17272 -0.18796) (xy 0.1651 -0.19558) (xy 0.1651 -0.7366) (xy 0.16256 -0.76835) (xy 0.1524 -0.8001)
						(xy 0.13716 -0.82804) (xy 0.11684 -0.85344) (xy 0.09144 -0.87376) (xy 0.0635 -0.889) (xy 0.03175 -0.89916)
					)
					(width 0)
					(fill yes)
				)
			)
		)
		(pad "4" smd custom
			(at -30.750002 4.100068 180)
			(size 0.1143 0.1143)
			(layers "B.Cu" "B.Mask" "B.Paste")
			(net "M_B_DQ4")
			(options
				(clearance outline)
				(anchor circle)
			)
			(primitives
				(gr_poly
					(pts
						(xy 0 -0.9017) (xy -0.03175 -0.89916) (xy -0.0635 -0.889) (xy -0.09144 -0.87376) (xy -0.11684 -0.85344)
						(xy -0.13716 -0.82804) (xy -0.1524 -0.8001) (xy -0.16256 -0.76835) (xy -0.1651 -0.7366) (xy -0.1651 -0.11938)
						(xy -0.17272 -0.11176) (xy -0.19812 -0.0762) (xy -0.2032 -0.06604) (xy -0.20701 -0.05715) (xy -0.21209 -0.04699)
						(xy -0.2159 -0.03683) (xy -0.21844 -0.02667) (xy -0.22225 -0.01524) (xy -0.22352 -0.00508) (xy -0.22606 0.00508)
						(xy -0.22733 0.01651) (xy -0.22733 0.02667) (xy -0.2286 0.0381) (xy -0.22733 0.04953) (xy -0.22733 0.05969)
						(xy -0.22606 0.07112) (xy -0.22352 0.08128) (xy -0.22225 0.09144) (xy -0.21844 0.10287) (xy -0.2159 0.11303)
						(xy -0.21209 0.12319) (xy -0.20701 0.13335) (xy -0.2032 0.14224) (xy -0.19812 0.1524) (xy -0.17272 0.18796)
						(xy -0.1651 0.19558) (xy -0.1651 0.7366) (xy -0.16256 0.76835) (xy -0.1524 0.8001) (xy -0.13716 0.82804)
						(xy -0.11684 0.85344) (xy -0.09144 0.87376) (xy -0.0635 0.889) (xy -0.03175 0.89916) (xy 0 0.9017)
						(xy 0.03175 0.89916) (xy 0.0635 0.889) (xy 0.09144 0.87376) (xy 0.11684 0.85344) (xy 0.13716 0.82804)
						(xy 0.1524 0.8001) (xy 0.16256 0.76835) (xy 0.1651 0.7366) (xy 0.1651 0.19685) (xy 0.17272 0.18923)
						(xy 0.17907 0.18034) (xy 0.18669 0.17145) (xy 0.19177 0.16256) (xy 0.19812 0.15367) (xy 0.20828 0.13335)
						(xy 0.21971 0.10287) (xy 0.22225 0.09271) (xy 0.22479 0.08128) (xy 0.22606 0.07112) (xy 0.2286 0.05969)
						(xy 0.2286 0.01651) (xy 0.22606 0.00508) (xy 0.22479 -0.00508) (xy 0.22225 -0.01651) (xy 0.21971 -0.02667)
						(xy 0.20828 -0.05715) (xy 0.19812 -0.07747) (xy 0.19177 -0.08636) (xy 0.18669 -0.09525) (xy 0.17907 -0.10414)
						(xy 0.17272 -0.11303) (xy 0.1651 -0.12065) (xy 0.1651 -0.7366) (xy 0.16256 -0.76835) (xy 0.1524 -0.8001)
						(xy 0.13716 -0.82804) (xy 0.11684 -0.85344) (xy 0.09144 -0.87376) (xy 0.0635 -0.889) (xy 0.03175 -0.89916)
					)
					(width 0)
					(fill yes)
				)
			)
		)
		(pad "5" smd custom
			(at -30.450028 -4.100068 180)
			(size 0.1143 0.1143)
			(layers "B.Cu" "B.Mask" "B.Paste")
			(net "M_B_DQ0")
			(options
				(clearance outline)
				(anchor circle)
			)
			(primitives
				(gr_poly
					(pts
						(xy 0 -0.9017) (xy -0.03175 -0.89916) (xy -0.0635 -0.889) (xy -0.09144 -0.87376) (xy -0.11684 -0.85344)
						(xy -0.13716 -0.82804) (xy -0.1524 -0.8001) (xy -0.16256 -0.76835) (xy -0.1651 -0.7366) (xy -0.1651 -0.44958)
						(xy -0.17272 -0.44196) (xy -0.19812 -0.4064) (xy -0.2032 -0.39624) (xy -0.20701 -0.38735) (xy -0.21209 -0.37719)
						(xy -0.2159 -0.36703) (xy -0.21844 -0.35687) (xy -0.22225 -0.34544) (xy -0.22352 -0.33528) (xy -0.22606 -0.32512)
						(xy -0.22733 -0.31369) (xy -0.22733 -0.30353) (xy -0.2286 -0.2921) (xy -0.22733 -0.28067) (xy -0.22733 -0.27051)
						(xy -0.22606 -0.25908) (xy -0.22352 -0.24892) (xy -0.22225 -0.23876) (xy -0.21844 -0.22733) (xy -0.2159 -0.21717)
						(xy -0.21209 -0.20701) (xy -0.20701 -0.19685) (xy -0.2032 -0.18796) (xy -0.19812 -0.1778) (xy -0.17272 -0.14224)
						(xy -0.1651 -0.13462) (xy -0.1651 0.7366) (xy -0.16256 0.76835) (xy -0.1524 0.8001) (xy -0.13716 0.82804)
						(xy -0.11684 0.85344) (xy -0.09144 0.87376) (xy -0.0635 0.889) (xy -0.03175 0.89916) (xy 0 0.9017)
						(xy 0.03175 0.89916) (xy 0.0635 0.889) (xy 0.09144 0.87376) (xy 0.11684 0.85344) (xy 0.13716 0.82804)
						(xy 0.1524 0.8001) (xy 0.16256 0.76835) (xy 0.1651 0.7366) (xy 0.1651 -0.13462) (xy 0.17272 -0.14224)
						(xy 0.19812 -0.1778) (xy 0.2032 -0.18796) (xy 0.20701 -0.19685) (xy 0.21209 -0.20701) (xy 0.2159 -0.21717)
						(xy 0.21844 -0.22733) (xy 0.22225 -0.23876) (xy 0.22352 -0.24892) (xy 0.22606 -0.25908) (xy 0.22733 -0.27051)
						(xy 0.22733 -0.28067) (xy 0.2286 -0.2921) (xy 0.22733 -0.30353) (xy 0.22733 -0.31369) (xy 0.22606 -0.32512)
						(xy 0.22352 -0.33528) (xy 0.22225 -0.34544) (xy 0.21844 -0.35687) (xy 0.2159 -0.36703) (xy 0.21209 -0.37719)
						(xy 0.20701 -0.38735) (xy 0.2032 -0.39624) (xy 0.19812 -0.4064) (xy 0.17272 -0.44196) (xy 0.1651 -0.44958)
						(xy 0.1651 -0.7366) (xy 0.16256 -0.76835) (xy 0.1524 -0.8001) (xy 0.13716 -0.82804) (xy 0.11684 -0.85344)
						(xy 0.09144 -0.87376) (xy 0.0635 -0.889) (xy 0.03175 -0.89916)
					)
					(width 0)
					(fill yes)
				)
			)
		)
		(pad "6" smd custom
			(at -30.150054 4.100068 180)
			(size 0.1143 0.1143)
			(layers "B.Cu" "B.Mask" "B.Paste")
			(net "M_B_DQ5")
			(options
				(clearance outline)
				(anchor circle)
			)
			(primitives
				(gr_poly
					(pts
						(xy 0 -0.9017) (xy -0.03175 -0.89916) (xy -0.0635 -0.889) (xy -0.09144 -0.87376) (xy -0.11684 -0.85344)
						(xy -0.13716 -0.82804) (xy -0.1524 -0.8001) (xy -0.16256 -0.76835) (xy -0.1651 -0.7366) (xy -0.1651 0.13462)
						(xy -0.17272 0.14224) (xy -0.19812 0.1778) (xy -0.2032 0.18796) (xy -0.20701 0.19685) (xy -0.21209 0.20701)
						(xy -0.2159 0.21717) (xy -0.21844 0.22733) (xy -0.22225 0.23876) (xy -0.22352 0.24892) (xy -0.22606 0.25908)
						(xy -0.22733 0.27051) (xy -0.22733 0.28067) (xy -0.2286 0.2921) (xy -0.22733 0.30353) (xy -0.22733 0.31369)
						(xy -0.22606 0.32512) (xy -0.22352 0.33528) (xy -0.22225 0.34544) (xy -0.21844 0.35687) (xy -0.2159 0.36703)
						(xy -0.21209 0.37719) (xy -0.20701 0.38735) (xy -0.2032 0.39624) (xy -0.19812 0.4064) (xy -0.17272 0.44196)
						(xy -0.1651 0.44958) (xy -0.1651 0.7366) (xy -0.16256 0.76835) (xy -0.1524 0.8001) (xy -0.13716 0.82804)
						(xy -0.11684 0.85344) (xy -0.09144 0.87376) (xy -0.0635 0.889) (xy -0.03175 0.89916) (xy 0 0.9017)
						(xy 0.03175 0.89916) (xy 0.0635 0.889) (xy 0.09144 0.87376) (xy 0.11684 0.85344) (xy 0.13716 0.82804)
						(xy 0.1524 0.8001) (xy 0.16256 0.76835) (xy 0.1651 0.7366) (xy 0.1651 0.44958) (xy 0.17272 0.44196)
						(xy 0.19812 0.4064) (xy 0.2032 0.39624) (xy 0.20701 0.38735) (xy 0.21209 0.37719) (xy 0.2159 0.36703)
						(xy 0.21844 0.35687) (xy 0.22225 0.34544) (xy 0.22352 0.33528) (xy 0.22606 0.32512) (xy 0.22733 0.31369)
						(xy 0.22733 0.30353) (xy 0.2286 0.2921) (xy 0.22733 0.28067) (xy 0.22733 0.27051) (xy 0.22606 0.25908)
						(xy 0.22352 0.24892) (xy 0.22225 0.23876) (xy 0.21844 0.22733) (xy 0.2159 0.21717) (xy 0.21209 0.20701)
						(xy 0.20701 0.19685) (xy 0.2032 0.18796) (xy 0.19812 0.1778) (xy 0.17272 0.14224) (xy 0.1651 0.13462)
						(xy 0.1651 -0.7366) (xy 0.16256 -0.76835) (xy 0.1524 -0.8001) (xy 0.13716 -0.82804) (xy 0.11684 -0.85344)
						(xy 0.09144 -0.87376) (xy 0.0635 -0.889) (xy 0.03175 -0.89916)
					)
					(width 0)
					(fill yes)
				)
			)
		)
		(pad "7" smd custom
			(at -29.85008 -4.100068 180)
			(size 0.1143 0.1143)
			(layers "B.Cu" "B.Mask" "B.Paste")
			(net "M_B_DQ1")
			(options
				(clearance outline)
				(anchor circle)
			)
			(primitives
				(gr_poly
					(pts
						(xy 0 -0.9017) (xy -0.03175 -0.89916) (xy -0.0635 -0.889) (xy -0.09144 -0.87376) (xy -0.11684 -0.85344)
						(xy -0.13716 -0.82804) (xy -0.1524 -0.8001) (xy -0.16256 -0.76835) (xy -0.1651 -0.7366) (xy -0.1651 -0.19685)
						(xy -0.17272 -0.18923) (xy -0.17907 -0.18034) (xy -0.18669 -0.17145) (xy -0.19177 -0.16256) (xy -0.19812 -0.15367)
						(xy -0.20828 -0.13335) (xy -0.21971 -0.10287) (xy -0.22225 -0.09271) (xy -0.22479 -0.08128) (xy -0.22606 -0.07112)
						(xy -0.2286 -0.05969) (xy -0.2286 -0.01651) (xy -0.22606 -0.00508) (xy -0.22479 0.00508) (xy -0.22225 0.01651)
						(xy -0.21971 0.02667) (xy -0.20828 0.05715) (xy -0.19812 0.07747) (xy -0.19177 0.08636) (xy -0.18669 0.09525)
						(xy -0.17907 0.10414) (xy -0.17272 0.11303) (xy -0.1651 0.12065) (xy -0.1651 0.7366) (xy -0.16256 0.76835)
						(xy -0.1524 0.8001) (xy -0.13716 0.82804) (xy -0.11684 0.85344) (xy -0.09144 0.87376) (xy -0.0635 0.889)
						(xy -0.03175 0.89916) (xy 0 0.9017) (xy 0.03175 0.89916) (xy 0.0635 0.889) (xy 0.09144 0.87376)
						(xy 0.11684 0.85344) (xy 0.13716 0.82804) (xy 0.1524 0.8001) (xy 0.16256 0.76835) (xy 0.1651 0.7366)
						(xy 0.1651 0.11938) (xy 0.17272 0.11176) (xy 0.19812 0.0762) (xy 0.2032 0.06604) (xy 0.20701 0.05715)
						(xy 0.21209 0.04699) (xy 0.2159 0.03683) (xy 0.21844 0.02667) (xy 0.22225 0.01524) (xy 0.22352 0.00508)
						(xy 0.22606 -0.00508) (xy 0.22733 -0.01651) (xy 0.22733 -0.02667) (xy 0.2286 -0.0381) (xy 0.22733 -0.04953)
						(xy 0.22733 -0.05969) (xy 0.22606 -0.07112) (xy 0.22352 -0.08128) (xy 0.22225 -0.09144) (xy 0.21844 -0.10287)
						(xy 0.2159 -0.11303) (xy 0.21209 -0.12319) (xy 0.20701 -0.13335) (xy 0.2032 -0.14224) (xy 0.19812 -0.1524)
						(xy 0.17272 -0.18796) (xy 0.1651 -0.19558) (xy 0.1651 -0.7366) (xy 0.16256 -0.76835) (xy 0.1524 -0.8001)
						(xy 0.13716 -0.82804) (xy 0.11684 -0.85344) (xy 0.09144 -0.87376) (xy 0.0635 -0.889) (xy 0.03175 -0.89916)
					)
					(width 0)
					(fill yes)
				)
			)
		)
		(pad "8" smd custom
			(at -29.550106 4.100068 180)
			(size 0.1143 0.1143)
			(layers "B.Cu" "B.Mask" "B.Paste")
			(net "GND")
			(options
				(clearance outline)
				(anchor circle)
			)
			(primitives
				(gr_poly
					(pts
						(xy 0 -0.9017) (xy -0.03175 -0.89916) (xy -0.0635 -0.889) (xy -0.09144 -0.87376) (xy -0.11684 -0.85344)
						(xy -0.13716 -0.82804) (xy -0.1524 -0.8001) (xy -0.16256 -0.76835) (xy -0.1651 -0.7366) (xy -0.1651 -0.11938)
						(xy -0.17272 -0.11176) (xy -0.19812 -0.0762) (xy -0.2032 -0.06604) (xy -0.20701 -0.05715) (xy -0.21209 -0.04699)
						(xy -0.2159 -0.03683) (xy -0.21844 -0.02667) (xy -0.22225 -0.01524) (xy -0.22352 -0.00508) (xy -0.22606 0.00508)
						(xy -0.22733 0.01651) (xy -0.22733 0.02667) (xy -0.2286 0.0381) (xy -0.22733 0.04953) (xy -0.22733 0.05969)
						(xy -0.22606 0.07112) (xy -0.22352 0.08128) (xy -0.22225 0.09144) (xy -0.21844 0.10287) (xy -0.2159 0.11303)
						(xy -0.21209 0.12319) (xy -0.20701 0.13335) (xy -0.2032 0.14224) (xy -0.19812 0.1524) (xy -0.17272 0.18796)
						(xy -0.1651 0.19558) (xy -0.1651 0.7366) (xy -0.16256 0.76835) (xy -0.1524 0.8001) (xy -0.13716 0.82804)
						(xy -0.11684 0.85344) (xy -0.09144 0.87376) (xy -0.0635 0.889) (xy -0.03175 0.89916) (xy 0 0.9017)
						(xy 0.03175 0.89916) (xy 0.0635 0.889) (xy 0.09144 0.87376) (xy 0.11684 0.85344) (xy 0.13716 0.82804)
						(xy 0.1524 0.8001) (xy 0.16256 0.76835) (xy 0.1651 0.7366) (xy 0.1651 0.19685) (xy 0.17272 0.18923)
						(xy 0.17907 0.18034) (xy 0.18669 0.17145) (xy 0.19177 0.16256) (xy 0.19812 0.15367) (xy 0.20828 0.13335)
						(xy 0.21971 0.10287) (xy 0.22225 0.09271) (xy 0.22479 0.08128) (xy 0.22606 0.07112) (xy 0.2286 0.05969)
						(xy 0.2286 0.01651) (xy 0.22606 0.00508) (xy 0.22479 -0.00508) (xy 0.22225 -0.01651) (xy 0.21971 -0.02667)
						(xy 0.20828 -0.05715) (xy 0.19812 -0.07747) (xy 0.19177 -0.08636) (xy 0.18669 -0.09525) (xy 0.17907 -0.10414)
						(xy 0.17272 -0.11303) (xy 0.1651 -0.12065) (xy 0.1651 -0.7366) (xy 0.16256 -0.76835) (xy 0.1524 -0.8001)
						(xy 0.13716 -0.82804) (xy 0.11684 -0.85344) (xy 0.09144 -0.87376) (xy 0.0635 -0.889) (xy 0.03175 -0.89916)
					)
					(width 0)
					(fill yes)
				)
			)
		)
		(pad "9" smd custom
			(at -29.249878 -4.100068 180)
			(size 0.1143 0.1143)
			(layers "B.Cu" "B.Mask" "B.Paste")
			(net "GND")
			(options
				(clearance outline)
				(anchor circle)
			)
			(primitives
				(gr_poly
					(pts
						(xy 0 -0.9017) (xy -0.03175 -0.89916) (xy -0.0635 -0.889) (xy -0.09144 -0.87376) (xy -0.11684 -0.85344)
						(xy -0.13716 -0.82804) (xy -0.1524 -0.8001) (xy -0.16256 -0.76835) (xy -0.1651 -0.7366) (xy -0.1651 -0.44958)
						(xy -0.17272 -0.44196) (xy -0.19812 -0.4064) (xy -0.2032 -0.39624) (xy -0.20701 -0.38735) (xy -0.21209 -0.37719)
						(xy -0.2159 -0.36703) (xy -0.21844 -0.35687) (xy -0.22225 -0.34544) (xy -0.22352 -0.33528) (xy -0.22606 -0.32512)
						(xy -0.22733 -0.31369) (xy -0.22733 -0.30353) (xy -0.2286 -0.2921) (xy -0.22733 -0.28067) (xy -0.22733 -0.27051)
						(xy -0.22606 -0.25908) (xy -0.22352 -0.24892) (xy -0.22225 -0.23876) (xy -0.21844 -0.22733) (xy -0.2159 -0.21717)
						(xy -0.21209 -0.20701) (xy -0.20701 -0.19685) (xy -0.2032 -0.18796) (xy -0.19812 -0.1778) (xy -0.17272 -0.14224)
						(xy -0.1651 -0.13462) (xy -0.1651 0.7366) (xy -0.16256 0.76835) (xy -0.1524 0.8001) (xy -0.13716 0.82804)
						(xy -0.11684 0.85344) (xy -0.09144 0.87376) (xy -0.0635 0.889) (xy -0.03175 0.89916) (xy 0 0.9017)
						(xy 0.03175 0.89916) (xy 0.0635 0.889) (xy 0.09144 0.87376) (xy 0.11684 0.85344) (xy 0.13716 0.82804)
						(xy 0.1524 0.8001) (xy 0.16256 0.76835) (xy 0.1651 0.7366) (xy 0.1651 -0.13462) (xy 0.17272 -0.14224)
						(xy 0.19812 -0.1778) (xy 0.2032 -0.18796) (xy 0.20701 -0.19685) (xy 0.21209 -0.20701) (xy 0.2159 -0.21717)
						(xy 0.21844 -0.22733) (xy 0.22225 -0.23876) (xy 0.22352 -0.24892) (xy 0.22606 -0.25908) (xy 0.22733 -0.27051)
						(xy 0.22733 -0.28067) (xy 0.2286 -0.2921) (xy 0.22733 -0.30353) (xy 0.22733 -0.31369) (xy 0.22606 -0.32512)
						(xy 0.22352 -0.33528) (xy 0.22225 -0.34544) (xy 0.21844 -0.35687) (xy 0.2159 -0.36703) (xy 0.21209 -0.37719)
						(xy 0.20701 -0.38735) (xy 0.2032 -0.39624) (xy 0.19812 -0.4064) (xy 0.17272 -0.44196) (xy 0.1651 -0.44958)
						(xy 0.1651 -0.7366) (xy 0.16256 -0.76835) (xy 0.1524 -0.8001) (xy 0.13716 -0.82804) (xy 0.11684 -0.85344)
						(xy 0.09144 -0.87376) (xy 0.0635 -0.889) (xy 0.03175 -0.89916)
					)
					(width 0)
					(fill yes)
				)
			)
		)
		(pad "10" smd custom
			(at -28.949904 4.100068 180)
			(size 0.1143 0.1143)
			(layers "B.Cu" "B.Mask" "B.Paste")
			(net "M_B_DQS_DN0")
			(options
				(clearance outline)
				(anchor circle)
			)
			(primitives
				(gr_poly
					(pts
						(xy 0 -0.9017) (xy -0.03175 -0.89916) (xy -0.0635 -0.889) (xy -0.09144 -0.87376) (xy -0.11684 -0.85344)
						(xy -0.13716 -0.82804) (xy -0.1524 -0.8001) (xy -0.16256 -0.76835) (xy -0.1651 -0.7366) (xy -0.1651 0.13462)
						(xy -0.17272 0.14224) (xy -0.19812 0.1778) (xy -0.2032 0.18796) (xy -0.20701 0.19685) (xy -0.21209 0.20701)
						(xy -0.2159 0.21717) (xy -0.21844 0.22733) (xy -0.22225 0.23876) (xy -0.22352 0.24892) (xy -0.22606 0.25908)
						(xy -0.22733 0.27051) (xy -0.22733 0.28067) (xy -0.2286 0.2921) (xy -0.22733 0.30353) (xy -0.22733 0.31369)
						(xy -0.22606 0.32512) (xy -0.22352 0.33528) (xy -0.22225 0.34544) (xy -0.21844 0.35687) (xy -0.2159 0.36703)
						(xy -0.21209 0.37719) (xy -0.20701 0.38735) (xy -0.2032 0.39624) (xy -0.19812 0.4064) (xy -0.17272 0.44196)
						(xy -0.1651 0.44958) (xy -0.1651 0.7366) (xy -0.16256 0.76835) (xy -0.1524 0.8001) (xy -0.13716 0.82804)
						(xy -0.11684 0.85344) (xy -0.09144 0.87376) (xy -0.0635 0.889) (xy -0.03175 0.89916) (xy 0 0.9017)
						(xy 0.03175 0.89916) (xy 0.0635 0.889) (xy 0.09144 0.87376) (xy 0.11684 0.85344) (xy 0.13716 0.82804)
						(xy 0.1524 0.8001) (xy 0.16256 0.76835) (xy 0.1651 0.7366) (xy 0.1651 0.44958) (xy 0.17272 0.44196)
						(xy 0.19812 0.4064) (xy 0.2032 0.39624) (xy 0.20701 0.38735) (xy 0.21209 0.37719) (xy 0.2159 0.36703)
						(xy 0.21844 0.35687) (xy 0.22225 0.34544) (xy 0.22352 0.33528) (xy 0.22606 0.32512) (xy 0.22733 0.31369)
						(xy 0.22733 0.30353) (xy 0.2286 0.2921) (xy 0.22733 0.28067) (xy 0.22733 0.27051) (xy 0.22606 0.25908)
						(xy 0.22352 0.24892) (xy 0.22225 0.23876) (xy 0.21844 0.22733) (xy 0.2159 0.21717) (xy 0.21209 0.20701)
						(xy 0.20701 0.19685) (xy 0.2032 0.18796) (xy 0.19812 0.1778) (xy 0.17272 0.14224) (xy 0.1651 0.13462)
						(xy 0.1651 -0.7366) (xy 0.16256 -0.76835) (xy 0.1524 -0.8001) (xy 0.13716 -0.82804) (xy 0.11684 -0.85344)
						(xy 0.09144 -0.87376) (xy 0.0635 -0.889) (xy 0.03175 -0.89916)
					)
					(width 0)
					(fill yes)
				)
			)
		)
		(pad "11" smd custom
			(at -28.64993 -4.100068 180)
			(size 0.1143 0.1143)
			(layers "B.Cu" "B.Mask" "B.Paste")
			(net "GND")
			(options
				(clearance outline)
				(anchor circle)
			)
			(primitives
				(gr_poly
					(pts
						(xy 0 -0.9017) (xy -0.03175 -0.89916) (xy -0.0635 -0.889) (xy -0.09144 -0.87376) (xy -0.11684 -0.85344)
						(xy -0.13716 -0.82804) (xy -0.1524 -0.8001) (xy -0.16256 -0.76835) (xy -0.1651 -0.7366) (xy -0.1651 -0.19685)
						(xy -0.17272 -0.18923) (xy -0.17907 -0.18034) (xy -0.18669 -0.17145) (xy -0.19177 -0.16256) (xy -0.19812 -0.15367)
						(xy -0.20828 -0.13335) (xy -0.21971 -0.10287) (xy -0.22225 -0.09271) (xy -0.22479 -0.08128) (xy -0.22606 -0.07112)
						(xy -0.2286 -0.05969) (xy -0.2286 -0.01651) (xy -0.22606 -0.00508) (xy -0.22479 0.00508) (xy -0.22225 0.01651)
						(xy -0.21971 0.02667) (xy -0.20828 0.05715) (xy -0.19812 0.07747) (xy -0.19177 0.08636) (xy -0.18669 0.09525)
						(xy -0.17907 0.10414) (xy -0.17272 0.11303) (xy -0.1651 0.12065) (xy -0.1651 0.7366) (xy -0.16256 0.76835)
						(xy -0.1524 0.8001) (xy -0.13716 0.82804) (xy -0.11684 0.85344) (xy -0.09144 0.87376) (xy -0.0635 0.889)
						(xy -0.03175 0.89916) (xy 0 0.9017) (xy 0.03175 0.89916) (xy 0.0635 0.889) (xy 0.09144 0.87376)
						(xy 0.11684 0.85344) (xy 0.13716 0.82804) (xy 0.1524 0.8001) (xy 0.16256 0.76835) (xy 0.1651 0.7366)
						(xy 0.1651 0.11938) (xy 0.17272 0.11176) (xy 0.19812 0.0762) (xy 0.2032 0.06604) (xy 0.20701 0.05715)
						(xy 0.21209 0.04699) (xy 0.2159 0.03683) (xy 0.21844 0.02667) (xy 0.22225 0.01524) (xy 0.22352 0.00508)
						(xy 0.22606 -0.00508) (xy 0.22733 -0.01651) (xy 0.22733 -0.02667) (xy 0.2286 -0.0381) (xy 0.22733 -0.04953)
						(xy 0.22733 -0.05969) (xy 0.22606 -0.07112) (xy 0.22352 -0.08128) (xy 0.22225 -0.09144) (xy 0.21844 -0.10287)
						(xy 0.2159 -0.11303) (xy 0.21209 -0.12319) (xy 0.20701 -0.13335) (xy 0.2032 -0.14224) (xy 0.19812 -0.1524)
						(xy 0.17272 -0.18796) (xy 0.1651 -0.19558) (xy 0.1651 -0.7366) (xy 0.16256 -0.76835) (xy 0.1524 -0.8001)
						(xy 0.13716 -0.82804) (xy 0.11684 -0.85344) (xy 0.09144 -0.87376) (xy 0.0635 -0.889) (xy 0.03175 -0.89916)
					)
					(width 0)
					(fill yes)
				)
			)
		)
		(pad "12" smd custom
			(at -28.349956 4.100068 180)
			(size 0.1143 0.1143)
			(layers "B.Cu" "B.Mask" "B.Paste")
			(net "M_B_DQS_DP0")
			(options
				(clearance outline)
				(anchor circle)
			)
			(primitives
				(gr_poly
					(pts
						(xy 0 -0.9017) (xy -0.03175 -0.89916) (xy -0.0635 -0.889) (xy -0.09144 -0.87376) (xy -0.11684 -0.85344)
						(xy -0.13716 -0.82804) (xy -0.1524 -0.8001) (xy -0.16256 -0.76835) (xy -0.1651 -0.7366) (xy -0.1651 -0.11938)
						(xy -0.17272 -0.11176) (xy -0.19812 -0.0762) (xy -0.2032 -0.06604) (xy -0.20701 -0.05715) (xy -0.21209 -0.04699)
						(xy -0.2159 -0.03683) (xy -0.21844 -0.02667) (xy -0.22225 -0.01524) (xy -0.22352 -0.00508) (xy -0.22606 0.00508)
						(xy -0.22733 0.01651) (xy -0.22733 0.02667) (xy -0.2286 0.0381) (xy -0.22733 0.04953) (xy -0.22733 0.05969)
						(xy -0.22606 0.07112) (xy -0.22352 0.08128) (xy -0.22225 0.09144) (xy -0.21844 0.10287) (xy -0.2159 0.11303)
						(xy -0.21209 0.12319) (xy -0.20701 0.13335) (xy -0.2032 0.14224) (xy -0.19812 0.1524) (xy -0.17272 0.18796)
						(xy -0.1651 0.19558) (xy -0.1651 0.7366) (xy -0.16256 0.76835) (xy -0.1524 0.8001) (xy -0.13716 0.82804)
						(xy -0.11684 0.85344) (xy -0.09144 0.87376) (xy -0.0635 0.889) (xy -0.03175 0.89916) (xy 0 0.9017)
						(xy 0.03175 0.89916) (xy 0.0635 0.889) (xy 0.09144 0.87376) (xy 0.11684 0.85344) (xy 0.13716 0.82804)
						(xy 0.1524 0.8001) (xy 0.16256 0.76835) (xy 0.1651 0.7366) (xy 0.1651 0.19685) (xy 0.17272 0.18923)
						(xy 0.17907 0.18034) (xy 0.18669 0.17145) (xy 0.19177 0.16256) (xy 0.19812 0.15367) (xy 0.20828 0.13335)
						(xy 0.21971 0.10287) (xy 0.22225 0.09271) (xy 0.22479 0.08128) (xy 0.22606 0.07112) (xy 0.2286 0.05969)
						(xy 0.2286 0.01651) (xy 0.22606 0.00508) (xy 0.22479 -0.00508) (xy 0.22225 -0.01651) (xy 0.21971 -0.02667)
						(xy 0.20828 -0.05715) (xy 0.19812 -0.07747) (xy 0.19177 -0.08636) (xy 0.18669 -0.09525) (xy 0.17907 -0.10414)
						(xy 0.17272 -0.11303) (xy 0.1651 -0.12065) (xy 0.1651 -0.7366) (xy 0.16256 -0.76835) (xy 0.1524 -0.8001)
						(xy 0.13716 -0.82804) (xy 0.11684 -0.85344) (xy 0.09144 -0.87376) (xy 0.0635 -0.889) (xy 0.03175 -0.89916)
					)
					(width 0)
					(fill yes)
				)
			)
		)
		(pad "13" smd custom
			(at -28.049982 -4.100068 180)
			(size 0.1143 0.1143)
			(layers "B.Cu" "B.Mask" "B.Paste")
			(net "M_B_DQ2")
			(options
				(clearance outline)
				(anchor circle)
			)
			(primitives
				(gr_poly
					(pts
						(xy 0 -0.9017) (xy -0.03175 -0.89916) (xy -0.0635 -0.889) (xy -0.09144 -0.87376) (xy -0.11684 -0.85344)
						(xy -0.13716 -0.82804) (xy -0.1524 -0.8001) (xy -0.16256 -0.76835) (xy -0.1651 -0.7366) (xy -0.1651 -0.44958)
						(xy -0.17272 -0.44196) (xy -0.19812 -0.4064) (xy -0.2032 -0.39624) (xy -0.20701 -0.38735) (xy -0.21209 -0.37719)
						(xy -0.2159 -0.36703) (xy -0.21844 -0.35687) (xy -0.22225 -0.34544) (xy -0.22352 -0.33528) (xy -0.22606 -0.32512)
						(xy -0.22733 -0.31369) (xy -0.22733 -0.30353) (xy -0.2286 -0.2921) (xy -0.22733 -0.28067) (xy -0.22733 -0.27051)
						(xy -0.22606 -0.25908) (xy -0.22352 -0.24892) (xy -0.22225 -0.23876) (xy -0.21844 -0.22733) (xy -0.2159 -0.21717)
						(xy -0.21209 -0.20701) (xy -0.20701 -0.19685) (xy -0.2032 -0.18796) (xy -0.19812 -0.1778) (xy -0.17272 -0.14224)
						(xy -0.1651 -0.13462) (xy -0.1651 0.7366) (xy -0.16256 0.76835) (xy -0.1524 0.8001) (xy -0.13716 0.82804)
						(xy -0.11684 0.85344) (xy -0.09144 0.87376) (xy -0.0635 0.889) (xy -0.03175 0.89916) (xy 0 0.9017)
						(xy 0.03175 0.89916) (xy 0.0635 0.889) (xy 0.09144 0.87376) (xy 0.11684 0.85344) (xy 0.13716 0.82804)
						(xy 0.1524 0.8001) (xy 0.16256 0.76835) (xy 0.1651 0.7366) (xy 0.1651 -0.13462) (xy 0.17272 -0.14224)
						(xy 0.19812 -0.1778) (xy 0.2032 -0.18796) (xy 0.20701 -0.19685) (xy 0.21209 -0.20701) (xy 0.2159 -0.21717)
						(xy 0.21844 -0.22733) (xy 0.22225 -0.23876) (xy 0.22352 -0.24892) (xy 0.22606 -0.25908) (xy 0.22733 -0.27051)
						(xy 0.22733 -0.28067) (xy 0.2286 -0.2921) (xy 0.22733 -0.30353) (xy 0.22733 -0.31369) (xy 0.22606 -0.32512)
						(xy 0.22352 -0.33528) (xy 0.22225 -0.34544) (xy 0.21844 -0.35687) (xy 0.2159 -0.36703) (xy 0.21209 -0.37719)
						(xy 0.20701 -0.38735) (xy 0.2032 -0.39624) (xy 0.19812 -0.4064) (xy 0.17272 -0.44196) (xy 0.1651 -0.44958)
						(xy 0.1651 -0.7366) (xy 0.16256 -0.76835) (xy 0.1524 -0.8001) (xy 0.13716 -0.82804) (xy 0.11684 -0.85344)
						(xy 0.09144 -0.87376) (xy 0.0635 -0.889) (xy 0.03175 -0.89916)
					)
					(width 0)
					(fill yes)
				)
			)
		)
		(pad "14" smd custom
			(at -27.750008 4.100068 180)
			(size 0.1143 0.1143)
			(layers "B.Cu" "B.Mask" "B.Paste")
			(net "GND")
			(options
				(clearance outline)
				(anchor circle)
			)
			(primitives
				(gr_poly
					(pts
						(xy 0 -0.9017) (xy -0.03175 -0.89916) (xy -0.0635 -0.889) (xy -0.09144 -0.87376) (xy -0.11684 -0.85344)
						(xy -0.13716 -0.82804) (xy -0.1524 -0.8001) (xy -0.16256 -0.76835) (xy -0.1651 -0.7366) (xy -0.1651 0.13462)
						(xy -0.17272 0.14224) (xy -0.19812 0.1778) (xy -0.2032 0.18796) (xy -0.20701 0.19685) (xy -0.21209 0.20701)
						(xy -0.2159 0.21717) (xy -0.21844 0.22733) (xy -0.22225 0.23876) (xy -0.22352 0.24892) (xy -0.22606 0.25908)
						(xy -0.22733 0.27051) (xy -0.22733 0.28067) (xy -0.2286 0.2921) (xy -0.22733 0.30353) (xy -0.22733 0.31369)
						(xy -0.22606 0.32512) (xy -0.22352 0.33528) (xy -0.22225 0.34544) (xy -0.21844 0.35687) (xy -0.2159 0.36703)
						(xy -0.21209 0.37719) (xy -0.20701 0.38735) (xy -0.2032 0.39624) (xy -0.19812 0.4064) (xy -0.17272 0.44196)
						(xy -0.1651 0.44958) (xy -0.1651 0.7366) (xy -0.16256 0.76835) (xy -0.1524 0.8001) (xy -0.13716 0.82804)
						(xy -0.11684 0.85344) (xy -0.09144 0.87376) (xy -0.0635 0.889) (xy -0.03175 0.89916) (xy 0 0.9017)
						(xy 0.03175 0.89916) (xy 0.0635 0.889) (xy 0.09144 0.87376) (xy 0.11684 0.85344) (xy 0.13716 0.82804)
						(xy 0.1524 0.8001) (xy 0.16256 0.76835) (xy 0.1651 0.7366) (xy 0.1651 0.44958) (xy 0.17272 0.44196)
						(xy 0.19812 0.4064) (xy 0.2032 0.39624) (xy 0.20701 0.38735) (xy 0.21209 0.37719) (xy 0.2159 0.36703)
						(xy 0.21844 0.35687) (xy 0.22225 0.34544) (xy 0.22352 0.33528) (xy 0.22606 0.32512) (xy 0.22733 0.31369)
						(xy 0.22733 0.30353) (xy 0.2286 0.2921) (xy 0.22733 0.28067) (xy 0.22733 0.27051) (xy 0.22606 0.25908)
						(xy 0.22352 0.24892) (xy 0.22225 0.23876) (xy 0.21844 0.22733) (xy 0.2159 0.21717) (xy 0.21209 0.20701)
						(xy 0.20701 0.19685) (xy 0.2032 0.18796) (xy 0.19812 0.1778) (xy 0.17272 0.14224) (xy 0.1651 0.13462)
						(xy 0.1651 -0.7366) (xy 0.16256 -0.76835) (xy 0.1524 -0.8001) (xy 0.13716 -0.82804) (xy 0.11684 -0.85344)
						(xy 0.09144 -0.87376) (xy 0.0635 -0.889) (xy 0.03175 -0.89916)
					)
					(width 0)
					(fill yes)
				)
			)
		)
		(pad "15" smd custom
			(at -27.450034 -4.100068 180)
			(size 0.1143 0.1143)
			(layers "B.Cu" "B.Mask" "B.Paste")
			(net "M_B_DQ3")
			(options
				(clearance outline)
				(anchor circle)
			)
			(primitives
				(gr_poly
					(pts
						(xy 0 -0.9017) (xy -0.03175 -0.89916) (xy -0.0635 -0.889) (xy -0.09144 -0.87376) (xy -0.11684 -0.85344)
						(xy -0.13716 -0.82804) (xy -0.1524 -0.8001) (xy -0.16256 -0.76835) (xy -0.1651 -0.7366) (xy -0.1651 -0.19685)
						(xy -0.17272 -0.18923) (xy -0.17907 -0.18034) (xy -0.18669 -0.17145) (xy -0.19177 -0.16256) (xy -0.19812 -0.15367)
						(xy -0.20828 -0.13335) (xy -0.21971 -0.10287) (xy -0.22225 -0.09271) (xy -0.22479 -0.08128) (xy -0.22606 -0.07112)
						(xy -0.2286 -0.05969) (xy -0.2286 -0.01651) (xy -0.22606 -0.00508) (xy -0.22479 0.00508) (xy -0.22225 0.01651)
						(xy -0.21971 0.02667) (xy -0.20828 0.05715) (xy -0.19812 0.07747) (xy -0.19177 0.08636) (xy -0.18669 0.09525)
						(xy -0.17907 0.10414) (xy -0.17272 0.11303) (xy -0.1651 0.12065) (xy -0.1651 0.7366) (xy -0.16256 0.76835)
						(xy -0.1524 0.8001) (xy -0.13716 0.82804) (xy -0.11684 0.85344) (xy -0.09144 0.87376) (xy -0.0635 0.889)
						(xy -0.03175 0.89916) (xy 0 0.9017) (xy 0.03175 0.89916) (xy 0.0635 0.889) (xy 0.09144 0.87376)
						(xy 0.11684 0.85344) (xy 0.13716 0.82804) (xy 0.1524 0.8001) (xy 0.16256 0.76835) (xy 0.1651 0.7366)
						(xy 0.1651 0.11938) (xy 0.17272 0.11176) (xy 0.19812 0.0762) (xy 0.2032 0.06604) (xy 0.20701 0.05715)
						(xy 0.21209 0.04699) (xy 0.2159 0.03683) (xy 0.21844 0.02667) (xy 0.22225 0.01524) (xy 0.22352 0.00508)
						(xy 0.22606 -0.00508) (xy 0.22733 -0.01651) (xy 0.22733 -0.02667) (xy 0.2286 -0.0381) (xy 0.22733 -0.04953)
						(xy 0.22733 -0.05969) (xy 0.22606 -0.07112) (xy 0.22352 -0.08128) (xy 0.22225 -0.09144) (xy 0.21844 -0.10287)
						(xy 0.2159 -0.11303) (xy 0.21209 -0.12319) (xy 0.20701 -0.13335) (xy 0.2032 -0.14224) (xy 0.19812 -0.1524)
						(xy 0.17272 -0.18796) (xy 0.1651 -0.19558) (xy 0.1651 -0.7366) (xy 0.16256 -0.76835) (xy 0.1524 -0.8001)
						(xy 0.13716 -0.82804) (xy 0.11684 -0.85344) (xy 0.09144 -0.87376) (xy 0.0635 -0.889) (xy 0.03175 -0.89916)
					)
					(width 0)
					(fill yes)
				)
			)
		)
		(pad "16" smd custom
			(at -27.15006 4.100068 180)
			(size 0.1143 0.1143)
			(layers "B.Cu" "B.Mask" "B.Paste")
			(net "M_B_DQ6")
			(options
				(clearance outline)
				(anchor circle)
			)
			(primitives
				(gr_poly
					(pts
						(xy 0 -0.9017) (xy -0.03175 -0.89916) (xy -0.0635 -0.889) (xy -0.09144 -0.87376) (xy -0.11684 -0.85344)
						(xy -0.13716 -0.82804) (xy -0.1524 -0.8001) (xy -0.16256 -0.76835) (xy -0.1651 -0.7366) (xy -0.1651 -0.11938)
						(xy -0.17272 -0.11176) (xy -0.19812 -0.0762) (xy -0.2032 -0.06604) (xy -0.20701 -0.05715) (xy -0.21209 -0.04699)
						(xy -0.2159 -0.03683) (xy -0.21844 -0.02667) (xy -0.22225 -0.01524) (xy -0.22352 -0.00508) (xy -0.22606 0.00508)
						(xy -0.22733 0.01651) (xy -0.22733 0.02667) (xy -0.2286 0.0381) (xy -0.22733 0.04953) (xy -0.22733 0.05969)
						(xy -0.22606 0.07112) (xy -0.22352 0.08128) (xy -0.22225 0.09144) (xy -0.21844 0.10287) (xy -0.2159 0.11303)
						(xy -0.21209 0.12319) (xy -0.20701 0.13335) (xy -0.2032 0.14224) (xy -0.19812 0.1524) (xy -0.17272 0.18796)
						(xy -0.1651 0.19558) (xy -0.1651 0.7366) (xy -0.16256 0.76835) (xy -0.1524 0.8001) (xy -0.13716 0.82804)
						(xy -0.11684 0.85344) (xy -0.09144 0.87376) (xy -0.0635 0.889) (xy -0.03175 0.89916) (xy 0 0.9017)
						(xy 0.03175 0.89916) (xy 0.0635 0.889) (xy 0.09144 0.87376) (xy 0.11684 0.85344) (xy 0.13716 0.82804)
						(xy 0.1524 0.8001) (xy 0.16256 0.76835) (xy 0.1651 0.7366) (xy 0.1651 0.19685) (xy 0.17272 0.18923)
						(xy 0.17907 0.18034) (xy 0.18669 0.17145) (xy 0.19177 0.16256) (xy 0.19812 0.15367) (xy 0.20828 0.13335)
						(xy 0.21971 0.10287) (xy 0.22225 0.09271) (xy 0.22479 0.08128) (xy 0.22606 0.07112) (xy 0.2286 0.05969)
						(xy 0.2286 0.01651) (xy 0.22606 0.00508) (xy 0.22479 -0.00508) (xy 0.22225 -0.01651) (xy 0.21971 -0.02667)
						(xy 0.20828 -0.05715) (xy 0.19812 -0.07747) (xy 0.19177 -0.08636) (xy 0.18669 -0.09525) (xy 0.17907 -0.10414)
						(xy 0.17272 -0.11303) (xy 0.1651 -0.12065) (xy 0.1651 -0.7366) (xy 0.16256 -0.76835) (xy 0.1524 -0.8001)
						(xy 0.13716 -0.82804) (xy 0.11684 -0.85344) (xy 0.09144 -0.87376) (xy 0.0635 -0.889) (xy 0.03175 -0.89916)
					)
					(width 0)
					(fill yes)
				)
			)
		)
		(pad "17" smd custom
			(at -26.850086 -4.100068 180)
			(size 0.1143 0.1143)
			(layers "B.Cu" "B.Mask" "B.Paste")
			(net "GND")
			(options
				(clearance outline)
				(anchor circle)
			)
			(primitives
				(gr_poly
					(pts
						(xy 0 -0.9017) (xy -0.03175 -0.89916) (xy -0.0635 -0.889) (xy -0.09144 -0.87376) (xy -0.11684 -0.85344)
						(xy -0.13716 -0.82804) (xy -0.1524 -0.8001) (xy -0.16256 -0.76835) (xy -0.1651 -0.7366) (xy -0.1651 -0.44958)
						(xy -0.17272 -0.44196) (xy -0.19812 -0.4064) (xy -0.2032 -0.39624) (xy -0.20701 -0.38735) (xy -0.21209 -0.37719)
						(xy -0.2159 -0.36703) (xy -0.21844 -0.35687) (xy -0.22225 -0.34544) (xy -0.22352 -0.33528) (xy -0.22606 -0.32512)
						(xy -0.22733 -0.31369) (xy -0.22733 -0.30353) (xy -0.2286 -0.2921) (xy -0.22733 -0.28067) (xy -0.22733 -0.27051)
						(xy -0.22606 -0.25908) (xy -0.22352 -0.24892) (xy -0.22225 -0.23876) (xy -0.21844 -0.22733) (xy -0.2159 -0.21717)
						(xy -0.21209 -0.20701) (xy -0.20701 -0.19685) (xy -0.2032 -0.18796) (xy -0.19812 -0.1778) (xy -0.17272 -0.14224)
						(xy -0.1651 -0.13462) (xy -0.1651 0.7366) (xy -0.16256 0.76835) (xy -0.1524 0.8001) (xy -0.13716 0.82804)
						(xy -0.11684 0.85344) (xy -0.09144 0.87376) (xy -0.0635 0.889) (xy -0.03175 0.89916) (xy 0 0.9017)
						(xy 0.03175 0.89916) (xy 0.0635 0.889) (xy 0.09144 0.87376) (xy 0.11684 0.85344) (xy 0.13716 0.82804)
						(xy 0.1524 0.8001) (xy 0.16256 0.76835) (xy 0.1651 0.7366) (xy 0.1651 -0.13462) (xy 0.17272 -0.14224)
						(xy 0.19812 -0.1778) (xy 0.2032 -0.18796) (xy 0.20701 -0.19685) (xy 0.21209 -0.20701) (xy 0.2159 -0.21717)
						(xy 0.21844 -0.22733) (xy 0.22225 -0.23876) (xy 0.22352 -0.24892) (xy 0.22606 -0.25908) (xy 0.22733 -0.27051)
						(xy 0.22733 -0.28067) (xy 0.2286 -0.2921) (xy 0.22733 -0.30353) (xy 0.22733 -0.31369) (xy 0.22606 -0.32512)
						(xy 0.22352 -0.33528) (xy 0.22225 -0.34544) (xy 0.21844 -0.35687) (xy 0.2159 -0.36703) (xy 0.21209 -0.37719)
						(xy 0.20701 -0.38735) (xy 0.2032 -0.39624) (xy 0.19812 -0.4064) (xy 0.17272 -0.44196) (xy 0.1651 -0.44958)
						(xy 0.1651 -0.7366) (xy 0.16256 -0.76835) (xy 0.1524 -0.8001) (xy 0.13716 -0.82804) (xy 0.11684 -0.85344)
						(xy 0.09144 -0.87376) (xy 0.0635 -0.889) (xy 0.03175 -0.89916)
					)
					(width 0)
					(fill yes)
				)
			)
		)
		(pad "18" smd custom
			(at -26.550112 4.100068 180)
			(size 0.1143 0.1143)
			(layers "B.Cu" "B.Mask" "B.Paste")
			(net "M_B_DQ7")
			(options
				(clearance outline)
				(anchor circle)
			)
			(primitives
				(gr_poly
					(pts
						(xy 0 -0.9017) (xy -0.03175 -0.89916) (xy -0.0635 -0.889) (xy -0.09144 -0.87376) (xy -0.11684 -0.85344)
						(xy -0.13716 -0.82804) (xy -0.1524 -0.8001) (xy -0.16256 -0.76835) (xy -0.1651 -0.7366) (xy -0.1651 0.13462)
						(xy -0.17272 0.14224) (xy -0.19812 0.1778) (xy -0.2032 0.18796) (xy -0.20701 0.19685) (xy -0.21209 0.20701)
						(xy -0.2159 0.21717) (xy -0.21844 0.22733) (xy -0.22225 0.23876) (xy -0.22352 0.24892) (xy -0.22606 0.25908)
						(xy -0.22733 0.27051) (xy -0.22733 0.28067) (xy -0.2286 0.2921) (xy -0.22733 0.30353) (xy -0.22733 0.31369)
						(xy -0.22606 0.32512) (xy -0.22352 0.33528) (xy -0.22225 0.34544) (xy -0.21844 0.35687) (xy -0.2159 0.36703)
						(xy -0.21209 0.37719) (xy -0.20701 0.38735) (xy -0.2032 0.39624) (xy -0.19812 0.4064) (xy -0.17272 0.44196)
						(xy -0.1651 0.44958) (xy -0.1651 0.7366) (xy -0.16256 0.76835) (xy -0.1524 0.8001) (xy -0.13716 0.82804)
						(xy -0.11684 0.85344) (xy -0.09144 0.87376) (xy -0.0635 0.889) (xy -0.03175 0.89916) (xy 0 0.9017)
						(xy 0.03175 0.89916) (xy 0.0635 0.889) (xy 0.09144 0.87376) (xy 0.11684 0.85344) (xy 0.13716 0.82804)
						(xy 0.1524 0.8001) (xy 0.16256 0.76835) (xy 0.1651 0.7366) (xy 0.1651 0.44958) (xy 0.17272 0.44196)
						(xy 0.19812 0.4064) (xy 0.2032 0.39624) (xy 0.20701 0.38735) (xy 0.21209 0.37719) (xy 0.2159 0.36703)
						(xy 0.21844 0.35687) (xy 0.22225 0.34544) (xy 0.22352 0.33528) (xy 0.22606 0.32512) (xy 0.22733 0.31369)
						(xy 0.22733 0.30353) (xy 0.2286 0.2921) (xy 0.22733 0.28067) (xy 0.22733 0.27051) (xy 0.22606 0.25908)
						(xy 0.22352 0.24892) (xy 0.22225 0.23876) (xy 0.21844 0.22733) (xy 0.2159 0.21717) (xy 0.21209 0.20701)
						(xy 0.20701 0.19685) (xy 0.2032 0.18796) (xy 0.19812 0.1778) (xy 0.17272 0.14224) (xy 0.1651 0.13462)
						(xy 0.1651 -0.7366) (xy 0.16256 -0.76835) (xy 0.1524 -0.8001) (xy 0.13716 -0.82804) (xy 0.11684 -0.85344)
						(xy 0.09144 -0.87376) (xy 0.0635 -0.889) (xy 0.03175 -0.89916)
					)
					(width 0)
					(fill yes)
				)
			)
		)
		(pad "19" smd custom
			(at -26.249884 -4.100068 180)
			(size 0.1143 0.1143)
			(layers "B.Cu" "B.Mask" "B.Paste")
			(net "M_B_DQ8")
			(options
				(clearance outline)
				(anchor circle)
			)
			(primitives
				(gr_poly
					(pts
						(xy 0 -0.9017) (xy -0.03175 -0.89916) (xy -0.0635 -0.889) (xy -0.09144 -0.87376) (xy -0.11684 -0.85344)
						(xy -0.13716 -0.82804) (xy -0.1524 -0.8001) (xy -0.16256 -0.76835) (xy -0.1651 -0.7366) (xy -0.1651 -0.19685)
						(xy -0.17272 -0.18923) (xy -0.17907 -0.18034) (xy -0.18669 -0.17145) (xy -0.19177 -0.16256) (xy -0.19812 -0.15367)
						(xy -0.20828 -0.13335) (xy -0.21971 -0.10287) (xy -0.22225 -0.09271) (xy -0.22479 -0.08128) (xy -0.22606 -0.07112)
						(xy -0.2286 -0.05969) (xy -0.2286 -0.01651) (xy -0.22606 -0.00508) (xy -0.22479 0.00508) (xy -0.22225 0.01651)
						(xy -0.21971 0.02667) (xy -0.20828 0.05715) (xy -0.19812 0.07747) (xy -0.19177 0.08636) (xy -0.18669 0.09525)
						(xy -0.17907 0.10414) (xy -0.17272 0.11303) (xy -0.1651 0.12065) (xy -0.1651 0.7366) (xy -0.16256 0.76835)
						(xy -0.1524 0.8001) (xy -0.13716 0.82804) (xy -0.11684 0.85344) (xy -0.09144 0.87376) (xy -0.0635 0.889)
						(xy -0.03175 0.89916) (xy 0 0.9017) (xy 0.03175 0.89916) (xy 0.0635 0.889) (xy 0.09144 0.87376)
						(xy 0.11684 0.85344) (xy 0.13716 0.82804) (xy 0.1524 0.8001) (xy 0.16256 0.76835) (xy 0.1651 0.7366)
						(xy 0.1651 0.11938) (xy 0.17272 0.11176) (xy 0.19812 0.0762) (xy 0.2032 0.06604) (xy 0.20701 0.05715)
						(xy 0.21209 0.04699) (xy 0.2159 0.03683) (xy 0.21844 0.02667) (xy 0.22225 0.01524) (xy 0.22352 0.00508)
						(xy 0.22606 -0.00508) (xy 0.22733 -0.01651) (xy 0.22733 -0.02667) (xy 0.2286 -0.0381) (xy 0.22733 -0.04953)
						(xy 0.22733 -0.05969) (xy 0.22606 -0.07112) (xy 0.22352 -0.08128) (xy 0.22225 -0.09144) (xy 0.21844 -0.10287)
						(xy 0.2159 -0.11303) (xy 0.21209 -0.12319) (xy 0.20701 -0.13335) (xy 0.2032 -0.14224) (xy 0.19812 -0.1524)
						(xy 0.17272 -0.18796) (xy 0.1651 -0.19558) (xy 0.1651 -0.7366) (xy 0.16256 -0.76835) (xy 0.1524 -0.8001)
						(xy 0.13716 -0.82804) (xy 0.11684 -0.85344) (xy 0.09144 -0.87376) (xy 0.0635 -0.889) (xy 0.03175 -0.89916)
					)
					(width 0)
					(fill yes)
				)
			)
		)
		(pad "20" smd custom
			(at -25.94991 4.100068 180)
			(size 0.1143 0.1143)
			(layers "B.Cu" "B.Mask" "B.Paste")
			(net "GND")
			(options
				(clearance outline)
				(anchor circle)
			)
			(primitives
				(gr_poly
					(pts
						(xy 0 -0.9017) (xy -0.03175 -0.89916) (xy -0.0635 -0.889) (xy -0.09144 -0.87376) (xy -0.11684 -0.85344)
						(xy -0.13716 -0.82804) (xy -0.1524 -0.8001) (xy -0.16256 -0.76835) (xy -0.1651 -0.7366) (xy -0.1651 -0.11938)
						(xy -0.17272 -0.11176) (xy -0.19812 -0.0762) (xy -0.2032 -0.06604) (xy -0.20701 -0.05715) (xy -0.21209 -0.04699)
						(xy -0.2159 -0.03683) (xy -0.21844 -0.02667) (xy -0.22225 -0.01524) (xy -0.22352 -0.00508) (xy -0.22606 0.00508)
						(xy -0.22733 0.01651) (xy -0.22733 0.02667) (xy -0.2286 0.0381) (xy -0.22733 0.04953) (xy -0.22733 0.05969)
						(xy -0.22606 0.07112) (xy -0.22352 0.08128) (xy -0.22225 0.09144) (xy -0.21844 0.10287) (xy -0.2159 0.11303)
						(xy -0.21209 0.12319) (xy -0.20701 0.13335) (xy -0.2032 0.14224) (xy -0.19812 0.1524) (xy -0.17272 0.18796)
						(xy -0.1651 0.19558) (xy -0.1651 0.7366) (xy -0.16256 0.76835) (xy -0.1524 0.8001) (xy -0.13716 0.82804)
						(xy -0.11684 0.85344) (xy -0.09144 0.87376) (xy -0.0635 0.889) (xy -0.03175 0.89916) (xy 0 0.9017)
						(xy 0.03175 0.89916) (xy 0.0635 0.889) (xy 0.09144 0.87376) (xy 0.11684 0.85344) (xy 0.13716 0.82804)
						(xy 0.1524 0.8001) (xy 0.16256 0.76835) (xy 0.1651 0.7366) (xy 0.1651 0.19685) (xy 0.17272 0.18923)
						(xy 0.17907 0.18034) (xy 0.18669 0.17145) (xy 0.19177 0.16256) (xy 0.19812 0.15367) (xy 0.20828 0.13335)
						(xy 0.21971 0.10287) (xy 0.22225 0.09271) (xy 0.22479 0.08128) (xy 0.22606 0.07112) (xy 0.2286 0.05969)
						(xy 0.2286 0.01651) (xy 0.22606 0.00508) (xy 0.22479 -0.00508) (xy 0.22225 -0.01651) (xy 0.21971 -0.02667)
						(xy 0.20828 -0.05715) (xy 0.19812 -0.07747) (xy 0.19177 -0.08636) (xy 0.18669 -0.09525) (xy 0.17907 -0.10414)
						(xy 0.17272 -0.11303) (xy 0.1651 -0.12065) (xy 0.1651 -0.7366) (xy 0.16256 -0.76835) (xy 0.1524 -0.8001)
						(xy 0.13716 -0.82804) (xy 0.11684 -0.85344) (xy 0.09144 -0.87376) (xy 0.0635 -0.889) (xy 0.03175 -0.89916)
					)
					(width 0)
					(fill yes)
				)
			)
		)
		(pad "21" smd custom
			(at -25.649936 -4.100068 180)
			(size 0.1143 0.1143)
			(layers "B.Cu" "B.Mask" "B.Paste")
			(net "M_B_DQ9")
			(options
				(clearance outline)
				(anchor circle)
			)
			(primitives
				(gr_poly
					(pts
						(xy 0 -0.9017) (xy -0.03175 -0.89916) (xy -0.0635 -0.889) (xy -0.09144 -0.87376) (xy -0.11684 -0.85344)
						(xy -0.13716 -0.82804) (xy -0.1524 -0.8001) (xy -0.16256 -0.76835) (xy -0.1651 -0.7366) (xy -0.1651 -0.44958)
						(xy -0.17272 -0.44196) (xy -0.19812 -0.4064) (xy -0.2032 -0.39624) (xy -0.20701 -0.38735) (xy -0.21209 -0.37719)
						(xy -0.2159 -0.36703) (xy -0.21844 -0.35687) (xy -0.22225 -0.34544) (xy -0.22352 -0.33528) (xy -0.22606 -0.32512)
						(xy -0.22733 -0.31369) (xy -0.22733 -0.30353) (xy -0.2286 -0.2921) (xy -0.22733 -0.28067) (xy -0.22733 -0.27051)
						(xy -0.22606 -0.25908) (xy -0.22352 -0.24892) (xy -0.22225 -0.23876) (xy -0.21844 -0.22733) (xy -0.2159 -0.21717)
						(xy -0.21209 -0.20701) (xy -0.20701 -0.19685) (xy -0.2032 -0.18796) (xy -0.19812 -0.1778) (xy -0.17272 -0.14224)
						(xy -0.1651 -0.13462) (xy -0.1651 0.7366) (xy -0.16256 0.76835) (xy -0.1524 0.8001) (xy -0.13716 0.82804)
						(xy -0.11684 0.85344) (xy -0.09144 0.87376) (xy -0.0635 0.889) (xy -0.03175 0.89916) (xy 0 0.9017)
						(xy 0.03175 0.89916) (xy 0.0635 0.889) (xy 0.09144 0.87376) (xy 0.11684 0.85344) (xy 0.13716 0.82804)
						(xy 0.1524 0.8001) (xy 0.16256 0.76835) (xy 0.1651 0.7366) (xy 0.1651 -0.13462) (xy 0.17272 -0.14224)
						(xy 0.19812 -0.1778) (xy 0.2032 -0.18796) (xy 0.20701 -0.19685) (xy 0.21209 -0.20701) (xy 0.2159 -0.21717)
						(xy 0.21844 -0.22733) (xy 0.22225 -0.23876) (xy 0.22352 -0.24892) (xy 0.22606 -0.25908) (xy 0.22733 -0.27051)
						(xy 0.22733 -0.28067) (xy 0.2286 -0.2921) (xy 0.22733 -0.30353) (xy 0.22733 -0.31369) (xy 0.22606 -0.32512)
						(xy 0.22352 -0.33528) (xy 0.22225 -0.34544) (xy 0.21844 -0.35687) (xy 0.2159 -0.36703) (xy 0.21209 -0.37719)
						(xy 0.20701 -0.38735) (xy 0.2032 -0.39624) (xy 0.19812 -0.4064) (xy 0.17272 -0.44196) (xy 0.1651 -0.44958)
						(xy 0.1651 -0.7366) (xy 0.16256 -0.76835) (xy 0.1524 -0.8001) (xy 0.13716 -0.82804) (xy 0.11684 -0.85344)
						(xy 0.09144 -0.87376) (xy 0.0635 -0.889) (xy 0.03175 -0.89916)
					)
					(width 0)
					(fill yes)
				)
			)
		)
		(pad "22" smd custom
			(at -25.349962 4.100068 180)
			(size 0.1143 0.1143)
			(layers "B.Cu" "B.Mask" "B.Paste")
			(net "M_B_DQ12")
			(options
				(clearance outline)
				(anchor circle)
			)
			(primitives
				(gr_poly
					(pts
						(xy 0 -0.9017) (xy -0.03175 -0.89916) (xy -0.0635 -0.889) (xy -0.09144 -0.87376) (xy -0.11684 -0.85344)
						(xy -0.13716 -0.82804) (xy -0.1524 -0.8001) (xy -0.16256 -0.76835) (xy -0.1651 -0.7366) (xy -0.1651 0.13462)
						(xy -0.17272 0.14224) (xy -0.19812 0.1778) (xy -0.2032 0.18796) (xy -0.20701 0.19685) (xy -0.21209 0.20701)
						(xy -0.2159 0.21717) (xy -0.21844 0.22733) (xy -0.22225 0.23876) (xy -0.22352 0.24892) (xy -0.22606 0.25908)
						(xy -0.22733 0.27051) (xy -0.22733 0.28067) (xy -0.2286 0.2921) (xy -0.22733 0.30353) (xy -0.22733 0.31369)
						(xy -0.22606 0.32512) (xy -0.22352 0.33528) (xy -0.22225 0.34544) (xy -0.21844 0.35687) (xy -0.2159 0.36703)
						(xy -0.21209 0.37719) (xy -0.20701 0.38735) (xy -0.2032 0.39624) (xy -0.19812 0.4064) (xy -0.17272 0.44196)
						(xy -0.1651 0.44958) (xy -0.1651 0.7366) (xy -0.16256 0.76835) (xy -0.1524 0.8001) (xy -0.13716 0.82804)
						(xy -0.11684 0.85344) (xy -0.09144 0.87376) (xy -0.0635 0.889) (xy -0.03175 0.89916) (xy 0 0.9017)
						(xy 0.03175 0.89916) (xy 0.0635 0.889) (xy 0.09144 0.87376) (xy 0.11684 0.85344) (xy 0.13716 0.82804)
						(xy 0.1524 0.8001) (xy 0.16256 0.76835) (xy 0.1651 0.7366) (xy 0.1651 0.44958) (xy 0.17272 0.44196)
						(xy 0.19812 0.4064) (xy 0.2032 0.39624) (xy 0.20701 0.38735) (xy 0.21209 0.37719) (xy 0.2159 0.36703)
						(xy 0.21844 0.35687) (xy 0.22225 0.34544) (xy 0.22352 0.33528) (xy 0.22606 0.32512) (xy 0.22733 0.31369)
						(xy 0.22733 0.30353) (xy 0.2286 0.2921) (xy 0.22733 0.28067) (xy 0.22733 0.27051) (xy 0.22606 0.25908)
						(xy 0.22352 0.24892) (xy 0.22225 0.23876) (xy 0.21844 0.22733) (xy 0.2159 0.21717) (xy 0.21209 0.20701)
						(xy 0.20701 0.19685) (xy 0.2032 0.18796) (xy 0.19812 0.1778) (xy 0.17272 0.14224) (xy 0.1651 0.13462)
						(xy 0.1651 -0.7366) (xy 0.16256 -0.76835) (xy 0.1524 -0.8001) (xy 0.13716 -0.82804) (xy 0.11684 -0.85344)
						(xy 0.09144 -0.87376) (xy 0.0635 -0.889) (xy 0.03175 -0.89916)
					)
					(width 0)
					(fill yes)
				)
			)
		)
		(pad "23" smd custom
			(at -25.049988 -4.100068 180)
			(size 0.1143 0.1143)
			(layers "B.Cu" "B.Mask" "B.Paste")
			(net "GND")
			(options
				(clearance outline)
				(anchor circle)
			)
			(primitives
				(gr_poly
					(pts
						(xy 0 -0.9017) (xy -0.03175 -0.89916) (xy -0.0635 -0.889) (xy -0.09144 -0.87376) (xy -0.11684 -0.85344)
						(xy -0.13716 -0.82804) (xy -0.1524 -0.8001) (xy -0.16256 -0.76835) (xy -0.1651 -0.7366) (xy -0.1651 -0.19685)
						(xy -0.17272 -0.18923) (xy -0.17907 -0.18034) (xy -0.18669 -0.17145) (xy -0.19177 -0.16256) (xy -0.19812 -0.15367)
						(xy -0.20828 -0.13335) (xy -0.21971 -0.10287) (xy -0.22225 -0.09271) (xy -0.22479 -0.08128) (xy -0.22606 -0.07112)
						(xy -0.2286 -0.05969) (xy -0.2286 -0.01651) (xy -0.22606 -0.00508) (xy -0.22479 0.00508) (xy -0.22225 0.01651)
						(xy -0.21971 0.02667) (xy -0.20828 0.05715) (xy -0.19812 0.07747) (xy -0.19177 0.08636) (xy -0.18669 0.09525)
						(xy -0.17907 0.10414) (xy -0.17272 0.11303) (xy -0.1651 0.12065) (xy -0.1651 0.7366) (xy -0.16256 0.76835)
						(xy -0.1524 0.8001) (xy -0.13716 0.82804) (xy -0.11684 0.85344) (xy -0.09144 0.87376) (xy -0.0635 0.889)
						(xy -0.03175 0.89916) (xy 0 0.9017) (xy 0.03175 0.89916) (xy 0.0635 0.889) (xy 0.09144 0.87376)
						(xy 0.11684 0.85344) (xy 0.13716 0.82804) (xy 0.1524 0.8001) (xy 0.16256 0.76835) (xy 0.1651 0.7366)
						(xy 0.1651 0.11938) (xy 0.17272 0.11176) (xy 0.19812 0.0762) (xy 0.2032 0.06604) (xy 0.20701 0.05715)
						(xy 0.21209 0.04699) (xy 0.2159 0.03683) (xy 0.21844 0.02667) (xy 0.22225 0.01524) (xy 0.22352 0.00508)
						(xy 0.22606 -0.00508) (xy 0.22733 -0.01651) (xy 0.22733 -0.02667) (xy 0.2286 -0.0381) (xy 0.22733 -0.04953)
						(xy 0.22733 -0.05969) (xy 0.22606 -0.07112) (xy 0.22352 -0.08128) (xy 0.22225 -0.09144) (xy 0.21844 -0.10287)
						(xy 0.2159 -0.11303) (xy 0.21209 -0.12319) (xy 0.20701 -0.13335) (xy 0.2032 -0.14224) (xy 0.19812 -0.1524)
						(xy 0.17272 -0.18796) (xy 0.1651 -0.19558) (xy 0.1651 -0.7366) (xy 0.16256 -0.76835) (xy 0.1524 -0.8001)
						(xy 0.13716 -0.82804) (xy 0.11684 -0.85344) (xy 0.09144 -0.87376) (xy 0.0635 -0.889) (xy 0.03175 -0.89916)
					)
					(width 0)
					(fill yes)
				)
			)
		)
		(pad "24" smd custom
			(at -24.750014 4.100068 180)
			(size 0.1143 0.1143)
			(layers "B.Cu" "B.Mask" "B.Paste")
			(net "M_B_DQ13")
			(options
				(clearance outline)
				(anchor circle)
			)
			(primitives
				(gr_poly
					(pts
						(xy 0 -0.9017) (xy -0.03175 -0.89916) (xy -0.0635 -0.889) (xy -0.09144 -0.87376) (xy -0.11684 -0.85344)
						(xy -0.13716 -0.82804) (xy -0.1524 -0.8001) (xy -0.16256 -0.76835) (xy -0.1651 -0.7366) (xy -0.1651 -0.11938)
						(xy -0.17272 -0.11176) (xy -0.19812 -0.0762) (xy -0.2032 -0.06604) (xy -0.20701 -0.05715) (xy -0.21209 -0.04699)
						(xy -0.2159 -0.03683) (xy -0.21844 -0.02667) (xy -0.22225 -0.01524) (xy -0.22352 -0.00508) (xy -0.22606 0.00508)
						(xy -0.22733 0.01651) (xy -0.22733 0.02667) (xy -0.2286 0.0381) (xy -0.22733 0.04953) (xy -0.22733 0.05969)
						(xy -0.22606 0.07112) (xy -0.22352 0.08128) (xy -0.22225 0.09144) (xy -0.21844 0.10287) (xy -0.2159 0.11303)
						(xy -0.21209 0.12319) (xy -0.20701 0.13335) (xy -0.2032 0.14224) (xy -0.19812 0.1524) (xy -0.17272 0.18796)
						(xy -0.1651 0.19558) (xy -0.1651 0.7366) (xy -0.16256 0.76835) (xy -0.1524 0.8001) (xy -0.13716 0.82804)
						(xy -0.11684 0.85344) (xy -0.09144 0.87376) (xy -0.0635 0.889) (xy -0.03175 0.89916) (xy 0 0.9017)
						(xy 0.03175 0.89916) (xy 0.0635 0.889) (xy 0.09144 0.87376) (xy 0.11684 0.85344) (xy 0.13716 0.82804)
						(xy 0.1524 0.8001) (xy 0.16256 0.76835) (xy 0.1651 0.7366) (xy 0.1651 0.19685) (xy 0.17272 0.18923)
						(xy 0.17907 0.18034) (xy 0.18669 0.17145) (xy 0.19177 0.16256) (xy 0.19812 0.15367) (xy 0.20828 0.13335)
						(xy 0.21971 0.10287) (xy 0.22225 0.09271) (xy 0.22479 0.08128) (xy 0.22606 0.07112) (xy 0.2286 0.05969)
						(xy 0.2286 0.01651) (xy 0.22606 0.00508) (xy 0.22479 -0.00508) (xy 0.22225 -0.01651) (xy 0.21971 -0.02667)
						(xy 0.20828 -0.05715) (xy 0.19812 -0.07747) (xy 0.19177 -0.08636) (xy 0.18669 -0.09525) (xy 0.17907 -0.10414)
						(xy 0.17272 -0.11303) (xy 0.1651 -0.12065) (xy 0.1651 -0.7366) (xy 0.16256 -0.76835) (xy 0.1524 -0.8001)
						(xy 0.13716 -0.82804) (xy 0.11684 -0.85344) (xy 0.09144 -0.87376) (xy 0.0635 -0.889) (xy 0.03175 -0.89916)
					)
					(width 0)
					(fill yes)
				)
			)
		)
		(pad "25" smd custom
			(at -24.45004 -4.100068 180)
			(size 0.1143 0.1143)
			(layers "B.Cu" "B.Mask" "B.Paste")
			(net "M_B_DQS_DN1")
			(options
				(clearance outline)
				(anchor circle)
			)
			(primitives
				(gr_poly
					(pts
						(xy 0 -0.9017) (xy -0.03175 -0.89916) (xy -0.0635 -0.889) (xy -0.09144 -0.87376) (xy -0.11684 -0.85344)
						(xy -0.13716 -0.82804) (xy -0.1524 -0.8001) (xy -0.16256 -0.76835) (xy -0.1651 -0.7366) (xy -0.1651 -0.44958)
						(xy -0.17272 -0.44196) (xy -0.19812 -0.4064) (xy -0.2032 -0.39624) (xy -0.20701 -0.38735) (xy -0.21209 -0.37719)
						(xy -0.2159 -0.36703) (xy -0.21844 -0.35687) (xy -0.22225 -0.34544) (xy -0.22352 -0.33528) (xy -0.22606 -0.32512)
						(xy -0.22733 -0.31369) (xy -0.22733 -0.30353) (xy -0.2286 -0.2921) (xy -0.22733 -0.28067) (xy -0.22733 -0.27051)
						(xy -0.22606 -0.25908) (xy -0.22352 -0.24892) (xy -0.22225 -0.23876) (xy -0.21844 -0.22733) (xy -0.2159 -0.21717)
						(xy -0.21209 -0.20701) (xy -0.20701 -0.19685) (xy -0.2032 -0.18796) (xy -0.19812 -0.1778) (xy -0.17272 -0.14224)
						(xy -0.1651 -0.13462) (xy -0.1651 0.7366) (xy -0.16256 0.76835) (xy -0.1524 0.8001) (xy -0.13716 0.82804)
						(xy -0.11684 0.85344) (xy -0.09144 0.87376) (xy -0.0635 0.889) (xy -0.03175 0.89916) (xy 0 0.9017)
						(xy 0.03175 0.89916) (xy 0.0635 0.889) (xy 0.09144 0.87376) (xy 0.11684 0.85344) (xy 0.13716 0.82804)
						(xy 0.1524 0.8001) (xy 0.16256 0.76835) (xy 0.1651 0.7366) (xy 0.1651 -0.13462) (xy 0.17272 -0.14224)
						(xy 0.19812 -0.1778) (xy 0.2032 -0.18796) (xy 0.20701 -0.19685) (xy 0.21209 -0.20701) (xy 0.2159 -0.21717)
						(xy 0.21844 -0.22733) (xy 0.22225 -0.23876) (xy 0.22352 -0.24892) (xy 0.22606 -0.25908) (xy 0.22733 -0.27051)
						(xy 0.22733 -0.28067) (xy 0.2286 -0.2921) (xy 0.22733 -0.30353) (xy 0.22733 -0.31369) (xy 0.22606 -0.32512)
						(xy 0.22352 -0.33528) (xy 0.22225 -0.34544) (xy 0.21844 -0.35687) (xy 0.2159 -0.36703) (xy 0.21209 -0.37719)
						(xy 0.20701 -0.38735) (xy 0.2032 -0.39624) (xy 0.19812 -0.4064) (xy 0.17272 -0.44196) (xy 0.1651 -0.44958)
						(xy 0.1651 -0.7366) (xy 0.16256 -0.76835) (xy 0.1524 -0.8001) (xy 0.13716 -0.82804) (xy 0.11684 -0.85344)
						(xy 0.09144 -0.87376) (xy 0.0635 -0.889) (xy 0.03175 -0.89916)
					)
					(width 0)
					(fill yes)
				)
			)
		)
		(pad "26" smd custom
			(at -24.150066 4.100068 180)
			(size 0.1143 0.1143)
			(layers "B.Cu" "B.Mask" "B.Paste")
			(net "GND")
			(options
				(clearance outline)
				(anchor circle)
			)
			(primitives
				(gr_poly
					(pts
						(xy 0 -0.9017) (xy -0.03175 -0.89916) (xy -0.0635 -0.889) (xy -0.09144 -0.87376) (xy -0.11684 -0.85344)
						(xy -0.13716 -0.82804) (xy -0.1524 -0.8001) (xy -0.16256 -0.76835) (xy -0.1651 -0.7366) (xy -0.1651 0.13462)
						(xy -0.17272 0.14224) (xy -0.19812 0.1778) (xy -0.2032 0.18796) (xy -0.20701 0.19685) (xy -0.21209 0.20701)
						(xy -0.2159 0.21717) (xy -0.21844 0.22733) (xy -0.22225 0.23876) (xy -0.22352 0.24892) (xy -0.22606 0.25908)
						(xy -0.22733 0.27051) (xy -0.22733 0.28067) (xy -0.2286 0.2921) (xy -0.22733 0.30353) (xy -0.22733 0.31369)
						(xy -0.22606 0.32512) (xy -0.22352 0.33528) (xy -0.22225 0.34544) (xy -0.21844 0.35687) (xy -0.2159 0.36703)
						(xy -0.21209 0.37719) (xy -0.20701 0.38735) (xy -0.2032 0.39624) (xy -0.19812 0.4064) (xy -0.17272 0.44196)
						(xy -0.1651 0.44958) (xy -0.1651 0.7366) (xy -0.16256 0.76835) (xy -0.1524 0.8001) (xy -0.13716 0.82804)
						(xy -0.11684 0.85344) (xy -0.09144 0.87376) (xy -0.0635 0.889) (xy -0.03175 0.89916) (xy 0 0.9017)
						(xy 0.03175 0.89916) (xy 0.0635 0.889) (xy 0.09144 0.87376) (xy 0.11684 0.85344) (xy 0.13716 0.82804)
						(xy 0.1524 0.8001) (xy 0.16256 0.76835) (xy 0.1651 0.7366) (xy 0.1651 0.44958) (xy 0.17272 0.44196)
						(xy 0.19812 0.4064) (xy 0.2032 0.39624) (xy 0.20701 0.38735) (xy 0.21209 0.37719) (xy 0.2159 0.36703)
						(xy 0.21844 0.35687) (xy 0.22225 0.34544) (xy 0.22352 0.33528) (xy 0.22606 0.32512) (xy 0.22733 0.31369)
						(xy 0.22733 0.30353) (xy 0.2286 0.2921) (xy 0.22733 0.28067) (xy 0.22733 0.27051) (xy 0.22606 0.25908)
						(xy 0.22352 0.24892) (xy 0.22225 0.23876) (xy 0.21844 0.22733) (xy 0.2159 0.21717) (xy 0.21209 0.20701)
						(xy 0.20701 0.19685) (xy 0.2032 0.18796) (xy 0.19812 0.1778) (xy 0.17272 0.14224) (xy 0.1651 0.13462)
						(xy 0.1651 -0.7366) (xy 0.16256 -0.76835) (xy 0.1524 -0.8001) (xy 0.13716 -0.82804) (xy 0.11684 -0.85344)
						(xy 0.09144 -0.87376) (xy 0.0635 -0.889) (xy 0.03175 -0.89916)
					)
					(width 0)
					(fill yes)
				)
			)
		)
		(pad "27" smd custom
			(at -23.850092 -4.100068 180)
			(size 0.1143 0.1143)
			(layers "B.Cu" "B.Mask" "B.Paste")
			(net "M_B_DQS_DP1")
			(options
				(clearance outline)
				(anchor circle)
			)
			(primitives
				(gr_poly
					(pts
						(xy 0 -0.9017) (xy -0.03175 -0.89916) (xy -0.0635 -0.889) (xy -0.09144 -0.87376) (xy -0.11684 -0.85344)
						(xy -0.13716 -0.82804) (xy -0.1524 -0.8001) (xy -0.16256 -0.76835) (xy -0.1651 -0.7366) (xy -0.1651 -0.19685)
						(xy -0.17272 -0.18923) (xy -0.17907 -0.18034) (xy -0.18669 -0.17145) (xy -0.19177 -0.16256) (xy -0.19812 -0.15367)
						(xy -0.20828 -0.13335) (xy -0.21971 -0.10287) (xy -0.22225 -0.09271) (xy -0.22479 -0.08128) (xy -0.22606 -0.07112)
						(xy -0.2286 -0.05969) (xy -0.2286 -0.01651) (xy -0.22606 -0.00508) (xy -0.22479 0.00508) (xy -0.22225 0.01651)
						(xy -0.21971 0.02667) (xy -0.20828 0.05715) (xy -0.19812 0.07747) (xy -0.19177 0.08636) (xy -0.18669 0.09525)
						(xy -0.17907 0.10414) (xy -0.17272 0.11303) (xy -0.1651 0.12065) (xy -0.1651 0.7366) (xy -0.16256 0.76835)
						(xy -0.1524 0.8001) (xy -0.13716 0.82804) (xy -0.11684 0.85344) (xy -0.09144 0.87376) (xy -0.0635 0.889)
						(xy -0.03175 0.89916) (xy 0 0.9017) (xy 0.03175 0.89916) (xy 0.0635 0.889) (xy 0.09144 0.87376)
						(xy 0.11684 0.85344) (xy 0.13716 0.82804) (xy 0.1524 0.8001) (xy 0.16256 0.76835) (xy 0.1651 0.7366)
						(xy 0.1651 0.11938) (xy 0.17272 0.11176) (xy 0.19812 0.0762) (xy 0.2032 0.06604) (xy 0.20701 0.05715)
						(xy 0.21209 0.04699) (xy 0.2159 0.03683) (xy 0.21844 0.02667) (xy 0.22225 0.01524) (xy 0.22352 0.00508)
						(xy 0.22606 -0.00508) (xy 0.22733 -0.01651) (xy 0.22733 -0.02667) (xy 0.2286 -0.0381) (xy 0.22733 -0.04953)
						(xy 0.22733 -0.05969) (xy 0.22606 -0.07112) (xy 0.22352 -0.08128) (xy 0.22225 -0.09144) (xy 0.21844 -0.10287)
						(xy 0.2159 -0.11303) (xy 0.21209 -0.12319) (xy 0.20701 -0.13335) (xy 0.2032 -0.14224) (xy 0.19812 -0.1524)
						(xy 0.17272 -0.18796) (xy 0.1651 -0.19558) (xy 0.1651 -0.7366) (xy 0.16256 -0.76835) (xy 0.1524 -0.8001)
						(xy 0.13716 -0.82804) (xy 0.11684 -0.85344) (xy 0.09144 -0.87376) (xy 0.0635 -0.889) (xy 0.03175 -0.89916)
					)
					(width 0)
					(fill yes)
				)
			)
		)
		(pad "28" smd custom
			(at -23.550118 4.100068 180)
			(size 0.1143 0.1143)
			(layers "B.Cu" "B.Mask" "B.Paste")
			(net "GND")
			(options
				(clearance outline)
				(anchor circle)
			)
			(primitives
				(gr_poly
					(pts
						(xy 0 -0.9017) (xy -0.03175 -0.89916) (xy -0.0635 -0.889) (xy -0.09144 -0.87376) (xy -0.11684 -0.85344)
						(xy -0.13716 -0.82804) (xy -0.1524 -0.8001) (xy -0.16256 -0.76835) (xy -0.1651 -0.7366) (xy -0.1651 -0.11938)
						(xy -0.17272 -0.11176) (xy -0.19812 -0.0762) (xy -0.2032 -0.06604) (xy -0.20701 -0.05715) (xy -0.21209 -0.04699)
						(xy -0.2159 -0.03683) (xy -0.21844 -0.02667) (xy -0.22225 -0.01524) (xy -0.22352 -0.00508) (xy -0.22606 0.00508)
						(xy -0.22733 0.01651) (xy -0.22733 0.02667) (xy -0.2286 0.0381) (xy -0.22733 0.04953) (xy -0.22733 0.05969)
						(xy -0.22606 0.07112) (xy -0.22352 0.08128) (xy -0.22225 0.09144) (xy -0.21844 0.10287) (xy -0.2159 0.11303)
						(xy -0.21209 0.12319) (xy -0.20701 0.13335) (xy -0.2032 0.14224) (xy -0.19812 0.1524) (xy -0.17272 0.18796)
						(xy -0.1651 0.19558) (xy -0.1651 0.7366) (xy -0.16256 0.76835) (xy -0.1524 0.8001) (xy -0.13716 0.82804)
						(xy -0.11684 0.85344) (xy -0.09144 0.87376) (xy -0.0635 0.889) (xy -0.03175 0.89916) (xy 0 0.9017)
						(xy 0.03175 0.89916) (xy 0.0635 0.889) (xy 0.09144 0.87376) (xy 0.11684 0.85344) (xy 0.13716 0.82804)
						(xy 0.1524 0.8001) (xy 0.16256 0.76835) (xy 0.1651 0.7366) (xy 0.1651 0.19685) (xy 0.17272 0.18923)
						(xy 0.17907 0.18034) (xy 0.18669 0.17145) (xy 0.19177 0.16256) (xy 0.19812 0.15367) (xy 0.20828 0.13335)
						(xy 0.21971 0.10287) (xy 0.22225 0.09271) (xy 0.22479 0.08128) (xy 0.22606 0.07112) (xy 0.2286 0.05969)
						(xy 0.2286 0.01651) (xy 0.22606 0.00508) (xy 0.22479 -0.00508) (xy 0.22225 -0.01651) (xy 0.21971 -0.02667)
						(xy 0.20828 -0.05715) (xy 0.19812 -0.07747) (xy 0.19177 -0.08636) (xy 0.18669 -0.09525) (xy 0.17907 -0.10414)
						(xy 0.17272 -0.11303) (xy 0.1651 -0.12065) (xy 0.1651 -0.7366) (xy 0.16256 -0.76835) (xy 0.1524 -0.8001)
						(xy 0.13716 -0.82804) (xy 0.11684 -0.85344) (xy 0.09144 -0.87376) (xy 0.0635 -0.889) (xy 0.03175 -0.89916)
					)
					(width 0)
					(fill yes)
				)
			)
		)
		(pad "29" smd custom
			(at -23.24989 -4.100068 180)
			(size 0.1143 0.1143)
			(layers "B.Cu" "B.Mask" "B.Paste")
			(net "GND")
			(options
				(clearance outline)
				(anchor circle)
			)
			(primitives
				(gr_poly
					(pts
						(xy 0 -0.9017) (xy -0.03175 -0.89916) (xy -0.0635 -0.889) (xy -0.09144 -0.87376) (xy -0.11684 -0.85344)
						(xy -0.13716 -0.82804) (xy -0.1524 -0.8001) (xy -0.16256 -0.76835) (xy -0.1651 -0.7366) (xy -0.1651 -0.44958)
						(xy -0.17272 -0.44196) (xy -0.19812 -0.4064) (xy -0.2032 -0.39624) (xy -0.20701 -0.38735) (xy -0.21209 -0.37719)
						(xy -0.2159 -0.36703) (xy -0.21844 -0.35687) (xy -0.22225 -0.34544) (xy -0.22352 -0.33528) (xy -0.22606 -0.32512)
						(xy -0.22733 -0.31369) (xy -0.22733 -0.30353) (xy -0.2286 -0.2921) (xy -0.22733 -0.28067) (xy -0.22733 -0.27051)
						(xy -0.22606 -0.25908) (xy -0.22352 -0.24892) (xy -0.22225 -0.23876) (xy -0.21844 -0.22733) (xy -0.2159 -0.21717)
						(xy -0.21209 -0.20701) (xy -0.20701 -0.19685) (xy -0.2032 -0.18796) (xy -0.19812 -0.1778) (xy -0.17272 -0.14224)
						(xy -0.1651 -0.13462) (xy -0.1651 0.7366) (xy -0.16256 0.76835) (xy -0.1524 0.8001) (xy -0.13716 0.82804)
						(xy -0.11684 0.85344) (xy -0.09144 0.87376) (xy -0.0635 0.889) (xy -0.03175 0.89916) (xy 0 0.9017)
						(xy 0.03175 0.89916) (xy 0.0635 0.889) (xy 0.09144 0.87376) (xy 0.11684 0.85344) (xy 0.13716 0.82804)
						(xy 0.1524 0.8001) (xy 0.16256 0.76835) (xy 0.1651 0.7366) (xy 0.1651 -0.13462) (xy 0.17272 -0.14224)
						(xy 0.19812 -0.1778) (xy 0.2032 -0.18796) (xy 0.20701 -0.19685) (xy 0.21209 -0.20701) (xy 0.2159 -0.21717)
						(xy 0.21844 -0.22733) (xy 0.22225 -0.23876) (xy 0.22352 -0.24892) (xy 0.22606 -0.25908) (xy 0.22733 -0.27051)
						(xy 0.22733 -0.28067) (xy 0.2286 -0.2921) (xy 0.22733 -0.30353) (xy 0.22733 -0.31369) (xy 0.22606 -0.32512)
						(xy 0.22352 -0.33528) (xy 0.22225 -0.34544) (xy 0.21844 -0.35687) (xy 0.2159 -0.36703) (xy 0.21209 -0.37719)
						(xy 0.20701 -0.38735) (xy 0.2032 -0.39624) (xy 0.19812 -0.4064) (xy 0.17272 -0.44196) (xy 0.1651 -0.44958)
						(xy 0.1651 -0.7366) (xy 0.16256 -0.76835) (xy 0.1524 -0.8001) (xy 0.13716 -0.82804) (xy 0.11684 -0.85344)
						(xy 0.09144 -0.87376) (xy 0.0635 -0.889) (xy 0.03175 -0.89916)
					)
					(width 0)
					(fill yes)
				)
			)
		)
		(pad "30" smd custom
			(at -22.949916 4.100068 180)
			(size 0.1143 0.1143)
			(layers "B.Cu" "B.Mask" "B.Paste")
			(net "M_B_RESET#")
			(options
				(clearance outline)
				(anchor circle)
			)
			(primitives
				(gr_poly
					(pts
						(xy 0 -0.9017) (xy -0.03175 -0.89916) (xy -0.0635 -0.889) (xy -0.09144 -0.87376) (xy -0.11684 -0.85344)
						(xy -0.13716 -0.82804) (xy -0.1524 -0.8001) (xy -0.16256 -0.76835) (xy -0.1651 -0.7366) (xy -0.1651 0.13462)
						(xy -0.17272 0.14224) (xy -0.19812 0.1778) (xy -0.2032 0.18796) (xy -0.20701 0.19685) (xy -0.21209 0.20701)
						(xy -0.2159 0.21717) (xy -0.21844 0.22733) (xy -0.22225 0.23876) (xy -0.22352 0.24892) (xy -0.22606 0.25908)
						(xy -0.22733 0.27051) (xy -0.22733 0.28067) (xy -0.2286 0.2921) (xy -0.22733 0.30353) (xy -0.22733 0.31369)
						(xy -0.22606 0.32512) (xy -0.22352 0.33528) (xy -0.22225 0.34544) (xy -0.21844 0.35687) (xy -0.2159 0.36703)
						(xy -0.21209 0.37719) (xy -0.20701 0.38735) (xy -0.2032 0.39624) (xy -0.19812 0.4064) (xy -0.17272 0.44196)
						(xy -0.1651 0.44958) (xy -0.1651 0.7366) (xy -0.16256 0.76835) (xy -0.1524 0.8001) (xy -0.13716 0.82804)
						(xy -0.11684 0.85344) (xy -0.09144 0.87376) (xy -0.0635 0.889) (xy -0.03175 0.89916) (xy 0 0.9017)
						(xy 0.03175 0.89916) (xy 0.0635 0.889) (xy 0.09144 0.87376) (xy 0.11684 0.85344) (xy 0.13716 0.82804)
						(xy 0.1524 0.8001) (xy 0.16256 0.76835) (xy 0.1651 0.7366) (xy 0.1651 0.44958) (xy 0.17272 0.44196)
						(xy 0.19812 0.4064) (xy 0.2032 0.39624) (xy 0.20701 0.38735) (xy 0.21209 0.37719) (xy 0.2159 0.36703)
						(xy 0.21844 0.35687) (xy 0.22225 0.34544) (xy 0.22352 0.33528) (xy 0.22606 0.32512) (xy 0.22733 0.31369)
						(xy 0.22733 0.30353) (xy 0.2286 0.2921) (xy 0.22733 0.28067) (xy 0.22733 0.27051) (xy 0.22606 0.25908)
						(xy 0.22352 0.24892) (xy 0.22225 0.23876) (xy 0.21844 0.22733) (xy 0.2159 0.21717) (xy 0.21209 0.20701)
						(xy 0.20701 0.19685) (xy 0.2032 0.18796) (xy 0.19812 0.1778) (xy 0.17272 0.14224) (xy 0.1651 0.13462)
						(xy 0.1651 -0.7366) (xy 0.16256 -0.76835) (xy 0.1524 -0.8001) (xy 0.13716 -0.82804) (xy 0.11684 -0.85344)
						(xy 0.09144 -0.87376) (xy 0.0635 -0.889) (xy 0.03175 -0.89916)
					)
					(width 0)
					(fill yes)
				)
			)
		)
		(pad "31" smd custom
			(at -22.649942 -4.100068 180)
			(size 0.1143 0.1143)
			(layers "B.Cu" "B.Mask" "B.Paste")
			(net "M_B_DQ10")
			(options
				(clearance outline)
				(anchor circle)
			)
			(primitives
				(gr_poly
					(pts
						(xy 0 -0.9017) (xy -0.03175 -0.89916) (xy -0.0635 -0.889) (xy -0.09144 -0.87376) (xy -0.11684 -0.85344)
						(xy -0.13716 -0.82804) (xy -0.1524 -0.8001) (xy -0.16256 -0.76835) (xy -0.1651 -0.7366) (xy -0.1651 -0.19685)
						(xy -0.17272 -0.18923) (xy -0.17907 -0.18034) (xy -0.18669 -0.17145) (xy -0.19177 -0.16256) (xy -0.19812 -0.15367)
						(xy -0.20828 -0.13335) (xy -0.21971 -0.10287) (xy -0.22225 -0.09271) (xy -0.22479 -0.08128) (xy -0.22606 -0.07112)
						(xy -0.2286 -0.05969) (xy -0.2286 -0.01651) (xy -0.22606 -0.00508) (xy -0.22479 0.00508) (xy -0.22225 0.01651)
						(xy -0.21971 0.02667) (xy -0.20828 0.05715) (xy -0.19812 0.07747) (xy -0.19177 0.08636) (xy -0.18669 0.09525)
						(xy -0.17907 0.10414) (xy -0.17272 0.11303) (xy -0.1651 0.12065) (xy -0.1651 0.7366) (xy -0.16256 0.76835)
						(xy -0.1524 0.8001) (xy -0.13716 0.82804) (xy -0.11684 0.85344) (xy -0.09144 0.87376) (xy -0.0635 0.889)
						(xy -0.03175 0.89916) (xy 0 0.9017) (xy 0.03175 0.89916) (xy 0.0635 0.889) (xy 0.09144 0.87376)
						(xy 0.11684 0.85344) (xy 0.13716 0.82804) (xy 0.1524 0.8001) (xy 0.16256 0.76835) (xy 0.1651 0.7366)
						(xy 0.1651 0.11938) (xy 0.17272 0.11176) (xy 0.19812 0.0762) (xy 0.2032 0.06604) (xy 0.20701 0.05715)
						(xy 0.21209 0.04699) (xy 0.2159 0.03683) (xy 0.21844 0.02667) (xy 0.22225 0.01524) (xy 0.22352 0.00508)
						(xy 0.22606 -0.00508) (xy 0.22733 -0.01651) (xy 0.22733 -0.02667) (xy 0.2286 -0.0381) (xy 0.22733 -0.04953)
						(xy 0.22733 -0.05969) (xy 0.22606 -0.07112) (xy 0.22352 -0.08128) (xy 0.22225 -0.09144) (xy 0.21844 -0.10287)
						(xy 0.2159 -0.11303) (xy 0.21209 -0.12319) (xy 0.20701 -0.13335) (xy 0.2032 -0.14224) (xy 0.19812 -0.1524)
						(xy 0.17272 -0.18796) (xy 0.1651 -0.19558) (xy 0.1651 -0.7366) (xy 0.16256 -0.76835) (xy 0.1524 -0.8001)
						(xy 0.13716 -0.82804) (xy 0.11684 -0.85344) (xy 0.09144 -0.87376) (xy 0.0635 -0.889) (xy 0.03175 -0.89916)
					)
					(width 0)
					(fill yes)
				)
			)
		)
		(pad "32" smd custom
			(at -22.349968 4.100068 180)
			(size 0.1143 0.1143)
			(layers "B.Cu" "B.Mask" "B.Paste")
			(net "GND")
			(options
				(clearance outline)
				(anchor circle)
			)
			(primitives
				(gr_poly
					(pts
						(xy 0 -0.9017) (xy -0.03175 -0.89916) (xy -0.0635 -0.889) (xy -0.09144 -0.87376) (xy -0.11684 -0.85344)
						(xy -0.13716 -0.82804) (xy -0.1524 -0.8001) (xy -0.16256 -0.76835) (xy -0.1651 -0.7366) (xy -0.1651 -0.11938)
						(xy -0.17272 -0.11176) (xy -0.19812 -0.0762) (xy -0.2032 -0.06604) (xy -0.20701 -0.05715) (xy -0.21209 -0.04699)
						(xy -0.2159 -0.03683) (xy -0.21844 -0.02667) (xy -0.22225 -0.01524) (xy -0.22352 -0.00508) (xy -0.22606 0.00508)
						(xy -0.22733 0.01651) (xy -0.22733 0.02667) (xy -0.2286 0.0381) (xy -0.22733 0.04953) (xy -0.22733 0.05969)
						(xy -0.22606 0.07112) (xy -0.22352 0.08128) (xy -0.22225 0.09144) (xy -0.21844 0.10287) (xy -0.2159 0.11303)
						(xy -0.21209 0.12319) (xy -0.20701 0.13335) (xy -0.2032 0.14224) (xy -0.19812 0.1524) (xy -0.17272 0.18796)
						(xy -0.1651 0.19558) (xy -0.1651 0.7366) (xy -0.16256 0.76835) (xy -0.1524 0.8001) (xy -0.13716 0.82804)
						(xy -0.11684 0.85344) (xy -0.09144 0.87376) (xy -0.0635 0.889) (xy -0.03175 0.89916) (xy 0 0.9017)
						(xy 0.03175 0.89916) (xy 0.0635 0.889) (xy 0.09144 0.87376) (xy 0.11684 0.85344) (xy 0.13716 0.82804)
						(xy 0.1524 0.8001) (xy 0.16256 0.76835) (xy 0.1651 0.7366) (xy 0.1651 0.19685) (xy 0.17272 0.18923)
						(xy 0.17907 0.18034) (xy 0.18669 0.17145) (xy 0.19177 0.16256) (xy 0.19812 0.15367) (xy 0.20828 0.13335)
						(xy 0.21971 0.10287) (xy 0.22225 0.09271) (xy 0.22479 0.08128) (xy 0.22606 0.07112) (xy 0.2286 0.05969)
						(xy 0.2286 0.01651) (xy 0.22606 0.00508) (xy 0.22479 -0.00508) (xy 0.22225 -0.01651) (xy 0.21971 -0.02667)
						(xy 0.20828 -0.05715) (xy 0.19812 -0.07747) (xy 0.19177 -0.08636) (xy 0.18669 -0.09525) (xy 0.17907 -0.10414)
						(xy 0.17272 -0.11303) (xy 0.1651 -0.12065) (xy 0.1651 -0.7366) (xy 0.16256 -0.76835) (xy 0.1524 -0.8001)
						(xy 0.13716 -0.82804) (xy 0.11684 -0.85344) (xy 0.09144 -0.87376) (xy 0.0635 -0.889) (xy 0.03175 -0.89916)
					)
					(width 0)
					(fill yes)
				)
			)
		)
		(pad "33" smd custom
			(at -22.049994 -4.100068 180)
			(size 0.1143 0.1143)
			(layers "B.Cu" "B.Mask" "B.Paste")
			(net "M_B_DQ11")
			(options
				(clearance outline)
				(anchor circle)
			)
			(primitives
				(gr_poly
					(pts
						(xy 0 -0.9017) (xy -0.03175 -0.89916) (xy -0.0635 -0.889) (xy -0.09144 -0.87376) (xy -0.11684 -0.85344)
						(xy -0.13716 -0.82804) (xy -0.1524 -0.8001) (xy -0.16256 -0.76835) (xy -0.1651 -0.7366) (xy -0.1651 -0.44958)
						(xy -0.17272 -0.44196) (xy -0.19812 -0.4064) (xy -0.2032 -0.39624) (xy -0.20701 -0.38735) (xy -0.21209 -0.37719)
						(xy -0.2159 -0.36703) (xy -0.21844 -0.35687) (xy -0.22225 -0.34544) (xy -0.22352 -0.33528) (xy -0.22606 -0.32512)
						(xy -0.22733 -0.31369) (xy -0.22733 -0.30353) (xy -0.2286 -0.2921) (xy -0.22733 -0.28067) (xy -0.22733 -0.27051)
						(xy -0.22606 -0.25908) (xy -0.22352 -0.24892) (xy -0.22225 -0.23876) (xy -0.21844 -0.22733) (xy -0.2159 -0.21717)
						(xy -0.21209 -0.20701) (xy -0.20701 -0.19685) (xy -0.2032 -0.18796) (xy -0.19812 -0.1778) (xy -0.17272 -0.14224)
						(xy -0.1651 -0.13462) (xy -0.1651 0.7366) (xy -0.16256 0.76835) (xy -0.1524 0.8001) (xy -0.13716 0.82804)
						(xy -0.11684 0.85344) (xy -0.09144 0.87376) (xy -0.0635 0.889) (xy -0.03175 0.89916) (xy 0 0.9017)
						(xy 0.03175 0.89916) (xy 0.0635 0.889) (xy 0.09144 0.87376) (xy 0.11684 0.85344) (xy 0.13716 0.82804)
						(xy 0.1524 0.8001) (xy 0.16256 0.76835) (xy 0.1651 0.7366) (xy 0.1651 -0.13462) (xy 0.17272 -0.14224)
						(xy 0.19812 -0.1778) (xy 0.2032 -0.18796) (xy 0.20701 -0.19685) (xy 0.21209 -0.20701) (xy 0.2159 -0.21717)
						(xy 0.21844 -0.22733) (xy 0.22225 -0.23876) (xy 0.22352 -0.24892) (xy 0.22606 -0.25908) (xy 0.22733 -0.27051)
						(xy 0.22733 -0.28067) (xy 0.2286 -0.2921) (xy 0.22733 -0.30353) (xy 0.22733 -0.31369) (xy 0.22606 -0.32512)
						(xy 0.22352 -0.33528) (xy 0.22225 -0.34544) (xy 0.21844 -0.35687) (xy 0.2159 -0.36703) (xy 0.21209 -0.37719)
						(xy 0.20701 -0.38735) (xy 0.2032 -0.39624) (xy 0.19812 -0.4064) (xy 0.17272 -0.44196) (xy 0.1651 -0.44958)
						(xy 0.1651 -0.7366) (xy 0.16256 -0.76835) (xy 0.1524 -0.8001) (xy 0.13716 -0.82804) (xy 0.11684 -0.85344)
						(xy 0.09144 -0.87376) (xy 0.0635 -0.889) (xy 0.03175 -0.89916)
					)
					(width 0)
					(fill yes)
				)
			)
		)
		(pad "34" smd custom
			(at -21.75002 4.100068 180)
			(size 0.1143 0.1143)
			(layers "B.Cu" "B.Mask" "B.Paste")
			(net "M_B_DQ14")
			(options
				(clearance outline)
				(anchor circle)
			)
			(primitives
				(gr_poly
					(pts
						(xy 0 -0.9017) (xy -0.03175 -0.89916) (xy -0.0635 -0.889) (xy -0.09144 -0.87376) (xy -0.11684 -0.85344)
						(xy -0.13716 -0.82804) (xy -0.1524 -0.8001) (xy -0.16256 -0.76835) (xy -0.1651 -0.7366) (xy -0.1651 0.13462)
						(xy -0.17272 0.14224) (xy -0.19812 0.1778) (xy -0.2032 0.18796) (xy -0.20701 0.19685) (xy -0.21209 0.20701)
						(xy -0.2159 0.21717) (xy -0.21844 0.22733) (xy -0.22225 0.23876) (xy -0.22352 0.24892) (xy -0.22606 0.25908)
						(xy -0.22733 0.27051) (xy -0.22733 0.28067) (xy -0.2286 0.2921) (xy -0.22733 0.30353) (xy -0.22733 0.31369)
						(xy -0.22606 0.32512) (xy -0.22352 0.33528) (xy -0.22225 0.34544) (xy -0.21844 0.35687) (xy -0.2159 0.36703)
						(xy -0.21209 0.37719) (xy -0.20701 0.38735) (xy -0.2032 0.39624) (xy -0.19812 0.4064) (xy -0.17272 0.44196)
						(xy -0.1651 0.44958) (xy -0.1651 0.7366) (xy -0.16256 0.76835) (xy -0.1524 0.8001) (xy -0.13716 0.82804)
						(xy -0.11684 0.85344) (xy -0.09144 0.87376) (xy -0.0635 0.889) (xy -0.03175 0.89916) (xy 0 0.9017)
						(xy 0.03175 0.89916) (xy 0.0635 0.889) (xy 0.09144 0.87376) (xy 0.11684 0.85344) (xy 0.13716 0.82804)
						(xy 0.1524 0.8001) (xy 0.16256 0.76835) (xy 0.1651 0.7366) (xy 0.1651 0.44958) (xy 0.17272 0.44196)
						(xy 0.19812 0.4064) (xy 0.2032 0.39624) (xy 0.20701 0.38735) (xy 0.21209 0.37719) (xy 0.2159 0.36703)
						(xy 0.21844 0.35687) (xy 0.22225 0.34544) (xy 0.22352 0.33528) (xy 0.22606 0.32512) (xy 0.22733 0.31369)
						(xy 0.22733 0.30353) (xy 0.2286 0.2921) (xy 0.22733 0.28067) (xy 0.22733 0.27051) (xy 0.22606 0.25908)
						(xy 0.22352 0.24892) (xy 0.22225 0.23876) (xy 0.21844 0.22733) (xy 0.2159 0.21717) (xy 0.21209 0.20701)
						(xy 0.20701 0.19685) (xy 0.2032 0.18796) (xy 0.19812 0.1778) (xy 0.17272 0.14224) (xy 0.1651 0.13462)
						(xy 0.1651 -0.7366) (xy 0.16256 -0.76835) (xy 0.1524 -0.8001) (xy 0.13716 -0.82804) (xy 0.11684 -0.85344)
						(xy 0.09144 -0.87376) (xy 0.0635 -0.889) (xy 0.03175 -0.89916)
					)
					(width 0)
					(fill yes)
				)
			)
		)
		(pad "35" smd custom
			(at -21.450046 -4.100068 180)
			(size 0.1143 0.1143)
			(layers "B.Cu" "B.Mask" "B.Paste")
			(net "GND")
			(options
				(clearance outline)
				(anchor circle)
			)
			(primitives
				(gr_poly
					(pts
						(xy 0 -0.9017) (xy -0.03175 -0.89916) (xy -0.0635 -0.889) (xy -0.09144 -0.87376) (xy -0.11684 -0.85344)
						(xy -0.13716 -0.82804) (xy -0.1524 -0.8001) (xy -0.16256 -0.76835) (xy -0.1651 -0.7366) (xy -0.1651 -0.19685)
						(xy -0.17272 -0.18923) (xy -0.17907 -0.18034) (xy -0.18669 -0.17145) (xy -0.19177 -0.16256) (xy -0.19812 -0.15367)
						(xy -0.20828 -0.13335) (xy -0.21971 -0.10287) (xy -0.22225 -0.09271) (xy -0.22479 -0.08128) (xy -0.22606 -0.07112)
						(xy -0.2286 -0.05969) (xy -0.2286 -0.01651) (xy -0.22606 -0.00508) (xy -0.22479 0.00508) (xy -0.22225 0.01651)
						(xy -0.21971 0.02667) (xy -0.20828 0.05715) (xy -0.19812 0.07747) (xy -0.19177 0.08636) (xy -0.18669 0.09525)
						(xy -0.17907 0.10414) (xy -0.17272 0.11303) (xy -0.1651 0.12065) (xy -0.1651 0.7366) (xy -0.16256 0.76835)
						(xy -0.1524 0.8001) (xy -0.13716 0.82804) (xy -0.11684 0.85344) (xy -0.09144 0.87376) (xy -0.0635 0.889)
						(xy -0.03175 0.89916) (xy 0 0.9017) (xy 0.03175 0.89916) (xy 0.0635 0.889) (xy 0.09144 0.87376)
						(xy 0.11684 0.85344) (xy 0.13716 0.82804) (xy 0.1524 0.8001) (xy 0.16256 0.76835) (xy 0.1651 0.7366)
						(xy 0.1651 0.11938) (xy 0.17272 0.11176) (xy 0.19812 0.0762) (xy 0.2032 0.06604) (xy 0.20701 0.05715)
						(xy 0.21209 0.04699) (xy 0.2159 0.03683) (xy 0.21844 0.02667) (xy 0.22225 0.01524) (xy 0.22352 0.00508)
						(xy 0.22606 -0.00508) (xy 0.22733 -0.01651) (xy 0.22733 -0.02667) (xy 0.2286 -0.0381) (xy 0.22733 -0.04953)
						(xy 0.22733 -0.05969) (xy 0.22606 -0.07112) (xy 0.22352 -0.08128) (xy 0.22225 -0.09144) (xy 0.21844 -0.10287)
						(xy 0.2159 -0.11303) (xy 0.21209 -0.12319) (xy 0.20701 -0.13335) (xy 0.2032 -0.14224) (xy 0.19812 -0.1524)
						(xy 0.17272 -0.18796) (xy 0.1651 -0.19558) (xy 0.1651 -0.7366) (xy 0.16256 -0.76835) (xy 0.1524 -0.8001)
						(xy 0.13716 -0.82804) (xy 0.11684 -0.85344) (xy 0.09144 -0.87376) (xy 0.0635 -0.889) (xy 0.03175 -0.89916)
					)
					(width 0)
					(fill yes)
				)
			)
		)
		(pad "36" smd custom
			(at -21.150072 4.100068 180)
			(size 0.1143 0.1143)
			(layers "B.Cu" "B.Mask" "B.Paste")
			(net "M_B_DQ15")
			(options
				(clearance outline)
				(anchor circle)
			)
			(primitives
				(gr_poly
					(pts
						(xy 0 -0.9017) (xy -0.03175 -0.89916) (xy -0.0635 -0.889) (xy -0.09144 -0.87376) (xy -0.11684 -0.85344)
						(xy -0.13716 -0.82804) (xy -0.1524 -0.8001) (xy -0.16256 -0.76835) (xy -0.1651 -0.7366) (xy -0.1651 -0.11938)
						(xy -0.17272 -0.11176) (xy -0.19812 -0.0762) (xy -0.2032 -0.06604) (xy -0.20701 -0.05715) (xy -0.21209 -0.04699)
						(xy -0.2159 -0.03683) (xy -0.21844 -0.02667) (xy -0.22225 -0.01524) (xy -0.22352 -0.00508) (xy -0.22606 0.00508)
						(xy -0.22733 0.01651) (xy -0.22733 0.02667) (xy -0.2286 0.0381) (xy -0.22733 0.04953) (xy -0.22733 0.05969)
						(xy -0.22606 0.07112) (xy -0.22352 0.08128) (xy -0.22225 0.09144) (xy -0.21844 0.10287) (xy -0.2159 0.11303)
						(xy -0.21209 0.12319) (xy -0.20701 0.13335) (xy -0.2032 0.14224) (xy -0.19812 0.1524) (xy -0.17272 0.18796)
						(xy -0.1651 0.19558) (xy -0.1651 0.7366) (xy -0.16256 0.76835) (xy -0.1524 0.8001) (xy -0.13716 0.82804)
						(xy -0.11684 0.85344) (xy -0.09144 0.87376) (xy -0.0635 0.889) (xy -0.03175 0.89916) (xy 0 0.9017)
						(xy 0.03175 0.89916) (xy 0.0635 0.889) (xy 0.09144 0.87376) (xy 0.11684 0.85344) (xy 0.13716 0.82804)
						(xy 0.1524 0.8001) (xy 0.16256 0.76835) (xy 0.1651 0.7366) (xy 0.1651 0.19685) (xy 0.17272 0.18923)
						(xy 0.17907 0.18034) (xy 0.18669 0.17145) (xy 0.19177 0.16256) (xy 0.19812 0.15367) (xy 0.20828 0.13335)
						(xy 0.21971 0.10287) (xy 0.22225 0.09271) (xy 0.22479 0.08128) (xy 0.22606 0.07112) (xy 0.2286 0.05969)
						(xy 0.2286 0.01651) (xy 0.22606 0.00508) (xy 0.22479 -0.00508) (xy 0.22225 -0.01651) (xy 0.21971 -0.02667)
						(xy 0.20828 -0.05715) (xy 0.19812 -0.07747) (xy 0.19177 -0.08636) (xy 0.18669 -0.09525) (xy 0.17907 -0.10414)
						(xy 0.17272 -0.11303) (xy 0.1651 -0.12065) (xy 0.1651 -0.7366) (xy 0.16256 -0.76835) (xy 0.1524 -0.8001)
						(xy 0.13716 -0.82804) (xy 0.11684 -0.85344) (xy 0.09144 -0.87376) (xy 0.0635 -0.889) (xy 0.03175 -0.89916)
					)
					(width 0)
					(fill yes)
				)
			)
		)
		(pad "37" smd custom
			(at -20.850098 -4.100068 180)
			(size 0.1143 0.1143)
			(layers "B.Cu" "B.Mask" "B.Paste")
			(net "M_B_DQ16")
			(options
				(clearance outline)
				(anchor circle)
			)
			(primitives
				(gr_poly
					(pts
						(xy 0 -0.9017) (xy -0.03175 -0.89916) (xy -0.0635 -0.889) (xy -0.09144 -0.87376) (xy -0.11684 -0.85344)
						(xy -0.13716 -0.82804) (xy -0.1524 -0.8001) (xy -0.16256 -0.76835) (xy -0.1651 -0.7366) (xy -0.1651 -0.44958)
						(xy -0.17272 -0.44196) (xy -0.19812 -0.4064) (xy -0.2032 -0.39624) (xy -0.20701 -0.38735) (xy -0.21209 -0.37719)
						(xy -0.2159 -0.36703) (xy -0.21844 -0.35687) (xy -0.22225 -0.34544) (xy -0.22352 -0.33528) (xy -0.22606 -0.32512)
						(xy -0.22733 -0.31369) (xy -0.22733 -0.30353) (xy -0.2286 -0.2921) (xy -0.22733 -0.28067) (xy -0.22733 -0.27051)
						(xy -0.22606 -0.25908) (xy -0.22352 -0.24892) (xy -0.22225 -0.23876) (xy -0.21844 -0.22733) (xy -0.2159 -0.21717)
						(xy -0.21209 -0.20701) (xy -0.20701 -0.19685) (xy -0.2032 -0.18796) (xy -0.19812 -0.1778) (xy -0.17272 -0.14224)
						(xy -0.1651 -0.13462) (xy -0.1651 0.7366) (xy -0.16256 0.76835) (xy -0.1524 0.8001) (xy -0.13716 0.82804)
						(xy -0.11684 0.85344) (xy -0.09144 0.87376) (xy -0.0635 0.889) (xy -0.03175 0.89916) (xy 0 0.9017)
						(xy 0.03175 0.89916) (xy 0.0635 0.889) (xy 0.09144 0.87376) (xy 0.11684 0.85344) (xy 0.13716 0.82804)
						(xy 0.1524 0.8001) (xy 0.16256 0.76835) (xy 0.1651 0.7366) (xy 0.1651 -0.13462) (xy 0.17272 -0.14224)
						(xy 0.19812 -0.1778) (xy 0.2032 -0.18796) (xy 0.20701 -0.19685) (xy 0.21209 -0.20701) (xy 0.2159 -0.21717)
						(xy 0.21844 -0.22733) (xy 0.22225 -0.23876) (xy 0.22352 -0.24892) (xy 0.22606 -0.25908) (xy 0.22733 -0.27051)
						(xy 0.22733 -0.28067) (xy 0.2286 -0.2921) (xy 0.22733 -0.30353) (xy 0.22733 -0.31369) (xy 0.22606 -0.32512)
						(xy 0.22352 -0.33528) (xy 0.22225 -0.34544) (xy 0.21844 -0.35687) (xy 0.2159 -0.36703) (xy 0.21209 -0.37719)
						(xy 0.20701 -0.38735) (xy 0.2032 -0.39624) (xy 0.19812 -0.4064) (xy 0.17272 -0.44196) (xy 0.1651 -0.44958)
						(xy 0.1651 -0.7366) (xy 0.16256 -0.76835) (xy 0.1524 -0.8001) (xy 0.13716 -0.82804) (xy 0.11684 -0.85344)
						(xy 0.09144 -0.87376) (xy 0.0635 -0.889) (xy 0.03175 -0.89916)
					)
					(width 0)
					(fill yes)
				)
			)
		)
		(pad "38" smd custom
			(at -20.550124 4.100068 180)
			(size 0.1143 0.1143)
			(layers "B.Cu" "B.Mask" "B.Paste")
			(net "GND")
			(options
				(clearance outline)
				(anchor circle)
			)
			(primitives
				(gr_poly
					(pts
						(xy 0 -0.9017) (xy -0.03175 -0.89916) (xy -0.0635 -0.889) (xy -0.09144 -0.87376) (xy -0.11684 -0.85344)
						(xy -0.13716 -0.82804) (xy -0.1524 -0.8001) (xy -0.16256 -0.76835) (xy -0.1651 -0.7366) (xy -0.1651 0.13462)
						(xy -0.17272 0.14224) (xy -0.19812 0.1778) (xy -0.2032 0.18796) (xy -0.20701 0.19685) (xy -0.21209 0.20701)
						(xy -0.2159 0.21717) (xy -0.21844 0.22733) (xy -0.22225 0.23876) (xy -0.22352 0.24892) (xy -0.22606 0.25908)
						(xy -0.22733 0.27051) (xy -0.22733 0.28067) (xy -0.2286 0.2921) (xy -0.22733 0.30353) (xy -0.22733 0.31369)
						(xy -0.22606 0.32512) (xy -0.22352 0.33528) (xy -0.22225 0.34544) (xy -0.21844 0.35687) (xy -0.2159 0.36703)
						(xy -0.21209 0.37719) (xy -0.20701 0.38735) (xy -0.2032 0.39624) (xy -0.19812 0.4064) (xy -0.17272 0.44196)
						(xy -0.1651 0.44958) (xy -0.1651 0.7366) (xy -0.16256 0.76835) (xy -0.1524 0.8001) (xy -0.13716 0.82804)
						(xy -0.11684 0.85344) (xy -0.09144 0.87376) (xy -0.0635 0.889) (xy -0.03175 0.89916) (xy 0 0.9017)
						(xy 0.03175 0.89916) (xy 0.0635 0.889) (xy 0.09144 0.87376) (xy 0.11684 0.85344) (xy 0.13716 0.82804)
						(xy 0.1524 0.8001) (xy 0.16256 0.76835) (xy 0.1651 0.7366) (xy 0.1651 0.44958) (xy 0.17272 0.44196)
						(xy 0.19812 0.4064) (xy 0.2032 0.39624) (xy 0.20701 0.38735) (xy 0.21209 0.37719) (xy 0.2159 0.36703)
						(xy 0.21844 0.35687) (xy 0.22225 0.34544) (xy 0.22352 0.33528) (xy 0.22606 0.32512) (xy 0.22733 0.31369)
						(xy 0.22733 0.30353) (xy 0.2286 0.2921) (xy 0.22733 0.28067) (xy 0.22733 0.27051) (xy 0.22606 0.25908)
						(xy 0.22352 0.24892) (xy 0.22225 0.23876) (xy 0.21844 0.22733) (xy 0.2159 0.21717) (xy 0.21209 0.20701)
						(xy 0.20701 0.19685) (xy 0.2032 0.18796) (xy 0.19812 0.1778) (xy 0.17272 0.14224) (xy 0.1651 0.13462)
						(xy 0.1651 -0.7366) (xy 0.16256 -0.76835) (xy 0.1524 -0.8001) (xy 0.13716 -0.82804) (xy 0.11684 -0.85344)
						(xy 0.09144 -0.87376) (xy 0.0635 -0.889) (xy 0.03175 -0.89916)
					)
					(width 0)
					(fill yes)
				)
			)
		)
		(pad "39" smd custom
			(at -20.249896 -4.100068 180)
			(size 0.1143 0.1143)
			(layers "B.Cu" "B.Mask" "B.Paste")
			(net "M_B_DQ17")
			(options
				(clearance outline)
				(anchor circle)
			)
			(primitives
				(gr_poly
					(pts
						(xy 0 -0.9017) (xy -0.03175 -0.89916) (xy -0.0635 -0.889) (xy -0.09144 -0.87376) (xy -0.11684 -0.85344)
						(xy -0.13716 -0.82804) (xy -0.1524 -0.8001) (xy -0.16256 -0.76835) (xy -0.1651 -0.7366) (xy -0.1651 -0.19685)
						(xy -0.17272 -0.18923) (xy -0.17907 -0.18034) (xy -0.18669 -0.17145) (xy -0.19177 -0.16256) (xy -0.19812 -0.15367)
						(xy -0.20828 -0.13335) (xy -0.21971 -0.10287) (xy -0.22225 -0.09271) (xy -0.22479 -0.08128) (xy -0.22606 -0.07112)
						(xy -0.2286 -0.05969) (xy -0.2286 -0.01651) (xy -0.22606 -0.00508) (xy -0.22479 0.00508) (xy -0.22225 0.01651)
						(xy -0.21971 0.02667) (xy -0.20828 0.05715) (xy -0.19812 0.07747) (xy -0.19177 0.08636) (xy -0.18669 0.09525)
						(xy -0.17907 0.10414) (xy -0.17272 0.11303) (xy -0.1651 0.12065) (xy -0.1651 0.7366) (xy -0.16256 0.76835)
						(xy -0.1524 0.8001) (xy -0.13716 0.82804) (xy -0.11684 0.85344) (xy -0.09144 0.87376) (xy -0.0635 0.889)
						(xy -0.03175 0.89916) (xy 0 0.9017) (xy 0.03175 0.89916) (xy 0.0635 0.889) (xy 0.09144 0.87376)
						(xy 0.11684 0.85344) (xy 0.13716 0.82804) (xy 0.1524 0.8001) (xy 0.16256 0.76835) (xy 0.1651 0.7366)
						(xy 0.1651 0.11938) (xy 0.17272 0.11176) (xy 0.19812 0.0762) (xy 0.2032 0.06604) (xy 0.20701 0.05715)
						(xy 0.21209 0.04699) (xy 0.2159 0.03683) (xy 0.21844 0.02667) (xy 0.22225 0.01524) (xy 0.22352 0.00508)
						(xy 0.22606 -0.00508) (xy 0.22733 -0.01651) (xy 0.22733 -0.02667) (xy 0.2286 -0.0381) (xy 0.22733 -0.04953)
						(xy 0.22733 -0.05969) (xy 0.22606 -0.07112) (xy 0.22352 -0.08128) (xy 0.22225 -0.09144) (xy 0.21844 -0.10287)
						(xy 0.2159 -0.11303) (xy 0.21209 -0.12319) (xy 0.20701 -0.13335) (xy 0.2032 -0.14224) (xy 0.19812 -0.1524)
						(xy 0.17272 -0.18796) (xy 0.1651 -0.19558) (xy 0.1651 -0.7366) (xy 0.16256 -0.76835) (xy 0.1524 -0.8001)
						(xy 0.13716 -0.82804) (xy 0.11684 -0.85344) (xy 0.09144 -0.87376) (xy 0.0635 -0.889) (xy 0.03175 -0.89916)
					)
					(width 0)
					(fill yes)
				)
			)
		)
		(pad "40" smd custom
			(at -19.949922 4.100068 180)
			(size 0.1143 0.1143)
			(layers "B.Cu" "B.Mask" "B.Paste")
			(net "M_B_DQ20")
			(options
				(clearance outline)
				(anchor circle)
			)
			(primitives
				(gr_poly
					(pts
						(xy 0 -0.9017) (xy -0.03175 -0.89916) (xy -0.0635 -0.889) (xy -0.09144 -0.87376) (xy -0.11684 -0.85344)
						(xy -0.13716 -0.82804) (xy -0.1524 -0.8001) (xy -0.16256 -0.76835) (xy -0.1651 -0.7366) (xy -0.1651 -0.11938)
						(xy -0.17272 -0.11176) (xy -0.19812 -0.0762) (xy -0.2032 -0.06604) (xy -0.20701 -0.05715) (xy -0.21209 -0.04699)
						(xy -0.2159 -0.03683) (xy -0.21844 -0.02667) (xy -0.22225 -0.01524) (xy -0.22352 -0.00508) (xy -0.22606 0.00508)
						(xy -0.22733 0.01651) (xy -0.22733 0.02667) (xy -0.2286 0.0381) (xy -0.22733 0.04953) (xy -0.22733 0.05969)
						(xy -0.22606 0.07112) (xy -0.22352 0.08128) (xy -0.22225 0.09144) (xy -0.21844 0.10287) (xy -0.2159 0.11303)
						(xy -0.21209 0.12319) (xy -0.20701 0.13335) (xy -0.2032 0.14224) (xy -0.19812 0.1524) (xy -0.17272 0.18796)
						(xy -0.1651 0.19558) (xy -0.1651 0.7366) (xy -0.16256 0.76835) (xy -0.1524 0.8001) (xy -0.13716 0.82804)
						(xy -0.11684 0.85344) (xy -0.09144 0.87376) (xy -0.0635 0.889) (xy -0.03175 0.89916) (xy 0 0.9017)
						(xy 0.03175 0.89916) (xy 0.0635 0.889) (xy 0.09144 0.87376) (xy 0.11684 0.85344) (xy 0.13716 0.82804)
						(xy 0.1524 0.8001) (xy 0.16256 0.76835) (xy 0.1651 0.7366) (xy 0.1651 0.19685) (xy 0.17272 0.18923)
						(xy 0.17907 0.18034) (xy 0.18669 0.17145) (xy 0.19177 0.16256) (xy 0.19812 0.15367) (xy 0.20828 0.13335)
						(xy 0.21971 0.10287) (xy 0.22225 0.09271) (xy 0.22479 0.08128) (xy 0.22606 0.07112) (xy 0.2286 0.05969)
						(xy 0.2286 0.01651) (xy 0.22606 0.00508) (xy 0.22479 -0.00508) (xy 0.22225 -0.01651) (xy 0.21971 -0.02667)
						(xy 0.20828 -0.05715) (xy 0.19812 -0.07747) (xy 0.19177 -0.08636) (xy 0.18669 -0.09525) (xy 0.17907 -0.10414)
						(xy 0.17272 -0.11303) (xy 0.1651 -0.12065) (xy 0.1651 -0.7366) (xy 0.16256 -0.76835) (xy 0.1524 -0.8001)
						(xy 0.13716 -0.82804) (xy 0.11684 -0.85344) (xy 0.09144 -0.87376) (xy 0.0635 -0.889) (xy 0.03175 -0.89916)
					)
					(width 0)
					(fill yes)
				)
			)
		)
		(pad "41" smd custom
			(at -19.649948 -4.100068 180)
			(size 0.1143 0.1143)
			(layers "B.Cu" "B.Mask" "B.Paste")
			(net "GND")
			(options
				(clearance outline)
				(anchor circle)
			)
			(primitives
				(gr_poly
					(pts
						(xy 0 -0.9017) (xy -0.03175 -0.89916) (xy -0.0635 -0.889) (xy -0.09144 -0.87376) (xy -0.11684 -0.85344)
						(xy -0.13716 -0.82804) (xy -0.1524 -0.8001) (xy -0.16256 -0.76835) (xy -0.1651 -0.7366) (xy -0.1651 -0.44958)
						(xy -0.17272 -0.44196) (xy -0.19812 -0.4064) (xy -0.2032 -0.39624) (xy -0.20701 -0.38735) (xy -0.21209 -0.37719)
						(xy -0.2159 -0.36703) (xy -0.21844 -0.35687) (xy -0.22225 -0.34544) (xy -0.22352 -0.33528) (xy -0.22606 -0.32512)
						(xy -0.22733 -0.31369) (xy -0.22733 -0.30353) (xy -0.2286 -0.2921) (xy -0.22733 -0.28067) (xy -0.22733 -0.27051)
						(xy -0.22606 -0.25908) (xy -0.22352 -0.24892) (xy -0.22225 -0.23876) (xy -0.21844 -0.22733) (xy -0.2159 -0.21717)
						(xy -0.21209 -0.20701) (xy -0.20701 -0.19685) (xy -0.2032 -0.18796) (xy -0.19812 -0.1778) (xy -0.17272 -0.14224)
						(xy -0.1651 -0.13462) (xy -0.1651 0.7366) (xy -0.16256 0.76835) (xy -0.1524 0.8001) (xy -0.13716 0.82804)
						(xy -0.11684 0.85344) (xy -0.09144 0.87376) (xy -0.0635 0.889) (xy -0.03175 0.89916) (xy 0 0.9017)
						(xy 0.03175 0.89916) (xy 0.0635 0.889) (xy 0.09144 0.87376) (xy 0.11684 0.85344) (xy 0.13716 0.82804)
						(xy 0.1524 0.8001) (xy 0.16256 0.76835) (xy 0.1651 0.7366) (xy 0.1651 -0.13462) (xy 0.17272 -0.14224)
						(xy 0.19812 -0.1778) (xy 0.2032 -0.18796) (xy 0.20701 -0.19685) (xy 0.21209 -0.20701) (xy 0.2159 -0.21717)
						(xy 0.21844 -0.22733) (xy 0.22225 -0.23876) (xy 0.22352 -0.24892) (xy 0.22606 -0.25908) (xy 0.22733 -0.27051)
						(xy 0.22733 -0.28067) (xy 0.2286 -0.2921) (xy 0.22733 -0.30353) (xy 0.22733 -0.31369) (xy 0.22606 -0.32512)
						(xy 0.22352 -0.33528) (xy 0.22225 -0.34544) (xy 0.21844 -0.35687) (xy 0.2159 -0.36703) (xy 0.21209 -0.37719)
						(xy 0.20701 -0.38735) (xy 0.2032 -0.39624) (xy 0.19812 -0.4064) (xy 0.17272 -0.44196) (xy 0.1651 -0.44958)
						(xy 0.1651 -0.7366) (xy 0.16256 -0.76835) (xy 0.1524 -0.8001) (xy 0.13716 -0.82804) (xy 0.11684 -0.85344)
						(xy 0.09144 -0.87376) (xy 0.0635 -0.889) (xy 0.03175 -0.89916)
					)
					(width 0)
					(fill yes)
				)
			)
		)
		(pad "42" smd custom
			(at -19.349974 4.100068 180)
			(size 0.1143 0.1143)
			(layers "B.Cu" "B.Mask" "B.Paste")
			(net "M_B_DQ21")
			(options
				(clearance outline)
				(anchor circle)
			)
			(primitives
				(gr_poly
					(pts
						(xy 0 -0.9017) (xy -0.03175 -0.89916) (xy -0.0635 -0.889) (xy -0.09144 -0.87376) (xy -0.11684 -0.85344)
						(xy -0.13716 -0.82804) (xy -0.1524 -0.8001) (xy -0.16256 -0.76835) (xy -0.1651 -0.7366) (xy -0.1651 0.13462)
						(xy -0.17272 0.14224) (xy -0.19812 0.1778) (xy -0.2032 0.18796) (xy -0.20701 0.19685) (xy -0.21209 0.20701)
						(xy -0.2159 0.21717) (xy -0.21844 0.22733) (xy -0.22225 0.23876) (xy -0.22352 0.24892) (xy -0.22606 0.25908)
						(xy -0.22733 0.27051) (xy -0.22733 0.28067) (xy -0.2286 0.2921) (xy -0.22733 0.30353) (xy -0.22733 0.31369)
						(xy -0.22606 0.32512) (xy -0.22352 0.33528) (xy -0.22225 0.34544) (xy -0.21844 0.35687) (xy -0.2159 0.36703)
						(xy -0.21209 0.37719) (xy -0.20701 0.38735) (xy -0.2032 0.39624) (xy -0.19812 0.4064) (xy -0.17272 0.44196)
						(xy -0.1651 0.44958) (xy -0.1651 0.7366) (xy -0.16256 0.76835) (xy -0.1524 0.8001) (xy -0.13716 0.82804)
						(xy -0.11684 0.85344) (xy -0.09144 0.87376) (xy -0.0635 0.889) (xy -0.03175 0.89916) (xy 0 0.9017)
						(xy 0.03175 0.89916) (xy 0.0635 0.889) (xy 0.09144 0.87376) (xy 0.11684 0.85344) (xy 0.13716 0.82804)
						(xy 0.1524 0.8001) (xy 0.16256 0.76835) (xy 0.1651 0.7366) (xy 0.1651 0.44958) (xy 0.17272 0.44196)
						(xy 0.19812 0.4064) (xy 0.2032 0.39624) (xy 0.20701 0.38735) (xy 0.21209 0.37719) (xy 0.2159 0.36703)
						(xy 0.21844 0.35687) (xy 0.22225 0.34544) (xy 0.22352 0.33528) (xy 0.22606 0.32512) (xy 0.22733 0.31369)
						(xy 0.22733 0.30353) (xy 0.2286 0.2921) (xy 0.22733 0.28067) (xy 0.22733 0.27051) (xy 0.22606 0.25908)
						(xy 0.22352 0.24892) (xy 0.22225 0.23876) (xy 0.21844 0.22733) (xy 0.2159 0.21717) (xy 0.21209 0.20701)
						(xy 0.20701 0.19685) (xy 0.2032 0.18796) (xy 0.19812 0.1778) (xy 0.17272 0.14224) (xy 0.1651 0.13462)
						(xy 0.1651 -0.7366) (xy 0.16256 -0.76835) (xy 0.1524 -0.8001) (xy 0.13716 -0.82804) (xy 0.11684 -0.85344)
						(xy 0.09144 -0.87376) (xy 0.0635 -0.889) (xy 0.03175 -0.89916)
					)
					(width 0)
					(fill yes)
				)
			)
		)
		(pad "43" smd custom
			(at -19.05 -4.100068 180)
			(size 0.1143 0.1143)
			(layers "B.Cu" "B.Mask" "B.Paste")
			(net "M_B_DQS_DN2")
			(options
				(clearance outline)
				(anchor circle)
			)
			(primitives
				(gr_poly
					(pts
						(xy 0 -0.9017) (xy -0.03175 -0.89916) (xy -0.0635 -0.889) (xy -0.09144 -0.87376) (xy -0.11684 -0.85344)
						(xy -0.13716 -0.82804) (xy -0.1524 -0.8001) (xy -0.16256 -0.76835) (xy -0.1651 -0.7366) (xy -0.1651 -0.19685)
						(xy -0.17272 -0.18923) (xy -0.17907 -0.18034) (xy -0.18669 -0.17145) (xy -0.19177 -0.16256) (xy -0.19812 -0.15367)
						(xy -0.20828 -0.13335) (xy -0.21971 -0.10287) (xy -0.22225 -0.09271) (xy -0.22479 -0.08128) (xy -0.22606 -0.07112)
						(xy -0.2286 -0.05969) (xy -0.2286 -0.01651) (xy -0.22606 -0.00508) (xy -0.22479 0.00508) (xy -0.22225 0.01651)
						(xy -0.21971 0.02667) (xy -0.20828 0.05715) (xy -0.19812 0.07747) (xy -0.19177 0.08636) (xy -0.18669 0.09525)
						(xy -0.17907 0.10414) (xy -0.17272 0.11303) (xy -0.1651 0.12065) (xy -0.1651 0.7366) (xy -0.16256 0.76835)
						(xy -0.1524 0.8001) (xy -0.13716 0.82804) (xy -0.11684 0.85344) (xy -0.09144 0.87376) (xy -0.0635 0.889)
						(xy -0.03175 0.89916) (xy 0 0.9017) (xy 0.03175 0.89916) (xy 0.0635 0.889) (xy 0.09144 0.87376)
						(xy 0.11684 0.85344) (xy 0.13716 0.82804) (xy 0.1524 0.8001) (xy 0.16256 0.76835) (xy 0.1651 0.7366)
						(xy 0.1651 0.11938) (xy 0.17272 0.11176) (xy 0.19812 0.0762) (xy 0.2032 0.06604) (xy 0.20701 0.05715)
						(xy 0.21209 0.04699) (xy 0.2159 0.03683) (xy 0.21844 0.02667) (xy 0.22225 0.01524) (xy 0.22352 0.00508)
						(xy 0.22606 -0.00508) (xy 0.22733 -0.01651) (xy 0.22733 -0.02667) (xy 0.2286 -0.0381) (xy 0.22733 -0.04953)
						(xy 0.22733 -0.05969) (xy 0.22606 -0.07112) (xy 0.22352 -0.08128) (xy 0.22225 -0.09144) (xy 0.21844 -0.10287)
						(xy 0.2159 -0.11303) (xy 0.21209 -0.12319) (xy 0.20701 -0.13335) (xy 0.2032 -0.14224) (xy 0.19812 -0.1524)
						(xy 0.17272 -0.18796) (xy 0.1651 -0.19558) (xy 0.1651 -0.7366) (xy 0.16256 -0.76835) (xy 0.1524 -0.8001)
						(xy 0.13716 -0.82804) (xy 0.11684 -0.85344) (xy 0.09144 -0.87376) (xy 0.0635 -0.889) (xy 0.03175 -0.89916)
					)
					(width 0)
					(fill yes)
				)
			)
		)
		(pad "44" smd custom
			(at -18.750026 4.100068 180)
			(size 0.1143 0.1143)
			(layers "B.Cu" "B.Mask" "B.Paste")
			(net "GND")
			(options
				(clearance outline)
				(anchor circle)
			)
			(primitives
				(gr_poly
					(pts
						(xy 0 -0.9017) (xy -0.03175 -0.89916) (xy -0.0635 -0.889) (xy -0.09144 -0.87376) (xy -0.11684 -0.85344)
						(xy -0.13716 -0.82804) (xy -0.1524 -0.8001) (xy -0.16256 -0.76835) (xy -0.1651 -0.7366) (xy -0.1651 -0.11938)
						(xy -0.17272 -0.11176) (xy -0.19812 -0.0762) (xy -0.2032 -0.06604) (xy -0.20701 -0.05715) (xy -0.21209 -0.04699)
						(xy -0.2159 -0.03683) (xy -0.21844 -0.02667) (xy -0.22225 -0.01524) (xy -0.22352 -0.00508) (xy -0.22606 0.00508)
						(xy -0.22733 0.01651) (xy -0.22733 0.02667) (xy -0.2286 0.0381) (xy -0.22733 0.04953) (xy -0.22733 0.05969)
						(xy -0.22606 0.07112) (xy -0.22352 0.08128) (xy -0.22225 0.09144) (xy -0.21844 0.10287) (xy -0.2159 0.11303)
						(xy -0.21209 0.12319) (xy -0.20701 0.13335) (xy -0.2032 0.14224) (xy -0.19812 0.1524) (xy -0.17272 0.18796)
						(xy -0.1651 0.19558) (xy -0.1651 0.7366) (xy -0.16256 0.76835) (xy -0.1524 0.8001) (xy -0.13716 0.82804)
						(xy -0.11684 0.85344) (xy -0.09144 0.87376) (xy -0.0635 0.889) (xy -0.03175 0.89916) (xy 0 0.9017)
						(xy 0.03175 0.89916) (xy 0.0635 0.889) (xy 0.09144 0.87376) (xy 0.11684 0.85344) (xy 0.13716 0.82804)
						(xy 0.1524 0.8001) (xy 0.16256 0.76835) (xy 0.1651 0.7366) (xy 0.1651 0.19685) (xy 0.17272 0.18923)
						(xy 0.17907 0.18034) (xy 0.18669 0.17145) (xy 0.19177 0.16256) (xy 0.19812 0.15367) (xy 0.20828 0.13335)
						(xy 0.21971 0.10287) (xy 0.22225 0.09271) (xy 0.22479 0.08128) (xy 0.22606 0.07112) (xy 0.2286 0.05969)
						(xy 0.2286 0.01651) (xy 0.22606 0.00508) (xy 0.22479 -0.00508) (xy 0.22225 -0.01651) (xy 0.21971 -0.02667)
						(xy 0.20828 -0.05715) (xy 0.19812 -0.07747) (xy 0.19177 -0.08636) (xy 0.18669 -0.09525) (xy 0.17907 -0.10414)
						(xy 0.17272 -0.11303) (xy 0.1651 -0.12065) (xy 0.1651 -0.7366) (xy 0.16256 -0.76835) (xy 0.1524 -0.8001)
						(xy 0.13716 -0.82804) (xy 0.11684 -0.85344) (xy 0.09144 -0.87376) (xy 0.0635 -0.889) (xy 0.03175 -0.89916)
					)
					(width 0)
					(fill yes)
				)
			)
		)
		(pad "45" smd custom
			(at -18.450052 -4.100068 180)
			(size 0.1143 0.1143)
			(layers "B.Cu" "B.Mask" "B.Paste")
			(net "M_B_DQS_DP2")
			(options
				(clearance outline)
				(anchor circle)
			)
			(primitives
				(gr_poly
					(pts
						(xy 0 -0.9017) (xy -0.03175 -0.89916) (xy -0.0635 -0.889) (xy -0.09144 -0.87376) (xy -0.11684 -0.85344)
						(xy -0.13716 -0.82804) (xy -0.1524 -0.8001) (xy -0.16256 -0.76835) (xy -0.1651 -0.7366) (xy -0.1651 -0.44958)
						(xy -0.17272 -0.44196) (xy -0.19812 -0.4064) (xy -0.2032 -0.39624) (xy -0.20701 -0.38735) (xy -0.21209 -0.37719)
						(xy -0.2159 -0.36703) (xy -0.21844 -0.35687) (xy -0.22225 -0.34544) (xy -0.22352 -0.33528) (xy -0.22606 -0.32512)
						(xy -0.22733 -0.31369) (xy -0.22733 -0.30353) (xy -0.2286 -0.2921) (xy -0.22733 -0.28067) (xy -0.22733 -0.27051)
						(xy -0.22606 -0.25908) (xy -0.22352 -0.24892) (xy -0.22225 -0.23876) (xy -0.21844 -0.22733) (xy -0.2159 -0.21717)
						(xy -0.21209 -0.20701) (xy -0.20701 -0.19685) (xy -0.2032 -0.18796) (xy -0.19812 -0.1778) (xy -0.17272 -0.14224)
						(xy -0.1651 -0.13462) (xy -0.1651 0.7366) (xy -0.16256 0.76835) (xy -0.1524 0.8001) (xy -0.13716 0.82804)
						(xy -0.11684 0.85344) (xy -0.09144 0.87376) (xy -0.0635 0.889) (xy -0.03175 0.89916) (xy 0 0.9017)
						(xy 0.03175 0.89916) (xy 0.0635 0.889) (xy 0.09144 0.87376) (xy 0.11684 0.85344) (xy 0.13716 0.82804)
						(xy 0.1524 0.8001) (xy 0.16256 0.76835) (xy 0.1651 0.7366) (xy 0.1651 -0.13462) (xy 0.17272 -0.14224)
						(xy 0.19812 -0.1778) (xy 0.2032 -0.18796) (xy 0.20701 -0.19685) (xy 0.21209 -0.20701) (xy 0.2159 -0.21717)
						(xy 0.21844 -0.22733) (xy 0.22225 -0.23876) (xy 0.22352 -0.24892) (xy 0.22606 -0.25908) (xy 0.22733 -0.27051)
						(xy 0.22733 -0.28067) (xy 0.2286 -0.2921) (xy 0.22733 -0.30353) (xy 0.22733 -0.31369) (xy 0.22606 -0.32512)
						(xy 0.22352 -0.33528) (xy 0.22225 -0.34544) (xy 0.21844 -0.35687) (xy 0.2159 -0.36703) (xy 0.21209 -0.37719)
						(xy 0.20701 -0.38735) (xy 0.2032 -0.39624) (xy 0.19812 -0.4064) (xy 0.17272 -0.44196) (xy 0.1651 -0.44958)
						(xy 0.1651 -0.7366) (xy 0.16256 -0.76835) (xy 0.1524 -0.8001) (xy 0.13716 -0.82804) (xy 0.11684 -0.85344)
						(xy 0.09144 -0.87376) (xy 0.0635 -0.889) (xy 0.03175 -0.89916)
					)
					(width 0)
					(fill yes)
				)
			)
		)
		(pad "46" smd custom
			(at -18.150078 4.100068 180)
			(size 0.1143 0.1143)
			(layers "B.Cu" "B.Mask" "B.Paste")
			(net "GND")
			(options
				(clearance outline)
				(anchor circle)
			)
			(primitives
				(gr_poly
					(pts
						(xy 0 -0.9017) (xy -0.03175 -0.89916) (xy -0.0635 -0.889) (xy -0.09144 -0.87376) (xy -0.11684 -0.85344)
						(xy -0.13716 -0.82804) (xy -0.1524 -0.8001) (xy -0.16256 -0.76835) (xy -0.1651 -0.7366) (xy -0.1651 0.13462)
						(xy -0.17272 0.14224) (xy -0.19812 0.1778) (xy -0.2032 0.18796) (xy -0.20701 0.19685) (xy -0.21209 0.20701)
						(xy -0.2159 0.21717) (xy -0.21844 0.22733) (xy -0.22225 0.23876) (xy -0.22352 0.24892) (xy -0.22606 0.25908)
						(xy -0.22733 0.27051) (xy -0.22733 0.28067) (xy -0.2286 0.2921) (xy -0.22733 0.30353) (xy -0.22733 0.31369)
						(xy -0.22606 0.32512) (xy -0.22352 0.33528) (xy -0.22225 0.34544) (xy -0.21844 0.35687) (xy -0.2159 0.36703)
						(xy -0.21209 0.37719) (xy -0.20701 0.38735) (xy -0.2032 0.39624) (xy -0.19812 0.4064) (xy -0.17272 0.44196)
						(xy -0.1651 0.44958) (xy -0.1651 0.7366) (xy -0.16256 0.76835) (xy -0.1524 0.8001) (xy -0.13716 0.82804)
						(xy -0.11684 0.85344) (xy -0.09144 0.87376) (xy -0.0635 0.889) (xy -0.03175 0.89916) (xy 0 0.9017)
						(xy 0.03175 0.89916) (xy 0.0635 0.889) (xy 0.09144 0.87376) (xy 0.11684 0.85344) (xy 0.13716 0.82804)
						(xy 0.1524 0.8001) (xy 0.16256 0.76835) (xy 0.1651 0.7366) (xy 0.1651 0.44958) (xy 0.17272 0.44196)
						(xy 0.19812 0.4064) (xy 0.2032 0.39624) (xy 0.20701 0.38735) (xy 0.21209 0.37719) (xy 0.2159 0.36703)
						(xy 0.21844 0.35687) (xy 0.22225 0.34544) (xy 0.22352 0.33528) (xy 0.22606 0.32512) (xy 0.22733 0.31369)
						(xy 0.22733 0.30353) (xy 0.2286 0.2921) (xy 0.22733 0.28067) (xy 0.22733 0.27051) (xy 0.22606 0.25908)
						(xy 0.22352 0.24892) (xy 0.22225 0.23876) (xy 0.21844 0.22733) (xy 0.2159 0.21717) (xy 0.21209 0.20701)
						(xy 0.20701 0.19685) (xy 0.2032 0.18796) (xy 0.19812 0.1778) (xy 0.17272 0.14224) (xy 0.1651 0.13462)
						(xy 0.1651 -0.7366) (xy 0.16256 -0.76835) (xy 0.1524 -0.8001) (xy 0.13716 -0.82804) (xy 0.11684 -0.85344)
						(xy 0.09144 -0.87376) (xy 0.0635 -0.889) (xy 0.03175 -0.89916)
					)
					(width 0)
					(fill yes)
				)
			)
		)
		(pad "47" smd custom
			(at -17.850104 -4.100068 180)
			(size 0.1143 0.1143)
			(layers "B.Cu" "B.Mask" "B.Paste")
			(net "GND")
			(options
				(clearance outline)
				(anchor circle)
			)
			(primitives
				(gr_poly
					(pts
						(xy 0 -0.9017) (xy -0.03175 -0.89916) (xy -0.0635 -0.889) (xy -0.09144 -0.87376) (xy -0.11684 -0.85344)
						(xy -0.13716 -0.82804) (xy -0.1524 -0.8001) (xy -0.16256 -0.76835) (xy -0.1651 -0.7366) (xy -0.1651 -0.19685)
						(xy -0.17272 -0.18923) (xy -0.17907 -0.18034) (xy -0.18669 -0.17145) (xy -0.19177 -0.16256) (xy -0.19812 -0.15367)
						(xy -0.20828 -0.13335) (xy -0.21971 -0.10287) (xy -0.22225 -0.09271) (xy -0.22479 -0.08128) (xy -0.22606 -0.07112)
						(xy -0.2286 -0.05969) (xy -0.2286 -0.01651) (xy -0.22606 -0.00508) (xy -0.22479 0.00508) (xy -0.22225 0.01651)
						(xy -0.21971 0.02667) (xy -0.20828 0.05715) (xy -0.19812 0.07747) (xy -0.19177 0.08636) (xy -0.18669 0.09525)
						(xy -0.17907 0.10414) (xy -0.17272 0.11303) (xy -0.1651 0.12065) (xy -0.1651 0.7366) (xy -0.16256 0.76835)
						(xy -0.1524 0.8001) (xy -0.13716 0.82804) (xy -0.11684 0.85344) (xy -0.09144 0.87376) (xy -0.0635 0.889)
						(xy -0.03175 0.89916) (xy 0 0.9017) (xy 0.03175 0.89916) (xy 0.0635 0.889) (xy 0.09144 0.87376)
						(xy 0.11684 0.85344) (xy 0.13716 0.82804) (xy 0.1524 0.8001) (xy 0.16256 0.76835) (xy 0.1651 0.7366)
						(xy 0.1651 0.11938) (xy 0.17272 0.11176) (xy 0.19812 0.0762) (xy 0.2032 0.06604) (xy 0.20701 0.05715)
						(xy 0.21209 0.04699) (xy 0.2159 0.03683) (xy 0.21844 0.02667) (xy 0.22225 0.01524) (xy 0.22352 0.00508)
						(xy 0.22606 -0.00508) (xy 0.22733 -0.01651) (xy 0.22733 -0.02667) (xy 0.2286 -0.0381) (xy 0.22733 -0.04953)
						(xy 0.22733 -0.05969) (xy 0.22606 -0.07112) (xy 0.22352 -0.08128) (xy 0.22225 -0.09144) (xy 0.21844 -0.10287)
						(xy 0.2159 -0.11303) (xy 0.21209 -0.12319) (xy 0.20701 -0.13335) (xy 0.2032 -0.14224) (xy 0.19812 -0.1524)
						(xy 0.17272 -0.18796) (xy 0.1651 -0.19558) (xy 0.1651 -0.7366) (xy 0.16256 -0.76835) (xy 0.1524 -0.8001)
						(xy 0.13716 -0.82804) (xy 0.11684 -0.85344) (xy 0.09144 -0.87376) (xy 0.0635 -0.889) (xy 0.03175 -0.89916)
					)
					(width 0)
					(fill yes)
				)
			)
		)
		(pad "48" smd custom
			(at -17.549876 4.100068 180)
			(size 0.1143 0.1143)
			(layers "B.Cu" "B.Mask" "B.Paste")
			(net "M_B_DQ22")
			(options
				(clearance outline)
				(anchor circle)
			)
			(primitives
				(gr_poly
					(pts
						(xy 0 -0.9017) (xy -0.03175 -0.89916) (xy -0.0635 -0.889) (xy -0.09144 -0.87376) (xy -0.11684 -0.85344)
						(xy -0.13716 -0.82804) (xy -0.1524 -0.8001) (xy -0.16256 -0.76835) (xy -0.1651 -0.7366) (xy -0.1651 -0.11938)
						(xy -0.17272 -0.11176) (xy -0.19812 -0.0762) (xy -0.2032 -0.06604) (xy -0.20701 -0.05715) (xy -0.21209 -0.04699)
						(xy -0.2159 -0.03683) (xy -0.21844 -0.02667) (xy -0.22225 -0.01524) (xy -0.22352 -0.00508) (xy -0.22606 0.00508)
						(xy -0.22733 0.01651) (xy -0.22733 0.02667) (xy -0.2286 0.0381) (xy -0.22733 0.04953) (xy -0.22733 0.05969)
						(xy -0.22606 0.07112) (xy -0.22352 0.08128) (xy -0.22225 0.09144) (xy -0.21844 0.10287) (xy -0.2159 0.11303)
						(xy -0.21209 0.12319) (xy -0.20701 0.13335) (xy -0.2032 0.14224) (xy -0.19812 0.1524) (xy -0.17272 0.18796)
						(xy -0.1651 0.19558) (xy -0.1651 0.7366) (xy -0.16256 0.76835) (xy -0.1524 0.8001) (xy -0.13716 0.82804)
						(xy -0.11684 0.85344) (xy -0.09144 0.87376) (xy -0.0635 0.889) (xy -0.03175 0.89916) (xy 0 0.9017)
						(xy 0.03175 0.89916) (xy 0.0635 0.889) (xy 0.09144 0.87376) (xy 0.11684 0.85344) (xy 0.13716 0.82804)
						(xy 0.1524 0.8001) (xy 0.16256 0.76835) (xy 0.1651 0.7366) (xy 0.1651 0.19685) (xy 0.17272 0.18923)
						(xy 0.17907 0.18034) (xy 0.18669 0.17145) (xy 0.19177 0.16256) (xy 0.19812 0.15367) (xy 0.20828 0.13335)
						(xy 0.21971 0.10287) (xy 0.22225 0.09271) (xy 0.22479 0.08128) (xy 0.22606 0.07112) (xy 0.2286 0.05969)
						(xy 0.2286 0.01651) (xy 0.22606 0.00508) (xy 0.22479 -0.00508) (xy 0.22225 -0.01651) (xy 0.21971 -0.02667)
						(xy 0.20828 -0.05715) (xy 0.19812 -0.07747) (xy 0.19177 -0.08636) (xy 0.18669 -0.09525) (xy 0.17907 -0.10414)
						(xy 0.17272 -0.11303) (xy 0.1651 -0.12065) (xy 0.1651 -0.7366) (xy 0.16256 -0.76835) (xy 0.1524 -0.8001)
						(xy 0.13716 -0.82804) (xy 0.11684 -0.85344) (xy 0.09144 -0.87376) (xy 0.0635 -0.889) (xy 0.03175 -0.89916)
					)
					(width 0)
					(fill yes)
				)
			)
		)
		(pad "49" smd custom
			(at -17.249902 -4.100068 180)
			(size 0.1143 0.1143)
			(layers "B.Cu" "B.Mask" "B.Paste")
			(net "M_B_DQ18")
			(options
				(clearance outline)
				(anchor circle)
			)
			(primitives
				(gr_poly
					(pts
						(xy 0 -0.9017) (xy -0.03175 -0.89916) (xy -0.0635 -0.889) (xy -0.09144 -0.87376) (xy -0.11684 -0.85344)
						(xy -0.13716 -0.82804) (xy -0.1524 -0.8001) (xy -0.16256 -0.76835) (xy -0.1651 -0.7366) (xy -0.1651 -0.44958)
						(xy -0.17272 -0.44196) (xy -0.19812 -0.4064) (xy -0.2032 -0.39624) (xy -0.20701 -0.38735) (xy -0.21209 -0.37719)
						(xy -0.2159 -0.36703) (xy -0.21844 -0.35687) (xy -0.22225 -0.34544) (xy -0.22352 -0.33528) (xy -0.22606 -0.32512)
						(xy -0.22733 -0.31369) (xy -0.22733 -0.30353) (xy -0.2286 -0.2921) (xy -0.22733 -0.28067) (xy -0.22733 -0.27051)
						(xy -0.22606 -0.25908) (xy -0.22352 -0.24892) (xy -0.22225 -0.23876) (xy -0.21844 -0.22733) (xy -0.2159 -0.21717)
						(xy -0.21209 -0.20701) (xy -0.20701 -0.19685) (xy -0.2032 -0.18796) (xy -0.19812 -0.1778) (xy -0.17272 -0.14224)
						(xy -0.1651 -0.13462) (xy -0.1651 0.7366) (xy -0.16256 0.76835) (xy -0.1524 0.8001) (xy -0.13716 0.82804)
						(xy -0.11684 0.85344) (xy -0.09144 0.87376) (xy -0.0635 0.889) (xy -0.03175 0.89916) (xy 0 0.9017)
						(xy 0.03175 0.89916) (xy 0.0635 0.889) (xy 0.09144 0.87376) (xy 0.11684 0.85344) (xy 0.13716 0.82804)
						(xy 0.1524 0.8001) (xy 0.16256 0.76835) (xy 0.1651 0.7366) (xy 0.1651 -0.13462) (xy 0.17272 -0.14224)
						(xy 0.19812 -0.1778) (xy 0.2032 -0.18796) (xy 0.20701 -0.19685) (xy 0.21209 -0.20701) (xy 0.2159 -0.21717)
						(xy 0.21844 -0.22733) (xy 0.22225 -0.23876) (xy 0.22352 -0.24892) (xy 0.22606 -0.25908) (xy 0.22733 -0.27051)
						(xy 0.22733 -0.28067) (xy 0.2286 -0.2921) (xy 0.22733 -0.30353) (xy 0.22733 -0.31369) (xy 0.22606 -0.32512)
						(xy 0.22352 -0.33528) (xy 0.22225 -0.34544) (xy 0.21844 -0.35687) (xy 0.2159 -0.36703) (xy 0.21209 -0.37719)
						(xy 0.20701 -0.38735) (xy 0.2032 -0.39624) (xy 0.19812 -0.4064) (xy 0.17272 -0.44196) (xy 0.1651 -0.44958)
						(xy 0.1651 -0.7366) (xy 0.16256 -0.76835) (xy 0.1524 -0.8001) (xy 0.13716 -0.82804) (xy 0.11684 -0.85344)
						(xy 0.09144 -0.87376) (xy 0.0635 -0.889) (xy 0.03175 -0.89916)
					)
					(width 0)
					(fill yes)
				)
			)
		)
		(pad "50" smd custom
			(at -16.949928 4.100068 180)
			(size 0.1143 0.1143)
			(layers "B.Cu" "B.Mask" "B.Paste")
			(net "M_B_DQ23")
			(options
				(clearance outline)
				(anchor circle)
			)
			(primitives
				(gr_poly
					(pts
						(xy 0 -0.9017) (xy -0.03175 -0.89916) (xy -0.0635 -0.889) (xy -0.09144 -0.87376) (xy -0.11684 -0.85344)
						(xy -0.13716 -0.82804) (xy -0.1524 -0.8001) (xy -0.16256 -0.76835) (xy -0.1651 -0.7366) (xy -0.1651 0.13462)
						(xy -0.17272 0.14224) (xy -0.19812 0.1778) (xy -0.2032 0.18796) (xy -0.20701 0.19685) (xy -0.21209 0.20701)
						(xy -0.2159 0.21717) (xy -0.21844 0.22733) (xy -0.22225 0.23876) (xy -0.22352 0.24892) (xy -0.22606 0.25908)
						(xy -0.22733 0.27051) (xy -0.22733 0.28067) (xy -0.2286 0.2921) (xy -0.22733 0.30353) (xy -0.22733 0.31369)
						(xy -0.22606 0.32512) (xy -0.22352 0.33528) (xy -0.22225 0.34544) (xy -0.21844 0.35687) (xy -0.2159 0.36703)
						(xy -0.21209 0.37719) (xy -0.20701 0.38735) (xy -0.2032 0.39624) (xy -0.19812 0.4064) (xy -0.17272 0.44196)
						(xy -0.1651 0.44958) (xy -0.1651 0.7366) (xy -0.16256 0.76835) (xy -0.1524 0.8001) (xy -0.13716 0.82804)
						(xy -0.11684 0.85344) (xy -0.09144 0.87376) (xy -0.0635 0.889) (xy -0.03175 0.89916) (xy 0 0.9017)
						(xy 0.03175 0.89916) (xy 0.0635 0.889) (xy 0.09144 0.87376) (xy 0.11684 0.85344) (xy 0.13716 0.82804)
						(xy 0.1524 0.8001) (xy 0.16256 0.76835) (xy 0.1651 0.7366) (xy 0.1651 0.44958) (xy 0.17272 0.44196)
						(xy 0.19812 0.4064) (xy 0.2032 0.39624) (xy 0.20701 0.38735) (xy 0.21209 0.37719) (xy 0.2159 0.36703)
						(xy 0.21844 0.35687) (xy 0.22225 0.34544) (xy 0.22352 0.33528) (xy 0.22606 0.32512) (xy 0.22733 0.31369)
						(xy 0.22733 0.30353) (xy 0.2286 0.2921) (xy 0.22733 0.28067) (xy 0.22733 0.27051) (xy 0.22606 0.25908)
						(xy 0.22352 0.24892) (xy 0.22225 0.23876) (xy 0.21844 0.22733) (xy 0.2159 0.21717) (xy 0.21209 0.20701)
						(xy 0.20701 0.19685) (xy 0.2032 0.18796) (xy 0.19812 0.1778) (xy 0.17272 0.14224) (xy 0.1651 0.13462)
						(xy 0.1651 -0.7366) (xy 0.16256 -0.76835) (xy 0.1524 -0.8001) (xy 0.13716 -0.82804) (xy 0.11684 -0.85344)
						(xy 0.09144 -0.87376) (xy 0.0635 -0.889) (xy 0.03175 -0.89916)
					)
					(width 0)
					(fill yes)
				)
			)
		)
		(pad "51" smd custom
			(at -16.649954 -4.100068 180)
			(size 0.1143 0.1143)
			(layers "B.Cu" "B.Mask" "B.Paste")
			(net "M_B_DQ19")
			(options
				(clearance outline)
				(anchor circle)
			)
			(primitives
				(gr_poly
					(pts
						(xy 0 -0.9017) (xy -0.03175 -0.89916) (xy -0.0635 -0.889) (xy -0.09144 -0.87376) (xy -0.11684 -0.85344)
						(xy -0.13716 -0.82804) (xy -0.1524 -0.8001) (xy -0.16256 -0.76835) (xy -0.1651 -0.7366) (xy -0.1651 -0.19685)
						(xy -0.17272 -0.18923) (xy -0.17907 -0.18034) (xy -0.18669 -0.17145) (xy -0.19177 -0.16256) (xy -0.19812 -0.15367)
						(xy -0.20828 -0.13335) (xy -0.21971 -0.10287) (xy -0.22225 -0.09271) (xy -0.22479 -0.08128) (xy -0.22606 -0.07112)
						(xy -0.2286 -0.05969) (xy -0.2286 -0.01651) (xy -0.22606 -0.00508) (xy -0.22479 0.00508) (xy -0.22225 0.01651)
						(xy -0.21971 0.02667) (xy -0.20828 0.05715) (xy -0.19812 0.07747) (xy -0.19177 0.08636) (xy -0.18669 0.09525)
						(xy -0.17907 0.10414) (xy -0.17272 0.11303) (xy -0.1651 0.12065) (xy -0.1651 0.7366) (xy -0.16256 0.76835)
						(xy -0.1524 0.8001) (xy -0.13716 0.82804) (xy -0.11684 0.85344) (xy -0.09144 0.87376) (xy -0.0635 0.889)
						(xy -0.03175 0.89916) (xy 0 0.9017) (xy 0.03175 0.89916) (xy 0.0635 0.889) (xy 0.09144 0.87376)
						(xy 0.11684 0.85344) (xy 0.13716 0.82804) (xy 0.1524 0.8001) (xy 0.16256 0.76835) (xy 0.1651 0.7366)
						(xy 0.1651 0.11938) (xy 0.17272 0.11176) (xy 0.19812 0.0762) (xy 0.2032 0.06604) (xy 0.20701 0.05715)
						(xy 0.21209 0.04699) (xy 0.2159 0.03683) (xy 0.21844 0.02667) (xy 0.22225 0.01524) (xy 0.22352 0.00508)
						(xy 0.22606 -0.00508) (xy 0.22733 -0.01651) (xy 0.22733 -0.02667) (xy 0.2286 -0.0381) (xy 0.22733 -0.04953)
						(xy 0.22733 -0.05969) (xy 0.22606 -0.07112) (xy 0.22352 -0.08128) (xy 0.22225 -0.09144) (xy 0.21844 -0.10287)
						(xy 0.2159 -0.11303) (xy 0.21209 -0.12319) (xy 0.20701 -0.13335) (xy 0.2032 -0.14224) (xy 0.19812 -0.1524)
						(xy 0.17272 -0.18796) (xy 0.1651 -0.19558) (xy 0.1651 -0.7366) (xy 0.16256 -0.76835) (xy 0.1524 -0.8001)
						(xy 0.13716 -0.82804) (xy 0.11684 -0.85344) (xy 0.09144 -0.87376) (xy 0.0635 -0.889) (xy 0.03175 -0.89916)
					)
					(width 0)
					(fill yes)
				)
			)
		)
		(pad "52" smd custom
			(at -16.34998 4.100068 180)
			(size 0.1143 0.1143)
			(layers "B.Cu" "B.Mask" "B.Paste")
			(net "GND")
			(options
				(clearance outline)
				(anchor circle)
			)
			(primitives
				(gr_poly
					(pts
						(xy 0 -0.9017) (xy -0.03175 -0.89916) (xy -0.0635 -0.889) (xy -0.09144 -0.87376) (xy -0.11684 -0.85344)
						(xy -0.13716 -0.82804) (xy -0.1524 -0.8001) (xy -0.16256 -0.76835) (xy -0.1651 -0.7366) (xy -0.1651 -0.11938)
						(xy -0.17272 -0.11176) (xy -0.19812 -0.0762) (xy -0.2032 -0.06604) (xy -0.20701 -0.05715) (xy -0.21209 -0.04699)
						(xy -0.2159 -0.03683) (xy -0.21844 -0.02667) (xy -0.22225 -0.01524) (xy -0.22352 -0.00508) (xy -0.22606 0.00508)
						(xy -0.22733 0.01651) (xy -0.22733 0.02667) (xy -0.2286 0.0381) (xy -0.22733 0.04953) (xy -0.22733 0.05969)
						(xy -0.22606 0.07112) (xy -0.22352 0.08128) (xy -0.22225 0.09144) (xy -0.21844 0.10287) (xy -0.2159 0.11303)
						(xy -0.21209 0.12319) (xy -0.20701 0.13335) (xy -0.2032 0.14224) (xy -0.19812 0.1524) (xy -0.17272 0.18796)
						(xy -0.1651 0.19558) (xy -0.1651 0.7366) (xy -0.16256 0.76835) (xy -0.1524 0.8001) (xy -0.13716 0.82804)
						(xy -0.11684 0.85344) (xy -0.09144 0.87376) (xy -0.0635 0.889) (xy -0.03175 0.89916) (xy 0 0.9017)
						(xy 0.03175 0.89916) (xy 0.0635 0.889) (xy 0.09144 0.87376) (xy 0.11684 0.85344) (xy 0.13716 0.82804)
						(xy 0.1524 0.8001) (xy 0.16256 0.76835) (xy 0.1651 0.7366) (xy 0.1651 0.19685) (xy 0.17272 0.18923)
						(xy 0.17907 0.18034) (xy 0.18669 0.17145) (xy 0.19177 0.16256) (xy 0.19812 0.15367) (xy 0.20828 0.13335)
						(xy 0.21971 0.10287) (xy 0.22225 0.09271) (xy 0.22479 0.08128) (xy 0.22606 0.07112) (xy 0.2286 0.05969)
						(xy 0.2286 0.01651) (xy 0.22606 0.00508) (xy 0.22479 -0.00508) (xy 0.22225 -0.01651) (xy 0.21971 -0.02667)
						(xy 0.20828 -0.05715) (xy 0.19812 -0.07747) (xy 0.19177 -0.08636) (xy 0.18669 -0.09525) (xy 0.17907 -0.10414)
						(xy 0.17272 -0.11303) (xy 0.1651 -0.12065) (xy 0.1651 -0.7366) (xy 0.16256 -0.76835) (xy 0.1524 -0.8001)
						(xy 0.13716 -0.82804) (xy 0.11684 -0.85344) (xy 0.09144 -0.87376) (xy 0.0635 -0.889) (xy 0.03175 -0.89916)
					)
					(width 0)
					(fill yes)
				)
			)
		)
		(pad "53" smd custom
			(at -16.050006 -4.100068 180)
			(size 0.1143 0.1143)
			(layers "B.Cu" "B.Mask" "B.Paste")
			(net "GND")
			(options
				(clearance outline)
				(anchor circle)
			)
			(primitives
				(gr_poly
					(pts
						(xy 0 -0.9017) (xy -0.03175 -0.89916) (xy -0.0635 -0.889) (xy -0.09144 -0.87376) (xy -0.11684 -0.85344)
						(xy -0.13716 -0.82804) (xy -0.1524 -0.8001) (xy -0.16256 -0.76835) (xy -0.1651 -0.7366) (xy -0.1651 -0.44958)
						(xy -0.17272 -0.44196) (xy -0.19812 -0.4064) (xy -0.2032 -0.39624) (xy -0.20701 -0.38735) (xy -0.21209 -0.37719)
						(xy -0.2159 -0.36703) (xy -0.21844 -0.35687) (xy -0.22225 -0.34544) (xy -0.22352 -0.33528) (xy -0.22606 -0.32512)
						(xy -0.22733 -0.31369) (xy -0.22733 -0.30353) (xy -0.2286 -0.2921) (xy -0.22733 -0.28067) (xy -0.22733 -0.27051)
						(xy -0.22606 -0.25908) (xy -0.22352 -0.24892) (xy -0.22225 -0.23876) (xy -0.21844 -0.22733) (xy -0.2159 -0.21717)
						(xy -0.21209 -0.20701) (xy -0.20701 -0.19685) (xy -0.2032 -0.18796) (xy -0.19812 -0.1778) (xy -0.17272 -0.14224)
						(xy -0.1651 -0.13462) (xy -0.1651 0.7366) (xy -0.16256 0.76835) (xy -0.1524 0.8001) (xy -0.13716 0.82804)
						(xy -0.11684 0.85344) (xy -0.09144 0.87376) (xy -0.0635 0.889) (xy -0.03175 0.89916) (xy 0 0.9017)
						(xy 0.03175 0.89916) (xy 0.0635 0.889) (xy 0.09144 0.87376) (xy 0.11684 0.85344) (xy 0.13716 0.82804)
						(xy 0.1524 0.8001) (xy 0.16256 0.76835) (xy 0.1651 0.7366) (xy 0.1651 -0.13462) (xy 0.17272 -0.14224)
						(xy 0.19812 -0.1778) (xy 0.2032 -0.18796) (xy 0.20701 -0.19685) (xy 0.21209 -0.20701) (xy 0.2159 -0.21717)
						(xy 0.21844 -0.22733) (xy 0.22225 -0.23876) (xy 0.22352 -0.24892) (xy 0.22606 -0.25908) (xy 0.22733 -0.27051)
						(xy 0.22733 -0.28067) (xy 0.2286 -0.2921) (xy 0.22733 -0.30353) (xy 0.22733 -0.31369) (xy 0.22606 -0.32512)
						(xy 0.22352 -0.33528) (xy 0.22225 -0.34544) (xy 0.21844 -0.35687) (xy 0.2159 -0.36703) (xy 0.21209 -0.37719)
						(xy 0.20701 -0.38735) (xy 0.2032 -0.39624) (xy 0.19812 -0.4064) (xy 0.17272 -0.44196) (xy 0.1651 -0.44958)
						(xy 0.1651 -0.7366) (xy 0.16256 -0.76835) (xy 0.1524 -0.8001) (xy 0.13716 -0.82804) (xy 0.11684 -0.85344)
						(xy 0.09144 -0.87376) (xy 0.0635 -0.889) (xy 0.03175 -0.89916)
					)
					(width 0)
					(fill yes)
				)
			)
		)
		(pad "54" smd custom
			(at -15.750032 4.100068 180)
			(size 0.1143 0.1143)
			(layers "B.Cu" "B.Mask" "B.Paste")
			(net "M_B_DQ28")
			(options
				(clearance outline)
				(anchor circle)
			)
			(primitives
				(gr_poly
					(pts
						(xy 0 -0.9017) (xy -0.03175 -0.89916) (xy -0.0635 -0.889) (xy -0.09144 -0.87376) (xy -0.11684 -0.85344)
						(xy -0.13716 -0.82804) (xy -0.1524 -0.8001) (xy -0.16256 -0.76835) (xy -0.1651 -0.7366) (xy -0.1651 0.13462)
						(xy -0.17272 0.14224) (xy -0.19812 0.1778) (xy -0.2032 0.18796) (xy -0.20701 0.19685) (xy -0.21209 0.20701)
						(xy -0.2159 0.21717) (xy -0.21844 0.22733) (xy -0.22225 0.23876) (xy -0.22352 0.24892) (xy -0.22606 0.25908)
						(xy -0.22733 0.27051) (xy -0.22733 0.28067) (xy -0.2286 0.2921) (xy -0.22733 0.30353) (xy -0.22733 0.31369)
						(xy -0.22606 0.32512) (xy -0.22352 0.33528) (xy -0.22225 0.34544) (xy -0.21844 0.35687) (xy -0.2159 0.36703)
						(xy -0.21209 0.37719) (xy -0.20701 0.38735) (xy -0.2032 0.39624) (xy -0.19812 0.4064) (xy -0.17272 0.44196)
						(xy -0.1651 0.44958) (xy -0.1651 0.7366) (xy -0.16256 0.76835) (xy -0.1524 0.8001) (xy -0.13716 0.82804)
						(xy -0.11684 0.85344) (xy -0.09144 0.87376) (xy -0.0635 0.889) (xy -0.03175 0.89916) (xy 0 0.9017)
						(xy 0.03175 0.89916) (xy 0.0635 0.889) (xy 0.09144 0.87376) (xy 0.11684 0.85344) (xy 0.13716 0.82804)
						(xy 0.1524 0.8001) (xy 0.16256 0.76835) (xy 0.1651 0.7366) (xy 0.1651 0.44958) (xy 0.17272 0.44196)
						(xy 0.19812 0.4064) (xy 0.2032 0.39624) (xy 0.20701 0.38735) (xy 0.21209 0.37719) (xy 0.2159 0.36703)
						(xy 0.21844 0.35687) (xy 0.22225 0.34544) (xy 0.22352 0.33528) (xy 0.22606 0.32512) (xy 0.22733 0.31369)
						(xy 0.22733 0.30353) (xy 0.2286 0.2921) (xy 0.22733 0.28067) (xy 0.22733 0.27051) (xy 0.22606 0.25908)
						(xy 0.22352 0.24892) (xy 0.22225 0.23876) (xy 0.21844 0.22733) (xy 0.2159 0.21717) (xy 0.21209 0.20701)
						(xy 0.20701 0.19685) (xy 0.2032 0.18796) (xy 0.19812 0.1778) (xy 0.17272 0.14224) (xy 0.1651 0.13462)
						(xy 0.1651 -0.7366) (xy 0.16256 -0.76835) (xy 0.1524 -0.8001) (xy 0.13716 -0.82804) (xy 0.11684 -0.85344)
						(xy 0.09144 -0.87376) (xy 0.0635 -0.889) (xy 0.03175 -0.89916)
					)
					(width 0)
					(fill yes)
				)
			)
		)
		(pad "55" smd custom
			(at -15.450058 -4.100068 180)
			(size 0.1143 0.1143)
			(layers "B.Cu" "B.Mask" "B.Paste")
			(net "M_B_DQ24")
			(options
				(clearance outline)
				(anchor circle)
			)
			(primitives
				(gr_poly
					(pts
						(xy 0 -0.9017) (xy -0.03175 -0.89916) (xy -0.0635 -0.889) (xy -0.09144 -0.87376) (xy -0.11684 -0.85344)
						(xy -0.13716 -0.82804) (xy -0.1524 -0.8001) (xy -0.16256 -0.76835) (xy -0.1651 -0.7366) (xy -0.1651 -0.19685)
						(xy -0.17272 -0.18923) (xy -0.17907 -0.18034) (xy -0.18669 -0.17145) (xy -0.19177 -0.16256) (xy -0.19812 -0.15367)
						(xy -0.20828 -0.13335) (xy -0.21971 -0.10287) (xy -0.22225 -0.09271) (xy -0.22479 -0.08128) (xy -0.22606 -0.07112)
						(xy -0.2286 -0.05969) (xy -0.2286 -0.01651) (xy -0.22606 -0.00508) (xy -0.22479 0.00508) (xy -0.22225 0.01651)
						(xy -0.21971 0.02667) (xy -0.20828 0.05715) (xy -0.19812 0.07747) (xy -0.19177 0.08636) (xy -0.18669 0.09525)
						(xy -0.17907 0.10414) (xy -0.17272 0.11303) (xy -0.1651 0.12065) (xy -0.1651 0.7366) (xy -0.16256 0.76835)
						(xy -0.1524 0.8001) (xy -0.13716 0.82804) (xy -0.11684 0.85344) (xy -0.09144 0.87376) (xy -0.0635 0.889)
						(xy -0.03175 0.89916) (xy 0 0.9017) (xy 0.03175 0.89916) (xy 0.0635 0.889) (xy 0.09144 0.87376)
						(xy 0.11684 0.85344) (xy 0.13716 0.82804) (xy 0.1524 0.8001) (xy 0.16256 0.76835) (xy 0.1651 0.7366)
						(xy 0.1651 0.11938) (xy 0.17272 0.11176) (xy 0.19812 0.0762) (xy 0.2032 0.06604) (xy 0.20701 0.05715)
						(xy 0.21209 0.04699) (xy 0.2159 0.03683) (xy 0.21844 0.02667) (xy 0.22225 0.01524) (xy 0.22352 0.00508)
						(xy 0.22606 -0.00508) (xy 0.22733 -0.01651) (xy 0.22733 -0.02667) (xy 0.2286 -0.0381) (xy 0.22733 -0.04953)
						(xy 0.22733 -0.05969) (xy 0.22606 -0.07112) (xy 0.22352 -0.08128) (xy 0.22225 -0.09144) (xy 0.21844 -0.10287)
						(xy 0.2159 -0.11303) (xy 0.21209 -0.12319) (xy 0.20701 -0.13335) (xy 0.2032 -0.14224) (xy 0.19812 -0.1524)
						(xy 0.17272 -0.18796) (xy 0.1651 -0.19558) (xy 0.1651 -0.7366) (xy 0.16256 -0.76835) (xy 0.1524 -0.8001)
						(xy 0.13716 -0.82804) (xy 0.11684 -0.85344) (xy 0.09144 -0.87376) (xy 0.0635 -0.889) (xy 0.03175 -0.89916)
					)
					(width 0)
					(fill yes)
				)
			)
		)
		(pad "56" smd custom
			(at -15.150084 4.100068 180)
			(size 0.1143 0.1143)
			(layers "B.Cu" "B.Mask" "B.Paste")
			(net "M_B_DQ29")
			(options
				(clearance outline)
				(anchor circle)
			)
			(primitives
				(gr_poly
					(pts
						(xy 0 -0.9017) (xy -0.03175 -0.89916) (xy -0.0635 -0.889) (xy -0.09144 -0.87376) (xy -0.11684 -0.85344)
						(xy -0.13716 -0.82804) (xy -0.1524 -0.8001) (xy -0.16256 -0.76835) (xy -0.1651 -0.7366) (xy -0.1651 -0.11938)
						(xy -0.17272 -0.11176) (xy -0.19812 -0.0762) (xy -0.2032 -0.06604) (xy -0.20701 -0.05715) (xy -0.21209 -0.04699)
						(xy -0.2159 -0.03683) (xy -0.21844 -0.02667) (xy -0.22225 -0.01524) (xy -0.22352 -0.00508) (xy -0.22606 0.00508)
						(xy -0.22733 0.01651) (xy -0.22733 0.02667) (xy -0.2286 0.0381) (xy -0.22733 0.04953) (xy -0.22733 0.05969)
						(xy -0.22606 0.07112) (xy -0.22352 0.08128) (xy -0.22225 0.09144) (xy -0.21844 0.10287) (xy -0.2159 0.11303)
						(xy -0.21209 0.12319) (xy -0.20701 0.13335) (xy -0.2032 0.14224) (xy -0.19812 0.1524) (xy -0.17272 0.18796)
						(xy -0.1651 0.19558) (xy -0.1651 0.7366) (xy -0.16256 0.76835) (xy -0.1524 0.8001) (xy -0.13716 0.82804)
						(xy -0.11684 0.85344) (xy -0.09144 0.87376) (xy -0.0635 0.889) (xy -0.03175 0.89916) (xy 0 0.9017)
						(xy 0.03175 0.89916) (xy 0.0635 0.889) (xy 0.09144 0.87376) (xy 0.11684 0.85344) (xy 0.13716 0.82804)
						(xy 0.1524 0.8001) (xy 0.16256 0.76835) (xy 0.1651 0.7366) (xy 0.1651 0.19685) (xy 0.17272 0.18923)
						(xy 0.17907 0.18034) (xy 0.18669 0.17145) (xy 0.19177 0.16256) (xy 0.19812 0.15367) (xy 0.20828 0.13335)
						(xy 0.21971 0.10287) (xy 0.22225 0.09271) (xy 0.22479 0.08128) (xy 0.22606 0.07112) (xy 0.2286 0.05969)
						(xy 0.2286 0.01651) (xy 0.22606 0.00508) (xy 0.22479 -0.00508) (xy 0.22225 -0.01651) (xy 0.21971 -0.02667)
						(xy 0.20828 -0.05715) (xy 0.19812 -0.07747) (xy 0.19177 -0.08636) (xy 0.18669 -0.09525) (xy 0.17907 -0.10414)
						(xy 0.17272 -0.11303) (xy 0.1651 -0.12065) (xy 0.1651 -0.7366) (xy 0.16256 -0.76835) (xy 0.1524 -0.8001)
						(xy 0.13716 -0.82804) (xy 0.11684 -0.85344) (xy 0.09144 -0.87376) (xy 0.0635 -0.889) (xy 0.03175 -0.89916)
					)
					(width 0)
					(fill yes)
				)
			)
		)
		(pad "57" smd custom
			(at -14.85011 -4.100068 180)
			(size 0.1143 0.1143)
			(layers "B.Cu" "B.Mask" "B.Paste")
			(net "M_B_DQ25")
			(options
				(clearance outline)
				(anchor circle)
			)
			(primitives
				(gr_poly
					(pts
						(xy 0 -0.9017) (xy -0.03175 -0.89916) (xy -0.0635 -0.889) (xy -0.09144 -0.87376) (xy -0.11684 -0.85344)
						(xy -0.13716 -0.82804) (xy -0.1524 -0.8001) (xy -0.16256 -0.76835) (xy -0.1651 -0.7366) (xy -0.1651 -0.44958)
						(xy -0.17272 -0.44196) (xy -0.19812 -0.4064) (xy -0.2032 -0.39624) (xy -0.20701 -0.38735) (xy -0.21209 -0.37719)
						(xy -0.2159 -0.36703) (xy -0.21844 -0.35687) (xy -0.22225 -0.34544) (xy -0.22352 -0.33528) (xy -0.22606 -0.32512)
						(xy -0.22733 -0.31369) (xy -0.22733 -0.30353) (xy -0.2286 -0.2921) (xy -0.22733 -0.28067) (xy -0.22733 -0.27051)
						(xy -0.22606 -0.25908) (xy -0.22352 -0.24892) (xy -0.22225 -0.23876) (xy -0.21844 -0.22733) (xy -0.2159 -0.21717)
						(xy -0.21209 -0.20701) (xy -0.20701 -0.19685) (xy -0.2032 -0.18796) (xy -0.19812 -0.1778) (xy -0.17272 -0.14224)
						(xy -0.1651 -0.13462) (xy -0.1651 0.7366) (xy -0.16256 0.76835) (xy -0.1524 0.8001) (xy -0.13716 0.82804)
						(xy -0.11684 0.85344) (xy -0.09144 0.87376) (xy -0.0635 0.889) (xy -0.03175 0.89916) (xy 0 0.9017)
						(xy 0.03175 0.89916) (xy 0.0635 0.889) (xy 0.09144 0.87376) (xy 0.11684 0.85344) (xy 0.13716 0.82804)
						(xy 0.1524 0.8001) (xy 0.16256 0.76835) (xy 0.1651 0.7366) (xy 0.1651 -0.13462) (xy 0.17272 -0.14224)
						(xy 0.19812 -0.1778) (xy 0.2032 -0.18796) (xy 0.20701 -0.19685) (xy 0.21209 -0.20701) (xy 0.2159 -0.21717)
						(xy 0.21844 -0.22733) (xy 0.22225 -0.23876) (xy 0.22352 -0.24892) (xy 0.22606 -0.25908) (xy 0.22733 -0.27051)
						(xy 0.22733 -0.28067) (xy 0.2286 -0.2921) (xy 0.22733 -0.30353) (xy 0.22733 -0.31369) (xy 0.22606 -0.32512)
						(xy 0.22352 -0.33528) (xy 0.22225 -0.34544) (xy 0.21844 -0.35687) (xy 0.2159 -0.36703) (xy 0.21209 -0.37719)
						(xy 0.20701 -0.38735) (xy 0.2032 -0.39624) (xy 0.19812 -0.4064) (xy 0.17272 -0.44196) (xy 0.1651 -0.44958)
						(xy 0.1651 -0.7366) (xy 0.16256 -0.76835) (xy 0.1524 -0.8001) (xy 0.13716 -0.82804) (xy 0.11684 -0.85344)
						(xy 0.09144 -0.87376) (xy 0.0635 -0.889) (xy 0.03175 -0.89916)
					)
					(width 0)
					(fill yes)
				)
			)
		)
		(pad "58" smd custom
			(at -14.549882 4.100068 180)
			(size 0.1143 0.1143)
			(layers "B.Cu" "B.Mask" "B.Paste")
			(net "GND")
			(options
				(clearance outline)
				(anchor circle)
			)
			(primitives
				(gr_poly
					(pts
						(xy 0 -0.9017) (xy -0.03175 -0.89916) (xy -0.0635 -0.889) (xy -0.09144 -0.87376) (xy -0.11684 -0.85344)
						(xy -0.13716 -0.82804) (xy -0.1524 -0.8001) (xy -0.16256 -0.76835) (xy -0.1651 -0.7366) (xy -0.1651 0.13462)
						(xy -0.17272 0.14224) (xy -0.19812 0.1778) (xy -0.2032 0.18796) (xy -0.20701 0.19685) (xy -0.21209 0.20701)
						(xy -0.2159 0.21717) (xy -0.21844 0.22733) (xy -0.22225 0.23876) (xy -0.22352 0.24892) (xy -0.22606 0.25908)
						(xy -0.22733 0.27051) (xy -0.22733 0.28067) (xy -0.2286 0.2921) (xy -0.22733 0.30353) (xy -0.22733 0.31369)
						(xy -0.22606 0.32512) (xy -0.22352 0.33528) (xy -0.22225 0.34544) (xy -0.21844 0.35687) (xy -0.2159 0.36703)
						(xy -0.21209 0.37719) (xy -0.20701 0.38735) (xy -0.2032 0.39624) (xy -0.19812 0.4064) (xy -0.17272 0.44196)
						(xy -0.1651 0.44958) (xy -0.1651 0.7366) (xy -0.16256 0.76835) (xy -0.1524 0.8001) (xy -0.13716 0.82804)
						(xy -0.11684 0.85344) (xy -0.09144 0.87376) (xy -0.0635 0.889) (xy -0.03175 0.89916) (xy 0 0.9017)
						(xy 0.03175 0.89916) (xy 0.0635 0.889) (xy 0.09144 0.87376) (xy 0.11684 0.85344) (xy 0.13716 0.82804)
						(xy 0.1524 0.8001) (xy 0.16256 0.76835) (xy 0.1651 0.7366) (xy 0.1651 0.44958) (xy 0.17272 0.44196)
						(xy 0.19812 0.4064) (xy 0.2032 0.39624) (xy 0.20701 0.38735) (xy 0.21209 0.37719) (xy 0.2159 0.36703)
						(xy 0.21844 0.35687) (xy 0.22225 0.34544) (xy 0.22352 0.33528) (xy 0.22606 0.32512) (xy 0.22733 0.31369)
						(xy 0.22733 0.30353) (xy 0.2286 0.2921) (xy 0.22733 0.28067) (xy 0.22733 0.27051) (xy 0.22606 0.25908)
						(xy 0.22352 0.24892) (xy 0.22225 0.23876) (xy 0.21844 0.22733) (xy 0.2159 0.21717) (xy 0.21209 0.20701)
						(xy 0.20701 0.19685) (xy 0.2032 0.18796) (xy 0.19812 0.1778) (xy 0.17272 0.14224) (xy 0.1651 0.13462)
						(xy 0.1651 -0.7366) (xy 0.16256 -0.76835) (xy 0.1524 -0.8001) (xy 0.13716 -0.82804) (xy 0.11684 -0.85344)
						(xy 0.09144 -0.87376) (xy 0.0635 -0.889) (xy 0.03175 -0.89916)
					)
					(width 0)
					(fill yes)
				)
			)
		)
		(pad "59" smd custom
			(at -14.249908 -4.100068 180)
			(size 0.1143 0.1143)
			(layers "B.Cu" "B.Mask" "B.Paste")
			(net "GND")
			(options
				(clearance outline)
				(anchor circle)
			)
			(primitives
				(gr_poly
					(pts
						(xy 0 -0.9017) (xy -0.03175 -0.89916) (xy -0.0635 -0.889) (xy -0.09144 -0.87376) (xy -0.11684 -0.85344)
						(xy -0.13716 -0.82804) (xy -0.1524 -0.8001) (xy -0.16256 -0.76835) (xy -0.1651 -0.7366) (xy -0.1651 -0.19685)
						(xy -0.17272 -0.18923) (xy -0.17907 -0.18034) (xy -0.18669 -0.17145) (xy -0.19177 -0.16256) (xy -0.19812 -0.15367)
						(xy -0.20828 -0.13335) (xy -0.21971 -0.10287) (xy -0.22225 -0.09271) (xy -0.22479 -0.08128) (xy -0.22606 -0.07112)
						(xy -0.2286 -0.05969) (xy -0.2286 -0.01651) (xy -0.22606 -0.00508) (xy -0.22479 0.00508) (xy -0.22225 0.01651)
						(xy -0.21971 0.02667) (xy -0.20828 0.05715) (xy -0.19812 0.07747) (xy -0.19177 0.08636) (xy -0.18669 0.09525)
						(xy -0.17907 0.10414) (xy -0.17272 0.11303) (xy -0.1651 0.12065) (xy -0.1651 0.7366) (xy -0.16256 0.76835)
						(xy -0.1524 0.8001) (xy -0.13716 0.82804) (xy -0.11684 0.85344) (xy -0.09144 0.87376) (xy -0.0635 0.889)
						(xy -0.03175 0.89916) (xy 0 0.9017) (xy 0.03175 0.89916) (xy 0.0635 0.889) (xy 0.09144 0.87376)
						(xy 0.11684 0.85344) (xy 0.13716 0.82804) (xy 0.1524 0.8001) (xy 0.16256 0.76835) (xy 0.1651 0.7366)
						(xy 0.1651 0.11938) (xy 0.17272 0.11176) (xy 0.19812 0.0762) (xy 0.2032 0.06604) (xy 0.20701 0.05715)
						(xy 0.21209 0.04699) (xy 0.2159 0.03683) (xy 0.21844 0.02667) (xy 0.22225 0.01524) (xy 0.22352 0.00508)
						(xy 0.22606 -0.00508) (xy 0.22733 -0.01651) (xy 0.22733 -0.02667) (xy 0.2286 -0.0381) (xy 0.22733 -0.04953)
						(xy 0.22733 -0.05969) (xy 0.22606 -0.07112) (xy 0.22352 -0.08128) (xy 0.22225 -0.09144) (xy 0.21844 -0.10287)
						(xy 0.2159 -0.11303) (xy 0.21209 -0.12319) (xy 0.20701 -0.13335) (xy 0.2032 -0.14224) (xy 0.19812 -0.1524)
						(xy 0.17272 -0.18796) (xy 0.1651 -0.19558) (xy 0.1651 -0.7366) (xy 0.16256 -0.76835) (xy 0.1524 -0.8001)
						(xy 0.13716 -0.82804) (xy 0.11684 -0.85344) (xy 0.09144 -0.87376) (xy 0.0635 -0.889) (xy 0.03175 -0.89916)
					)
					(width 0)
					(fill yes)
				)
			)
		)
		(pad "60" smd custom
			(at -13.949934 4.100068 180)
			(size 0.1143 0.1143)
			(layers "B.Cu" "B.Mask" "B.Paste")
			(net "M_B_DQS_DN3")
			(options
				(clearance outline)
				(anchor circle)
			)
			(primitives
				(gr_poly
					(pts
						(xy 0 -0.9017) (xy -0.03175 -0.89916) (xy -0.0635 -0.889) (xy -0.09144 -0.87376) (xy -0.11684 -0.85344)
						(xy -0.13716 -0.82804) (xy -0.1524 -0.8001) (xy -0.16256 -0.76835) (xy -0.1651 -0.7366) (xy -0.1651 -0.11938)
						(xy -0.17272 -0.11176) (xy -0.19812 -0.0762) (xy -0.2032 -0.06604) (xy -0.20701 -0.05715) (xy -0.21209 -0.04699)
						(xy -0.2159 -0.03683) (xy -0.21844 -0.02667) (xy -0.22225 -0.01524) (xy -0.22352 -0.00508) (xy -0.22606 0.00508)
						(xy -0.22733 0.01651) (xy -0.22733 0.02667) (xy -0.2286 0.0381) (xy -0.22733 0.04953) (xy -0.22733 0.05969)
						(xy -0.22606 0.07112) (xy -0.22352 0.08128) (xy -0.22225 0.09144) (xy -0.21844 0.10287) (xy -0.2159 0.11303)
						(xy -0.21209 0.12319) (xy -0.20701 0.13335) (xy -0.2032 0.14224) (xy -0.19812 0.1524) (xy -0.17272 0.18796)
						(xy -0.1651 0.19558) (xy -0.1651 0.7366) (xy -0.16256 0.76835) (xy -0.1524 0.8001) (xy -0.13716 0.82804)
						(xy -0.11684 0.85344) (xy -0.09144 0.87376) (xy -0.0635 0.889) (xy -0.03175 0.89916) (xy 0 0.9017)
						(xy 0.03175 0.89916) (xy 0.0635 0.889) (xy 0.09144 0.87376) (xy 0.11684 0.85344) (xy 0.13716 0.82804)
						(xy 0.1524 0.8001) (xy 0.16256 0.76835) (xy 0.1651 0.7366) (xy 0.1651 0.19685) (xy 0.17272 0.18923)
						(xy 0.17907 0.18034) (xy 0.18669 0.17145) (xy 0.19177 0.16256) (xy 0.19812 0.15367) (xy 0.20828 0.13335)
						(xy 0.21971 0.10287) (xy 0.22225 0.09271) (xy 0.22479 0.08128) (xy 0.22606 0.07112) (xy 0.2286 0.05969)
						(xy 0.2286 0.01651) (xy 0.22606 0.00508) (xy 0.22479 -0.00508) (xy 0.22225 -0.01651) (xy 0.21971 -0.02667)
						(xy 0.20828 -0.05715) (xy 0.19812 -0.07747) (xy 0.19177 -0.08636) (xy 0.18669 -0.09525) (xy 0.17907 -0.10414)
						(xy 0.17272 -0.11303) (xy 0.1651 -0.12065) (xy 0.1651 -0.7366) (xy 0.16256 -0.76835) (xy 0.1524 -0.8001)
						(xy 0.13716 -0.82804) (xy 0.11684 -0.85344) (xy 0.09144 -0.87376) (xy 0.0635 -0.889) (xy 0.03175 -0.89916)
					)
					(width 0)
					(fill yes)
				)
			)
		)
		(pad "61" smd custom
			(at -13.64996 -4.100068 180)
			(size 0.1143 0.1143)
			(layers "B.Cu" "B.Mask" "B.Paste")
			(net "GND")
			(options
				(clearance outline)
				(anchor circle)
			)
			(primitives
				(gr_poly
					(pts
						(xy 0 -0.9017) (xy -0.03175 -0.89916) (xy -0.0635 -0.889) (xy -0.09144 -0.87376) (xy -0.11684 -0.85344)
						(xy -0.13716 -0.82804) (xy -0.1524 -0.8001) (xy -0.16256 -0.76835) (xy -0.1651 -0.7366) (xy -0.1651 -0.44958)
						(xy -0.17272 -0.44196) (xy -0.19812 -0.4064) (xy -0.2032 -0.39624) (xy -0.20701 -0.38735) (xy -0.21209 -0.37719)
						(xy -0.2159 -0.36703) (xy -0.21844 -0.35687) (xy -0.22225 -0.34544) (xy -0.22352 -0.33528) (xy -0.22606 -0.32512)
						(xy -0.22733 -0.31369) (xy -0.22733 -0.30353) (xy -0.2286 -0.2921) (xy -0.22733 -0.28067) (xy -0.22733 -0.27051)
						(xy -0.22606 -0.25908) (xy -0.22352 -0.24892) (xy -0.22225 -0.23876) (xy -0.21844 -0.22733) (xy -0.2159 -0.21717)
						(xy -0.21209 -0.20701) (xy -0.20701 -0.19685) (xy -0.2032 -0.18796) (xy -0.19812 -0.1778) (xy -0.17272 -0.14224)
						(xy -0.1651 -0.13462) (xy -0.1651 0.7366) (xy -0.16256 0.76835) (xy -0.1524 0.8001) (xy -0.13716 0.82804)
						(xy -0.11684 0.85344) (xy -0.09144 0.87376) (xy -0.0635 0.889) (xy -0.03175 0.89916) (xy 0 0.9017)
						(xy 0.03175 0.89916) (xy 0.0635 0.889) (xy 0.09144 0.87376) (xy 0.11684 0.85344) (xy 0.13716 0.82804)
						(xy 0.1524 0.8001) (xy 0.16256 0.76835) (xy 0.1651 0.7366) (xy 0.1651 -0.13462) (xy 0.17272 -0.14224)
						(xy 0.19812 -0.1778) (xy 0.2032 -0.18796) (xy 0.20701 -0.19685) (xy 0.21209 -0.20701) (xy 0.2159 -0.21717)
						(xy 0.21844 -0.22733) (xy 0.22225 -0.23876) (xy 0.22352 -0.24892) (xy 0.22606 -0.25908) (xy 0.22733 -0.27051)
						(xy 0.22733 -0.28067) (xy 0.2286 -0.2921) (xy 0.22733 -0.30353) (xy 0.22733 -0.31369) (xy 0.22606 -0.32512)
						(xy 0.22352 -0.33528) (xy 0.22225 -0.34544) (xy 0.21844 -0.35687) (xy 0.2159 -0.36703) (xy 0.21209 -0.37719)
						(xy 0.20701 -0.38735) (xy 0.2032 -0.39624) (xy 0.19812 -0.4064) (xy 0.17272 -0.44196) (xy 0.1651 -0.44958)
						(xy 0.1651 -0.7366) (xy 0.16256 -0.76835) (xy 0.1524 -0.8001) (xy 0.13716 -0.82804) (xy 0.11684 -0.85344)
						(xy 0.09144 -0.87376) (xy 0.0635 -0.889) (xy 0.03175 -0.89916)
					)
					(width 0)
					(fill yes)
				)
			)
		)
		(pad "62" smd custom
			(at -13.349986 4.100068 180)
			(size 0.1143 0.1143)
			(layers "B.Cu" "B.Mask" "B.Paste")
			(net "M_B_DQS_DP3")
			(options
				(clearance outline)
				(anchor circle)
			)
			(primitives
				(gr_poly
					(pts
						(xy 0 -0.9017) (xy -0.03175 -0.89916) (xy -0.0635 -0.889) (xy -0.09144 -0.87376) (xy -0.11684 -0.85344)
						(xy -0.13716 -0.82804) (xy -0.1524 -0.8001) (xy -0.16256 -0.76835) (xy -0.1651 -0.7366) (xy -0.1651 0.13462)
						(xy -0.17272 0.14224) (xy -0.19812 0.1778) (xy -0.2032 0.18796) (xy -0.20701 0.19685) (xy -0.21209 0.20701)
						(xy -0.2159 0.21717) (xy -0.21844 0.22733) (xy -0.22225 0.23876) (xy -0.22352 0.24892) (xy -0.22606 0.25908)
						(xy -0.22733 0.27051) (xy -0.22733 0.28067) (xy -0.2286 0.2921) (xy -0.22733 0.30353) (xy -0.22733 0.31369)
						(xy -0.22606 0.32512) (xy -0.22352 0.33528) (xy -0.22225 0.34544) (xy -0.21844 0.35687) (xy -0.2159 0.36703)
						(xy -0.21209 0.37719) (xy -0.20701 0.38735) (xy -0.2032 0.39624) (xy -0.19812 0.4064) (xy -0.17272 0.44196)
						(xy -0.1651 0.44958) (xy -0.1651 0.7366) (xy -0.16256 0.76835) (xy -0.1524 0.8001) (xy -0.13716 0.82804)
						(xy -0.11684 0.85344) (xy -0.09144 0.87376) (xy -0.0635 0.889) (xy -0.03175 0.89916) (xy 0 0.9017)
						(xy 0.03175 0.89916) (xy 0.0635 0.889) (xy 0.09144 0.87376) (xy 0.11684 0.85344) (xy 0.13716 0.82804)
						(xy 0.1524 0.8001) (xy 0.16256 0.76835) (xy 0.1651 0.7366) (xy 0.1651 0.44958) (xy 0.17272 0.44196)
						(xy 0.19812 0.4064) (xy 0.2032 0.39624) (xy 0.20701 0.38735) (xy 0.21209 0.37719) (xy 0.2159 0.36703)
						(xy 0.21844 0.35687) (xy 0.22225 0.34544) (xy 0.22352 0.33528) (xy 0.22606 0.32512) (xy 0.22733 0.31369)
						(xy 0.22733 0.30353) (xy 0.2286 0.2921) (xy 0.22733 0.28067) (xy 0.22733 0.27051) (xy 0.22606 0.25908)
						(xy 0.22352 0.24892) (xy 0.22225 0.23876) (xy 0.21844 0.22733) (xy 0.2159 0.21717) (xy 0.21209 0.20701)
						(xy 0.20701 0.19685) (xy 0.2032 0.18796) (xy 0.19812 0.1778) (xy 0.17272 0.14224) (xy 0.1651 0.13462)
						(xy 0.1651 -0.7366) (xy 0.16256 -0.76835) (xy 0.1524 -0.8001) (xy 0.13716 -0.82804) (xy 0.11684 -0.85344)
						(xy 0.09144 -0.87376) (xy 0.0635 -0.889) (xy 0.03175 -0.89916)
					)
					(width 0)
					(fill yes)
				)
			)
		)
		(pad "63" smd custom
			(at -13.050012 -4.100068 180)
			(size 0.1143 0.1143)
			(layers "B.Cu" "B.Mask" "B.Paste")
			(net "M_B_DQ26")
			(options
				(clearance outline)
				(anchor circle)
			)
			(primitives
				(gr_poly
					(pts
						(xy 0 -0.9017) (xy -0.03175 -0.89916) (xy -0.0635 -0.889) (xy -0.09144 -0.87376) (xy -0.11684 -0.85344)
						(xy -0.13716 -0.82804) (xy -0.1524 -0.8001) (xy -0.16256 -0.76835) (xy -0.1651 -0.7366) (xy -0.1651 -0.19685)
						(xy -0.17272 -0.18923) (xy -0.17907 -0.18034) (xy -0.18669 -0.17145) (xy -0.19177 -0.16256) (xy -0.19812 -0.15367)
						(xy -0.20828 -0.13335) (xy -0.21971 -0.10287) (xy -0.22225 -0.09271) (xy -0.22479 -0.08128) (xy -0.22606 -0.07112)
						(xy -0.2286 -0.05969) (xy -0.2286 -0.01651) (xy -0.22606 -0.00508) (xy -0.22479 0.00508) (xy -0.22225 0.01651)
						(xy -0.21971 0.02667) (xy -0.20828 0.05715) (xy -0.19812 0.07747) (xy -0.19177 0.08636) (xy -0.18669 0.09525)
						(xy -0.17907 0.10414) (xy -0.17272 0.11303) (xy -0.1651 0.12065) (xy -0.1651 0.7366) (xy -0.16256 0.76835)
						(xy -0.1524 0.8001) (xy -0.13716 0.82804) (xy -0.11684 0.85344) (xy -0.09144 0.87376) (xy -0.0635 0.889)
						(xy -0.03175 0.89916) (xy 0 0.9017) (xy 0.03175 0.89916) (xy 0.0635 0.889) (xy 0.09144 0.87376)
						(xy 0.11684 0.85344) (xy 0.13716 0.82804) (xy 0.1524 0.8001) (xy 0.16256 0.76835) (xy 0.1651 0.7366)
						(xy 0.1651 0.11938) (xy 0.17272 0.11176) (xy 0.19812 0.0762) (xy 0.2032 0.06604) (xy 0.20701 0.05715)
						(xy 0.21209 0.04699) (xy 0.2159 0.03683) (xy 0.21844 0.02667) (xy 0.22225 0.01524) (xy 0.22352 0.00508)
						(xy 0.22606 -0.00508) (xy 0.22733 -0.01651) (xy 0.22733 -0.02667) (xy 0.2286 -0.0381) (xy 0.22733 -0.04953)
						(xy 0.22733 -0.05969) (xy 0.22606 -0.07112) (xy 0.22352 -0.08128) (xy 0.22225 -0.09144) (xy 0.21844 -0.10287)
						(xy 0.2159 -0.11303) (xy 0.21209 -0.12319) (xy 0.20701 -0.13335) (xy 0.2032 -0.14224) (xy 0.19812 -0.1524)
						(xy 0.17272 -0.18796) (xy 0.1651 -0.19558) (xy 0.1651 -0.7366) (xy 0.16256 -0.76835) (xy 0.1524 -0.8001)
						(xy 0.13716 -0.82804) (xy 0.11684 -0.85344) (xy 0.09144 -0.87376) (xy 0.0635 -0.889) (xy 0.03175 -0.89916)
					)
					(width 0)
					(fill yes)
				)
			)
		)
		(pad "64" smd custom
			(at -12.750038 4.100068 180)
			(size 0.1143 0.1143)
			(layers "B.Cu" "B.Mask" "B.Paste")
			(net "GND")
			(options
				(clearance outline)
				(anchor circle)
			)
			(primitives
				(gr_poly
					(pts
						(xy 0 -0.9017) (xy -0.03175 -0.89916) (xy -0.0635 -0.889) (xy -0.09144 -0.87376) (xy -0.11684 -0.85344)
						(xy -0.13716 -0.82804) (xy -0.1524 -0.8001) (xy -0.16256 -0.76835) (xy -0.1651 -0.7366) (xy -0.1651 -0.11938)
						(xy -0.17272 -0.11176) (xy -0.19812 -0.0762) (xy -0.2032 -0.06604) (xy -0.20701 -0.05715) (xy -0.21209 -0.04699)
						(xy -0.2159 -0.03683) (xy -0.21844 -0.02667) (xy -0.22225 -0.01524) (xy -0.22352 -0.00508) (xy -0.22606 0.00508)
						(xy -0.22733 0.01651) (xy -0.22733 0.02667) (xy -0.2286 0.0381) (xy -0.22733 0.04953) (xy -0.22733 0.05969)
						(xy -0.22606 0.07112) (xy -0.22352 0.08128) (xy -0.22225 0.09144) (xy -0.21844 0.10287) (xy -0.2159 0.11303)
						(xy -0.21209 0.12319) (xy -0.20701 0.13335) (xy -0.2032 0.14224) (xy -0.19812 0.1524) (xy -0.17272 0.18796)
						(xy -0.1651 0.19558) (xy -0.1651 0.7366) (xy -0.16256 0.76835) (xy -0.1524 0.8001) (xy -0.13716 0.82804)
						(xy -0.11684 0.85344) (xy -0.09144 0.87376) (xy -0.0635 0.889) (xy -0.03175 0.89916) (xy 0 0.9017)
						(xy 0.03175 0.89916) (xy 0.0635 0.889) (xy 0.09144 0.87376) (xy 0.11684 0.85344) (xy 0.13716 0.82804)
						(xy 0.1524 0.8001) (xy 0.16256 0.76835) (xy 0.1651 0.7366) (xy 0.1651 0.19685) (xy 0.17272 0.18923)
						(xy 0.17907 0.18034) (xy 0.18669 0.17145) (xy 0.19177 0.16256) (xy 0.19812 0.15367) (xy 0.20828 0.13335)
						(xy 0.21971 0.10287) (xy 0.22225 0.09271) (xy 0.22479 0.08128) (xy 0.22606 0.07112) (xy 0.2286 0.05969)
						(xy 0.2286 0.01651) (xy 0.22606 0.00508) (xy 0.22479 -0.00508) (xy 0.22225 -0.01651) (xy 0.21971 -0.02667)
						(xy 0.20828 -0.05715) (xy 0.19812 -0.07747) (xy 0.19177 -0.08636) (xy 0.18669 -0.09525) (xy 0.17907 -0.10414)
						(xy 0.17272 -0.11303) (xy 0.1651 -0.12065) (xy 0.1651 -0.7366) (xy 0.16256 -0.76835) (xy 0.1524 -0.8001)
						(xy 0.13716 -0.82804) (xy 0.11684 -0.85344) (xy 0.09144 -0.87376) (xy 0.0635 -0.889) (xy 0.03175 -0.89916)
					)
					(width 0)
					(fill yes)
				)
			)
		)
		(pad "65" smd custom
			(at -12.450064 -4.100068 180)
			(size 0.1143 0.1143)
			(layers "B.Cu" "B.Mask" "B.Paste")
			(net "M_B_DQ27")
			(options
				(clearance outline)
				(anchor circle)
			)
			(primitives
				(gr_poly
					(pts
						(xy 0 -0.9017) (xy -0.03175 -0.89916) (xy -0.0635 -0.889) (xy -0.09144 -0.87376) (xy -0.11684 -0.85344)
						(xy -0.13716 -0.82804) (xy -0.1524 -0.8001) (xy -0.16256 -0.76835) (xy -0.1651 -0.7366) (xy -0.1651 -0.44958)
						(xy -0.17272 -0.44196) (xy -0.19812 -0.4064) (xy -0.2032 -0.39624) (xy -0.20701 -0.38735) (xy -0.21209 -0.37719)
						(xy -0.2159 -0.36703) (xy -0.21844 -0.35687) (xy -0.22225 -0.34544) (xy -0.22352 -0.33528) (xy -0.22606 -0.32512)
						(xy -0.22733 -0.31369) (xy -0.22733 -0.30353) (xy -0.2286 -0.2921) (xy -0.22733 -0.28067) (xy -0.22733 -0.27051)
						(xy -0.22606 -0.25908) (xy -0.22352 -0.24892) (xy -0.22225 -0.23876) (xy -0.21844 -0.22733) (xy -0.2159 -0.21717)
						(xy -0.21209 -0.20701) (xy -0.20701 -0.19685) (xy -0.2032 -0.18796) (xy -0.19812 -0.1778) (xy -0.17272 -0.14224)
						(xy -0.1651 -0.13462) (xy -0.1651 0.7366) (xy -0.16256 0.76835) (xy -0.1524 0.8001) (xy -0.13716 0.82804)
						(xy -0.11684 0.85344) (xy -0.09144 0.87376) (xy -0.0635 0.889) (xy -0.03175 0.89916) (xy 0 0.9017)
						(xy 0.03175 0.89916) (xy 0.0635 0.889) (xy 0.09144 0.87376) (xy 0.11684 0.85344) (xy 0.13716 0.82804)
						(xy 0.1524 0.8001) (xy 0.16256 0.76835) (xy 0.1651 0.7366) (xy 0.1651 -0.13462) (xy 0.17272 -0.14224)
						(xy 0.19812 -0.1778) (xy 0.2032 -0.18796) (xy 0.20701 -0.19685) (xy 0.21209 -0.20701) (xy 0.2159 -0.21717)
						(xy 0.21844 -0.22733) (xy 0.22225 -0.23876) (xy 0.22352 -0.24892) (xy 0.22606 -0.25908) (xy 0.22733 -0.27051)
						(xy 0.22733 -0.28067) (xy 0.2286 -0.2921) (xy 0.22733 -0.30353) (xy 0.22733 -0.31369) (xy 0.22606 -0.32512)
						(xy 0.22352 -0.33528) (xy 0.22225 -0.34544) (xy 0.21844 -0.35687) (xy 0.2159 -0.36703) (xy 0.21209 -0.37719)
						(xy 0.20701 -0.38735) (xy 0.2032 -0.39624) (xy 0.19812 -0.4064) (xy 0.17272 -0.44196) (xy 0.1651 -0.44958)
						(xy 0.1651 -0.7366) (xy 0.16256 -0.76835) (xy 0.1524 -0.8001) (xy 0.13716 -0.82804) (xy 0.11684 -0.85344)
						(xy 0.09144 -0.87376) (xy 0.0635 -0.889) (xy 0.03175 -0.89916)
					)
					(width 0)
					(fill yes)
				)
			)
		)
		(pad "66" smd custom
			(at -12.15009 4.100068 180)
			(size 0.1143 0.1143)
			(layers "B.Cu" "B.Mask" "B.Paste")
			(net "M_B_DQ30")
			(options
				(clearance outline)
				(anchor circle)
			)
			(primitives
				(gr_poly
					(pts
						(xy 0 -0.9017) (xy -0.03175 -0.89916) (xy -0.0635 -0.889) (xy -0.09144 -0.87376) (xy -0.11684 -0.85344)
						(xy -0.13716 -0.82804) (xy -0.1524 -0.8001) (xy -0.16256 -0.76835) (xy -0.1651 -0.7366) (xy -0.1651 0.13462)
						(xy -0.17272 0.14224) (xy -0.19812 0.1778) (xy -0.2032 0.18796) (xy -0.20701 0.19685) (xy -0.21209 0.20701)
						(xy -0.2159 0.21717) (xy -0.21844 0.22733) (xy -0.22225 0.23876) (xy -0.22352 0.24892) (xy -0.22606 0.25908)
						(xy -0.22733 0.27051) (xy -0.22733 0.28067) (xy -0.2286 0.2921) (xy -0.22733 0.30353) (xy -0.22733 0.31369)
						(xy -0.22606 0.32512) (xy -0.22352 0.33528) (xy -0.22225 0.34544) (xy -0.21844 0.35687) (xy -0.2159 0.36703)
						(xy -0.21209 0.37719) (xy -0.20701 0.38735) (xy -0.2032 0.39624) (xy -0.19812 0.4064) (xy -0.17272 0.44196)
						(xy -0.1651 0.44958) (xy -0.1651 0.7366) (xy -0.16256 0.76835) (xy -0.1524 0.8001) (xy -0.13716 0.82804)
						(xy -0.11684 0.85344) (xy -0.09144 0.87376) (xy -0.0635 0.889) (xy -0.03175 0.89916) (xy 0 0.9017)
						(xy 0.03175 0.89916) (xy 0.0635 0.889) (xy 0.09144 0.87376) (xy 0.11684 0.85344) (xy 0.13716 0.82804)
						(xy 0.1524 0.8001) (xy 0.16256 0.76835) (xy 0.1651 0.7366) (xy 0.1651 0.44958) (xy 0.17272 0.44196)
						(xy 0.19812 0.4064) (xy 0.2032 0.39624) (xy 0.20701 0.38735) (xy 0.21209 0.37719) (xy 0.2159 0.36703)
						(xy 0.21844 0.35687) (xy 0.22225 0.34544) (xy 0.22352 0.33528) (xy 0.22606 0.32512) (xy 0.22733 0.31369)
						(xy 0.22733 0.30353) (xy 0.2286 0.2921) (xy 0.22733 0.28067) (xy 0.22733 0.27051) (xy 0.22606 0.25908)
						(xy 0.22352 0.24892) (xy 0.22225 0.23876) (xy 0.21844 0.22733) (xy 0.2159 0.21717) (xy 0.21209 0.20701)
						(xy 0.20701 0.19685) (xy 0.2032 0.18796) (xy 0.19812 0.1778) (xy 0.17272 0.14224) (xy 0.1651 0.13462)
						(xy 0.1651 -0.7366) (xy 0.16256 -0.76835) (xy 0.1524 -0.8001) (xy 0.13716 -0.82804) (xy 0.11684 -0.85344)
						(xy 0.09144 -0.87376) (xy 0.0635 -0.889) (xy 0.03175 -0.89916)
					)
					(width 0)
					(fill yes)
				)
			)
		)
		(pad "67" smd custom
			(at -11.850116 -4.100068 180)
			(size 0.1143 0.1143)
			(layers "B.Cu" "B.Mask" "B.Paste")
			(net "GND")
			(options
				(clearance outline)
				(anchor circle)
			)
			(primitives
				(gr_poly
					(pts
						(xy 0 -0.9017) (xy -0.03175 -0.89916) (xy -0.0635 -0.889) (xy -0.09144 -0.87376) (xy -0.11684 -0.85344)
						(xy -0.13716 -0.82804) (xy -0.1524 -0.8001) (xy -0.16256 -0.76835) (xy -0.1651 -0.7366) (xy -0.1651 -0.19685)
						(xy -0.17272 -0.18923) (xy -0.17907 -0.18034) (xy -0.18669 -0.17145) (xy -0.19177 -0.16256) (xy -0.19812 -0.15367)
						(xy -0.20828 -0.13335) (xy -0.21971 -0.10287) (xy -0.22225 -0.09271) (xy -0.22479 -0.08128) (xy -0.22606 -0.07112)
						(xy -0.2286 -0.05969) (xy -0.2286 -0.01651) (xy -0.22606 -0.00508) (xy -0.22479 0.00508) (xy -0.22225 0.01651)
						(xy -0.21971 0.02667) (xy -0.20828 0.05715) (xy -0.19812 0.07747) (xy -0.19177 0.08636) (xy -0.18669 0.09525)
						(xy -0.17907 0.10414) (xy -0.17272 0.11303) (xy -0.1651 0.12065) (xy -0.1651 0.7366) (xy -0.16256 0.76835)
						(xy -0.1524 0.8001) (xy -0.13716 0.82804) (xy -0.11684 0.85344) (xy -0.09144 0.87376) (xy -0.0635 0.889)
						(xy -0.03175 0.89916) (xy 0 0.9017) (xy 0.03175 0.89916) (xy 0.0635 0.889) (xy 0.09144 0.87376)
						(xy 0.11684 0.85344) (xy 0.13716 0.82804) (xy 0.1524 0.8001) (xy 0.16256 0.76835) (xy 0.1651 0.7366)
						(xy 0.1651 0.11938) (xy 0.17272 0.11176) (xy 0.19812 0.0762) (xy 0.2032 0.06604) (xy 0.20701 0.05715)
						(xy 0.21209 0.04699) (xy 0.2159 0.03683) (xy 0.21844 0.02667) (xy 0.22225 0.01524) (xy 0.22352 0.00508)
						(xy 0.22606 -0.00508) (xy 0.22733 -0.01651) (xy 0.22733 -0.02667) (xy 0.2286 -0.0381) (xy 0.22733 -0.04953)
						(xy 0.22733 -0.05969) (xy 0.22606 -0.07112) (xy 0.22352 -0.08128) (xy 0.22225 -0.09144) (xy 0.21844 -0.10287)
						(xy 0.2159 -0.11303) (xy 0.21209 -0.12319) (xy 0.20701 -0.13335) (xy 0.2032 -0.14224) (xy 0.19812 -0.1524)
						(xy 0.17272 -0.18796) (xy 0.1651 -0.19558) (xy 0.1651 -0.7366) (xy 0.16256 -0.76835) (xy 0.1524 -0.8001)
						(xy 0.13716 -0.82804) (xy 0.11684 -0.85344) (xy 0.09144 -0.87376) (xy 0.0635 -0.889) (xy 0.03175 -0.89916)
					)
					(width 0)
					(fill yes)
				)
			)
		)
		(pad "68" smd custom
			(at -11.549888 4.100068 180)
			(size 0.1143 0.1143)
			(layers "B.Cu" "B.Mask" "B.Paste")
			(net "M_B_DQ31")
			(options
				(clearance outline)
				(anchor circle)
			)
			(primitives
				(gr_poly
					(pts
						(xy 0 -0.9017) (xy -0.03175 -0.89916) (xy -0.0635 -0.889) (xy -0.09144 -0.87376) (xy -0.11684 -0.85344)
						(xy -0.13716 -0.82804) (xy -0.1524 -0.8001) (xy -0.16256 -0.76835) (xy -0.1651 -0.7366) (xy -0.1651 -0.11938)
						(xy -0.17272 -0.11176) (xy -0.19812 -0.0762) (xy -0.2032 -0.06604) (xy -0.20701 -0.05715) (xy -0.21209 -0.04699)
						(xy -0.2159 -0.03683) (xy -0.21844 -0.02667) (xy -0.22225 -0.01524) (xy -0.22352 -0.00508) (xy -0.22606 0.00508)
						(xy -0.22733 0.01651) (xy -0.22733 0.02667) (xy -0.2286 0.0381) (xy -0.22733 0.04953) (xy -0.22733 0.05969)
						(xy -0.22606 0.07112) (xy -0.22352 0.08128) (xy -0.22225 0.09144) (xy -0.21844 0.10287) (xy -0.2159 0.11303)
						(xy -0.21209 0.12319) (xy -0.20701 0.13335) (xy -0.2032 0.14224) (xy -0.19812 0.1524) (xy -0.17272 0.18796)
						(xy -0.1651 0.19558) (xy -0.1651 0.7366) (xy -0.16256 0.76835) (xy -0.1524 0.8001) (xy -0.13716 0.82804)
						(xy -0.11684 0.85344) (xy -0.09144 0.87376) (xy -0.0635 0.889) (xy -0.03175 0.89916) (xy 0 0.9017)
						(xy 0.03175 0.89916) (xy 0.0635 0.889) (xy 0.09144 0.87376) (xy 0.11684 0.85344) (xy 0.13716 0.82804)
						(xy 0.1524 0.8001) (xy 0.16256 0.76835) (xy 0.1651 0.7366) (xy 0.1651 0.19685) (xy 0.17272 0.18923)
						(xy 0.17907 0.18034) (xy 0.18669 0.17145) (xy 0.19177 0.16256) (xy 0.19812 0.15367) (xy 0.20828 0.13335)
						(xy 0.21971 0.10287) (xy 0.22225 0.09271) (xy 0.22479 0.08128) (xy 0.22606 0.07112) (xy 0.2286 0.05969)
						(xy 0.2286 0.01651) (xy 0.22606 0.00508) (xy 0.22479 -0.00508) (xy 0.22225 -0.01651) (xy 0.21971 -0.02667)
						(xy 0.20828 -0.05715) (xy 0.19812 -0.07747) (xy 0.19177 -0.08636) (xy 0.18669 -0.09525) (xy 0.17907 -0.10414)
						(xy 0.17272 -0.11303) (xy 0.1651 -0.12065) (xy 0.1651 -0.7366) (xy 0.16256 -0.76835) (xy 0.1524 -0.8001)
						(xy 0.13716 -0.82804) (xy 0.11684 -0.85344) (xy 0.09144 -0.87376) (xy 0.0635 -0.889) (xy 0.03175 -0.89916)
					)
					(width 0)
					(fill yes)
				)
			)
		)
		(pad "69" smd custom
			(at -11.249914 -4.100068 180)
			(size 0.1143 0.1143)
			(layers "B.Cu" "B.Mask" "B.Paste")
			(net "M_B_ECC0")
			(options
				(clearance outline)
				(anchor circle)
			)
			(primitives
				(gr_poly
					(pts
						(xy 0 -0.9017) (xy -0.03175 -0.89916) (xy -0.0635 -0.889) (xy -0.09144 -0.87376) (xy -0.11684 -0.85344)
						(xy -0.13716 -0.82804) (xy -0.1524 -0.8001) (xy -0.16256 -0.76835) (xy -0.1651 -0.7366) (xy -0.1651 -0.44958)
						(xy -0.17272 -0.44196) (xy -0.19812 -0.4064) (xy -0.2032 -0.39624) (xy -0.20701 -0.38735) (xy -0.21209 -0.37719)
						(xy -0.2159 -0.36703) (xy -0.21844 -0.35687) (xy -0.22225 -0.34544) (xy -0.22352 -0.33528) (xy -0.22606 -0.32512)
						(xy -0.22733 -0.31369) (xy -0.22733 -0.30353) (xy -0.2286 -0.2921) (xy -0.22733 -0.28067) (xy -0.22733 -0.27051)
						(xy -0.22606 -0.25908) (xy -0.22352 -0.24892) (xy -0.22225 -0.23876) (xy -0.21844 -0.22733) (xy -0.2159 -0.21717)
						(xy -0.21209 -0.20701) (xy -0.20701 -0.19685) (xy -0.2032 -0.18796) (xy -0.19812 -0.1778) (xy -0.17272 -0.14224)
						(xy -0.1651 -0.13462) (xy -0.1651 0.7366) (xy -0.16256 0.76835) (xy -0.1524 0.8001) (xy -0.13716 0.82804)
						(xy -0.11684 0.85344) (xy -0.09144 0.87376) (xy -0.0635 0.889) (xy -0.03175 0.89916) (xy 0 0.9017)
						(xy 0.03175 0.89916) (xy 0.0635 0.889) (xy 0.09144 0.87376) (xy 0.11684 0.85344) (xy 0.13716 0.82804)
						(xy 0.1524 0.8001) (xy 0.16256 0.76835) (xy 0.1651 0.7366) (xy 0.1651 -0.13462) (xy 0.17272 -0.14224)
						(xy 0.19812 -0.1778) (xy 0.2032 -0.18796) (xy 0.20701 -0.19685) (xy 0.21209 -0.20701) (xy 0.2159 -0.21717)
						(xy 0.21844 -0.22733) (xy 0.22225 -0.23876) (xy 0.22352 -0.24892) (xy 0.22606 -0.25908) (xy 0.22733 -0.27051)
						(xy 0.22733 -0.28067) (xy 0.2286 -0.2921) (xy 0.22733 -0.30353) (xy 0.22733 -0.31369) (xy 0.22606 -0.32512)
						(xy 0.22352 -0.33528) (xy 0.22225 -0.34544) (xy 0.21844 -0.35687) (xy 0.2159 -0.36703) (xy 0.21209 -0.37719)
						(xy 0.20701 -0.38735) (xy 0.2032 -0.39624) (xy 0.19812 -0.4064) (xy 0.17272 -0.44196) (xy 0.1651 -0.44958)
						(xy 0.1651 -0.7366) (xy 0.16256 -0.76835) (xy 0.1524 -0.8001) (xy 0.13716 -0.82804) (xy 0.11684 -0.85344)
						(xy 0.09144 -0.87376) (xy 0.0635 -0.889) (xy 0.03175 -0.89916)
					)
					(width 0)
					(fill yes)
				)
			)
		)
		(pad "70" smd custom
			(at -10.94994 4.100068 180)
			(size 0.1143 0.1143)
			(layers "B.Cu" "B.Mask" "B.Paste")
			(net "GND")
			(options
				(clearance outline)
				(anchor circle)
			)
			(primitives
				(gr_poly
					(pts
						(xy 0 -0.9017) (xy -0.03175 -0.89916) (xy -0.0635 -0.889) (xy -0.09144 -0.87376) (xy -0.11684 -0.85344)
						(xy -0.13716 -0.82804) (xy -0.1524 -0.8001) (xy -0.16256 -0.76835) (xy -0.1651 -0.7366) (xy -0.1651 0.13462)
						(xy -0.17272 0.14224) (xy -0.19812 0.1778) (xy -0.2032 0.18796) (xy -0.20701 0.19685) (xy -0.21209 0.20701)
						(xy -0.2159 0.21717) (xy -0.21844 0.22733) (xy -0.22225 0.23876) (xy -0.22352 0.24892) (xy -0.22606 0.25908)
						(xy -0.22733 0.27051) (xy -0.22733 0.28067) (xy -0.2286 0.2921) (xy -0.22733 0.30353) (xy -0.22733 0.31369)
						(xy -0.22606 0.32512) (xy -0.22352 0.33528) (xy -0.22225 0.34544) (xy -0.21844 0.35687) (xy -0.2159 0.36703)
						(xy -0.21209 0.37719) (xy -0.20701 0.38735) (xy -0.2032 0.39624) (xy -0.19812 0.4064) (xy -0.17272 0.44196)
						(xy -0.1651 0.44958) (xy -0.1651 0.7366) (xy -0.16256 0.76835) (xy -0.1524 0.8001) (xy -0.13716 0.82804)
						(xy -0.11684 0.85344) (xy -0.09144 0.87376) (xy -0.0635 0.889) (xy -0.03175 0.89916) (xy 0 0.9017)
						(xy 0.03175 0.89916) (xy 0.0635 0.889) (xy 0.09144 0.87376) (xy 0.11684 0.85344) (xy 0.13716 0.82804)
						(xy 0.1524 0.8001) (xy 0.16256 0.76835) (xy 0.1651 0.7366) (xy 0.1651 0.44958) (xy 0.17272 0.44196)
						(xy 0.19812 0.4064) (xy 0.2032 0.39624) (xy 0.20701 0.38735) (xy 0.21209 0.37719) (xy 0.2159 0.36703)
						(xy 0.21844 0.35687) (xy 0.22225 0.34544) (xy 0.22352 0.33528) (xy 0.22606 0.32512) (xy 0.22733 0.31369)
						(xy 0.22733 0.30353) (xy 0.2286 0.2921) (xy 0.22733 0.28067) (xy 0.22733 0.27051) (xy 0.22606 0.25908)
						(xy 0.22352 0.24892) (xy 0.22225 0.23876) (xy 0.21844 0.22733) (xy 0.2159 0.21717) (xy 0.21209 0.20701)
						(xy 0.20701 0.19685) (xy 0.2032 0.18796) (xy 0.19812 0.1778) (xy 0.17272 0.14224) (xy 0.1651 0.13462)
						(xy 0.1651 -0.7366) (xy 0.16256 -0.76835) (xy 0.1524 -0.8001) (xy 0.13716 -0.82804) (xy 0.11684 -0.85344)
						(xy 0.09144 -0.87376) (xy 0.0635 -0.889) (xy 0.03175 -0.89916)
					)
					(width 0)
					(fill yes)
				)
			)
		)
		(pad "71" smd custom
			(at -10.649966 -4.100068 180)
			(size 0.1143 0.1143)
			(layers "B.Cu" "B.Mask" "B.Paste")
			(net "M_B_ECC1")
			(options
				(clearance outline)
				(anchor circle)
			)
			(primitives
				(gr_poly
					(pts
						(xy 0 -0.9017) (xy -0.03175 -0.89916) (xy -0.0635 -0.889) (xy -0.09144 -0.87376) (xy -0.11684 -0.85344)
						(xy -0.13716 -0.82804) (xy -0.1524 -0.8001) (xy -0.16256 -0.76835) (xy -0.1651 -0.7366) (xy -0.1651 -0.19685)
						(xy -0.17272 -0.18923) (xy -0.17907 -0.18034) (xy -0.18669 -0.17145) (xy -0.19177 -0.16256) (xy -0.19812 -0.15367)
						(xy -0.20828 -0.13335) (xy -0.21971 -0.10287) (xy -0.22225 -0.09271) (xy -0.22479 -0.08128) (xy -0.22606 -0.07112)
						(xy -0.2286 -0.05969) (xy -0.2286 -0.01651) (xy -0.22606 -0.00508) (xy -0.22479 0.00508) (xy -0.22225 0.01651)
						(xy -0.21971 0.02667) (xy -0.20828 0.05715) (xy -0.19812 0.07747) (xy -0.19177 0.08636) (xy -0.18669 0.09525)
						(xy -0.17907 0.10414) (xy -0.17272 0.11303) (xy -0.1651 0.12065) (xy -0.1651 0.7366) (xy -0.16256 0.76835)
						(xy -0.1524 0.8001) (xy -0.13716 0.82804) (xy -0.11684 0.85344) (xy -0.09144 0.87376) (xy -0.0635 0.889)
						(xy -0.03175 0.89916) (xy 0 0.9017) (xy 0.03175 0.89916) (xy 0.0635 0.889) (xy 0.09144 0.87376)
						(xy 0.11684 0.85344) (xy 0.13716 0.82804) (xy 0.1524 0.8001) (xy 0.16256 0.76835) (xy 0.1651 0.7366)
						(xy 0.1651 0.11938) (xy 0.17272 0.11176) (xy 0.19812 0.0762) (xy 0.2032 0.06604) (xy 0.20701 0.05715)
						(xy 0.21209 0.04699) (xy 0.2159 0.03683) (xy 0.21844 0.02667) (xy 0.22225 0.01524) (xy 0.22352 0.00508)
						(xy 0.22606 -0.00508) (xy 0.22733 -0.01651) (xy 0.22733 -0.02667) (xy 0.2286 -0.0381) (xy 0.22733 -0.04953)
						(xy 0.22733 -0.05969) (xy 0.22606 -0.07112) (xy 0.22352 -0.08128) (xy 0.22225 -0.09144) (xy 0.21844 -0.10287)
						(xy 0.2159 -0.11303) (xy 0.21209 -0.12319) (xy 0.20701 -0.13335) (xy 0.2032 -0.14224) (xy 0.19812 -0.1524)
						(xy 0.17272 -0.18796) (xy 0.1651 -0.19558) (xy 0.1651 -0.7366) (xy 0.16256 -0.76835) (xy 0.1524 -0.8001)
						(xy 0.13716 -0.82804) (xy 0.11684 -0.85344) (xy 0.09144 -0.87376) (xy 0.0635 -0.889) (xy 0.03175 -0.89916)
					)
					(width 0)
					(fill yes)
				)
			)
		)
		(pad "72" smd custom
			(at -10.349992 4.100068 180)
			(size 0.1143 0.1143)
			(layers "B.Cu" "B.Mask" "B.Paste")
			(net "M_B_ECC4")
			(options
				(clearance outline)
				(anchor circle)
			)
			(primitives
				(gr_poly
					(pts
						(xy 0 -0.9017) (xy -0.03175 -0.89916) (xy -0.0635 -0.889) (xy -0.09144 -0.87376) (xy -0.11684 -0.85344)
						(xy -0.13716 -0.82804) (xy -0.1524 -0.8001) (xy -0.16256 -0.76835) (xy -0.1651 -0.7366) (xy -0.1651 -0.11938)
						(xy -0.17272 -0.11176) (xy -0.19812 -0.0762) (xy -0.2032 -0.06604) (xy -0.20701 -0.05715) (xy -0.21209 -0.04699)
						(xy -0.2159 -0.03683) (xy -0.21844 -0.02667) (xy -0.22225 -0.01524) (xy -0.22352 -0.00508) (xy -0.22606 0.00508)
						(xy -0.22733 0.01651) (xy -0.22733 0.02667) (xy -0.2286 0.0381) (xy -0.22733 0.04953) (xy -0.22733 0.05969)
						(xy -0.22606 0.07112) (xy -0.22352 0.08128) (xy -0.22225 0.09144) (xy -0.21844 0.10287) (xy -0.2159 0.11303)
						(xy -0.21209 0.12319) (xy -0.20701 0.13335) (xy -0.2032 0.14224) (xy -0.19812 0.1524) (xy -0.17272 0.18796)
						(xy -0.1651 0.19558) (xy -0.1651 0.7366) (xy -0.16256 0.76835) (xy -0.1524 0.8001) (xy -0.13716 0.82804)
						(xy -0.11684 0.85344) (xy -0.09144 0.87376) (xy -0.0635 0.889) (xy -0.03175 0.89916) (xy 0 0.9017)
						(xy 0.03175 0.89916) (xy 0.0635 0.889) (xy 0.09144 0.87376) (xy 0.11684 0.85344) (xy 0.13716 0.82804)
						(xy 0.1524 0.8001) (xy 0.16256 0.76835) (xy 0.1651 0.7366) (xy 0.1651 0.19685) (xy 0.17272 0.18923)
						(xy 0.17907 0.18034) (xy 0.18669 0.17145) (xy 0.19177 0.16256) (xy 0.19812 0.15367) (xy 0.20828 0.13335)
						(xy 0.21971 0.10287) (xy 0.22225 0.09271) (xy 0.22479 0.08128) (xy 0.22606 0.07112) (xy 0.2286 0.05969)
						(xy 0.2286 0.01651) (xy 0.22606 0.00508) (xy 0.22479 -0.00508) (xy 0.22225 -0.01651) (xy 0.21971 -0.02667)
						(xy 0.20828 -0.05715) (xy 0.19812 -0.07747) (xy 0.19177 -0.08636) (xy 0.18669 -0.09525) (xy 0.17907 -0.10414)
						(xy 0.17272 -0.11303) (xy 0.1651 -0.12065) (xy 0.1651 -0.7366) (xy 0.16256 -0.76835) (xy 0.1524 -0.8001)
						(xy 0.13716 -0.82804) (xy 0.11684 -0.85344) (xy 0.09144 -0.87376) (xy 0.0635 -0.889) (xy 0.03175 -0.89916)
					)
					(width 0)
					(fill yes)
				)
			)
		)
		(pad "73" smd custom
			(at -7.649972 -4.100068 180)
			(size 0.1143 0.1143)
			(layers "B.Cu" "B.Mask" "B.Paste")
			(net "GND")
			(options
				(clearance outline)
				(anchor circle)
			)
			(primitives
				(gr_poly
					(pts
						(xy 0 -0.9017) (xy -0.03175 -0.89916) (xy -0.0635 -0.889) (xy -0.09144 -0.87376) (xy -0.11684 -0.85344)
						(xy -0.13716 -0.82804) (xy -0.1524 -0.8001) (xy -0.16256 -0.76835) (xy -0.1651 -0.7366) (xy -0.1651 -0.44958)
						(xy -0.17272 -0.44196) (xy -0.19812 -0.4064) (xy -0.2032 -0.39624) (xy -0.20701 -0.38735) (xy -0.21209 -0.37719)
						(xy -0.2159 -0.36703) (xy -0.21844 -0.35687) (xy -0.22225 -0.34544) (xy -0.22352 -0.33528) (xy -0.22606 -0.32512)
						(xy -0.22733 -0.31369) (xy -0.22733 -0.30353) (xy -0.2286 -0.2921) (xy -0.22733 -0.28067) (xy -0.22733 -0.27051)
						(xy -0.22606 -0.25908) (xy -0.22352 -0.24892) (xy -0.22225 -0.23876) (xy -0.21844 -0.22733) (xy -0.2159 -0.21717)
						(xy -0.21209 -0.20701) (xy -0.20701 -0.19685) (xy -0.2032 -0.18796) (xy -0.19812 -0.1778) (xy -0.17272 -0.14224)
						(xy -0.1651 -0.13462) (xy -0.1651 0.7366) (xy -0.16256 0.76835) (xy -0.1524 0.8001) (xy -0.13716 0.82804)
						(xy -0.11684 0.85344) (xy -0.09144 0.87376) (xy -0.0635 0.889) (xy -0.03175 0.89916) (xy 0 0.9017)
						(xy 0.03175 0.89916) (xy 0.0635 0.889) (xy 0.09144 0.87376) (xy 0.11684 0.85344) (xy 0.13716 0.82804)
						(xy 0.1524 0.8001) (xy 0.16256 0.76835) (xy 0.1651 0.7366) (xy 0.1651 -0.13462) (xy 0.17272 -0.14224)
						(xy 0.19812 -0.1778) (xy 0.2032 -0.18796) (xy 0.20701 -0.19685) (xy 0.21209 -0.20701) (xy 0.2159 -0.21717)
						(xy 0.21844 -0.22733) (xy 0.22225 -0.23876) (xy 0.22352 -0.24892) (xy 0.22606 -0.25908) (xy 0.22733 -0.27051)
						(xy 0.22733 -0.28067) (xy 0.2286 -0.2921) (xy 0.22733 -0.30353) (xy 0.22733 -0.31369) (xy 0.22606 -0.32512)
						(xy 0.22352 -0.33528) (xy 0.22225 -0.34544) (xy 0.21844 -0.35687) (xy 0.2159 -0.36703) (xy 0.21209 -0.37719)
						(xy 0.20701 -0.38735) (xy 0.2032 -0.39624) (xy 0.19812 -0.4064) (xy 0.17272 -0.44196) (xy 0.1651 -0.44958)
						(xy 0.1651 -0.7366) (xy 0.16256 -0.76835) (xy 0.1524 -0.8001) (xy 0.13716 -0.82804) (xy 0.11684 -0.85344)
						(xy 0.09144 -0.87376) (xy 0.0635 -0.889) (xy 0.03175 -0.89916)
					)
					(width 0)
					(fill yes)
				)
			)
		)
		(pad "74" smd custom
			(at -7.349998 4.100068 180)
			(size 0.1143 0.1143)
			(layers "B.Cu" "B.Mask" "B.Paste")
			(net "M_B_ECC5")
			(options
				(clearance outline)
				(anchor circle)
			)
			(primitives
				(gr_poly
					(pts
						(xy 0 -0.9017) (xy -0.03175 -0.89916) (xy -0.0635 -0.889) (xy -0.09144 -0.87376) (xy -0.11684 -0.85344)
						(xy -0.13716 -0.82804) (xy -0.1524 -0.8001) (xy -0.16256 -0.76835) (xy -0.1651 -0.7366) (xy -0.1651 0.13462)
						(xy -0.17272 0.14224) (xy -0.19812 0.1778) (xy -0.2032 0.18796) (xy -0.20701 0.19685) (xy -0.21209 0.20701)
						(xy -0.2159 0.21717) (xy -0.21844 0.22733) (xy -0.22225 0.23876) (xy -0.22352 0.24892) (xy -0.22606 0.25908)
						(xy -0.22733 0.27051) (xy -0.22733 0.28067) (xy -0.2286 0.2921) (xy -0.22733 0.30353) (xy -0.22733 0.31369)
						(xy -0.22606 0.32512) (xy -0.22352 0.33528) (xy -0.22225 0.34544) (xy -0.21844 0.35687) (xy -0.2159 0.36703)
						(xy -0.21209 0.37719) (xy -0.20701 0.38735) (xy -0.2032 0.39624) (xy -0.19812 0.4064) (xy -0.17272 0.44196)
						(xy -0.1651 0.44958) (xy -0.1651 0.7366) (xy -0.16256 0.76835) (xy -0.1524 0.8001) (xy -0.13716 0.82804)
						(xy -0.11684 0.85344) (xy -0.09144 0.87376) (xy -0.0635 0.889) (xy -0.03175 0.89916) (xy 0 0.9017)
						(xy 0.03175 0.89916) (xy 0.0635 0.889) (xy 0.09144 0.87376) (xy 0.11684 0.85344) (xy 0.13716 0.82804)
						(xy 0.1524 0.8001) (xy 0.16256 0.76835) (xy 0.1651 0.7366) (xy 0.1651 0.44958) (xy 0.17272 0.44196)
						(xy 0.19812 0.4064) (xy 0.2032 0.39624) (xy 0.20701 0.38735) (xy 0.21209 0.37719) (xy 0.2159 0.36703)
						(xy 0.21844 0.35687) (xy 0.22225 0.34544) (xy 0.22352 0.33528) (xy 0.22606 0.32512) (xy 0.22733 0.31369)
						(xy 0.22733 0.30353) (xy 0.2286 0.2921) (xy 0.22733 0.28067) (xy 0.22733 0.27051) (xy 0.22606 0.25908)
						(xy 0.22352 0.24892) (xy 0.22225 0.23876) (xy 0.21844 0.22733) (xy 0.2159 0.21717) (xy 0.21209 0.20701)
						(xy 0.20701 0.19685) (xy 0.2032 0.18796) (xy 0.19812 0.1778) (xy 0.17272 0.14224) (xy 0.1651 0.13462)
						(xy 0.1651 -0.7366) (xy 0.16256 -0.76835) (xy 0.1524 -0.8001) (xy 0.13716 -0.82804) (xy 0.11684 -0.85344)
						(xy 0.09144 -0.87376) (xy 0.0635 -0.889) (xy 0.03175 -0.89916)
					)
					(width 0)
					(fill yes)
				)
			)
		)
		(pad "75" smd custom
			(at -7.050024 -4.100068 180)
			(size 0.1143 0.1143)
			(layers "B.Cu" "B.Mask" "B.Paste")
			(net "M_B_DQS_DN8")
			(options
				(clearance outline)
				(anchor circle)
			)
			(primitives
				(gr_poly
					(pts
						(xy 0 -0.9017) (xy -0.03175 -0.89916) (xy -0.0635 -0.889) (xy -0.09144 -0.87376) (xy -0.11684 -0.85344)
						(xy -0.13716 -0.82804) (xy -0.1524 -0.8001) (xy -0.16256 -0.76835) (xy -0.1651 -0.7366) (xy -0.1651 -0.19685)
						(xy -0.17272 -0.18923) (xy -0.17907 -0.18034) (xy -0.18669 -0.17145) (xy -0.19177 -0.16256) (xy -0.19812 -0.15367)
						(xy -0.20828 -0.13335) (xy -0.21971 -0.10287) (xy -0.22225 -0.09271) (xy -0.22479 -0.08128) (xy -0.22606 -0.07112)
						(xy -0.2286 -0.05969) (xy -0.2286 -0.01651) (xy -0.22606 -0.00508) (xy -0.22479 0.00508) (xy -0.22225 0.01651)
						(xy -0.21971 0.02667) (xy -0.20828 0.05715) (xy -0.19812 0.07747) (xy -0.19177 0.08636) (xy -0.18669 0.09525)
						(xy -0.17907 0.10414) (xy -0.17272 0.11303) (xy -0.1651 0.12065) (xy -0.1651 0.7366) (xy -0.16256 0.76835)
						(xy -0.1524 0.8001) (xy -0.13716 0.82804) (xy -0.11684 0.85344) (xy -0.09144 0.87376) (xy -0.0635 0.889)
						(xy -0.03175 0.89916) (xy 0 0.9017) (xy 0.03175 0.89916) (xy 0.0635 0.889) (xy 0.09144 0.87376)
						(xy 0.11684 0.85344) (xy 0.13716 0.82804) (xy 0.1524 0.8001) (xy 0.16256 0.76835) (xy 0.1651 0.7366)
						(xy 0.1651 0.11938) (xy 0.17272 0.11176) (xy 0.19812 0.0762) (xy 0.2032 0.06604) (xy 0.20701 0.05715)
						(xy 0.21209 0.04699) (xy 0.2159 0.03683) (xy 0.21844 0.02667) (xy 0.22225 0.01524) (xy 0.22352 0.00508)
						(xy 0.22606 -0.00508) (xy 0.22733 -0.01651) (xy 0.22733 -0.02667) (xy 0.2286 -0.0381) (xy 0.22733 -0.04953)
						(xy 0.22733 -0.05969) (xy 0.22606 -0.07112) (xy 0.22352 -0.08128) (xy 0.22225 -0.09144) (xy 0.21844 -0.10287)
						(xy 0.2159 -0.11303) (xy 0.21209 -0.12319) (xy 0.20701 -0.13335) (xy 0.2032 -0.14224) (xy 0.19812 -0.1524)
						(xy 0.17272 -0.18796) (xy 0.1651 -0.19558) (xy 0.1651 -0.7366) (xy 0.16256 -0.76835) (xy 0.1524 -0.8001)
						(xy 0.13716 -0.82804) (xy 0.11684 -0.85344) (xy 0.09144 -0.87376) (xy 0.0635 -0.889) (xy 0.03175 -0.89916)
					)
					(width 0)
					(fill yes)
				)
			)
		)
		(pad "76" smd custom
			(at -6.75005 4.100068 180)
			(size 0.1143 0.1143)
			(layers "B.Cu" "B.Mask" "B.Paste")
			(net "GND")
			(options
				(clearance outline)
				(anchor circle)
			)
			(primitives
				(gr_poly
					(pts
						(xy 0 -0.9017) (xy -0.03175 -0.89916) (xy -0.0635 -0.889) (xy -0.09144 -0.87376) (xy -0.11684 -0.85344)
						(xy -0.13716 -0.82804) (xy -0.1524 -0.8001) (xy -0.16256 -0.76835) (xy -0.1651 -0.7366) (xy -0.1651 -0.11938)
						(xy -0.17272 -0.11176) (xy -0.19812 -0.0762) (xy -0.2032 -0.06604) (xy -0.20701 -0.05715) (xy -0.21209 -0.04699)
						(xy -0.2159 -0.03683) (xy -0.21844 -0.02667) (xy -0.22225 -0.01524) (xy -0.22352 -0.00508) (xy -0.22606 0.00508)
						(xy -0.22733 0.01651) (xy -0.22733 0.02667) (xy -0.2286 0.0381) (xy -0.22733 0.04953) (xy -0.22733 0.05969)
						(xy -0.22606 0.07112) (xy -0.22352 0.08128) (xy -0.22225 0.09144) (xy -0.21844 0.10287) (xy -0.2159 0.11303)
						(xy -0.21209 0.12319) (xy -0.20701 0.13335) (xy -0.2032 0.14224) (xy -0.19812 0.1524) (xy -0.17272 0.18796)
						(xy -0.1651 0.19558) (xy -0.1651 0.7366) (xy -0.16256 0.76835) (xy -0.1524 0.8001) (xy -0.13716 0.82804)
						(xy -0.11684 0.85344) (xy -0.09144 0.87376) (xy -0.0635 0.889) (xy -0.03175 0.89916) (xy 0 0.9017)
						(xy 0.03175 0.89916) (xy 0.0635 0.889) (xy 0.09144 0.87376) (xy 0.11684 0.85344) (xy 0.13716 0.82804)
						(xy 0.1524 0.8001) (xy 0.16256 0.76835) (xy 0.1651 0.7366) (xy 0.1651 0.19685) (xy 0.17272 0.18923)
						(xy 0.17907 0.18034) (xy 0.18669 0.17145) (xy 0.19177 0.16256) (xy 0.19812 0.15367) (xy 0.20828 0.13335)
						(xy 0.21971 0.10287) (xy 0.22225 0.09271) (xy 0.22479 0.08128) (xy 0.22606 0.07112) (xy 0.2286 0.05969)
						(xy 0.2286 0.01651) (xy 0.22606 0.00508) (xy 0.22479 -0.00508) (xy 0.22225 -0.01651) (xy 0.21971 -0.02667)
						(xy 0.20828 -0.05715) (xy 0.19812 -0.07747) (xy 0.19177 -0.08636) (xy 0.18669 -0.09525) (xy 0.17907 -0.10414)
						(xy 0.17272 -0.11303) (xy 0.1651 -0.12065) (xy 0.1651 -0.7366) (xy 0.16256 -0.76835) (xy 0.1524 -0.8001)
						(xy 0.13716 -0.82804) (xy 0.11684 -0.85344) (xy 0.09144 -0.87376) (xy 0.0635 -0.889) (xy 0.03175 -0.89916)
					)
					(width 0)
					(fill yes)
				)
			)
		)
		(pad "77" smd custom
			(at -6.450076 -4.100068 180)
			(size 0.1143 0.1143)
			(layers "B.Cu" "B.Mask" "B.Paste")
			(net "M_B_DQS_DP8")
			(options
				(clearance outline)
				(anchor circle)
			)
			(primitives
				(gr_poly
					(pts
						(xy 0 -0.9017) (xy -0.03175 -0.89916) (xy -0.0635 -0.889) (xy -0.09144 -0.87376) (xy -0.11684 -0.85344)
						(xy -0.13716 -0.82804) (xy -0.1524 -0.8001) (xy -0.16256 -0.76835) (xy -0.1651 -0.7366) (xy -0.1651 -0.44958)
						(xy -0.17272 -0.44196) (xy -0.19812 -0.4064) (xy -0.2032 -0.39624) (xy -0.20701 -0.38735) (xy -0.21209 -0.37719)
						(xy -0.2159 -0.36703) (xy -0.21844 -0.35687) (xy -0.22225 -0.34544) (xy -0.22352 -0.33528) (xy -0.22606 -0.32512)
						(xy -0.22733 -0.31369) (xy -0.22733 -0.30353) (xy -0.2286 -0.2921) (xy -0.22733 -0.28067) (xy -0.22733 -0.27051)
						(xy -0.22606 -0.25908) (xy -0.22352 -0.24892) (xy -0.22225 -0.23876) (xy -0.21844 -0.22733) (xy -0.2159 -0.21717)
						(xy -0.21209 -0.20701) (xy -0.20701 -0.19685) (xy -0.2032 -0.18796) (xy -0.19812 -0.1778) (xy -0.17272 -0.14224)
						(xy -0.1651 -0.13462) (xy -0.1651 0.7366) (xy -0.16256 0.76835) (xy -0.1524 0.8001) (xy -0.13716 0.82804)
						(xy -0.11684 0.85344) (xy -0.09144 0.87376) (xy -0.0635 0.889) (xy -0.03175 0.89916) (xy 0 0.9017)
						(xy 0.03175 0.89916) (xy 0.0635 0.889) (xy 0.09144 0.87376) (xy 0.11684 0.85344) (xy 0.13716 0.82804)
						(xy 0.1524 0.8001) (xy 0.16256 0.76835) (xy 0.1651 0.7366) (xy 0.1651 -0.13462) (xy 0.17272 -0.14224)
						(xy 0.19812 -0.1778) (xy 0.2032 -0.18796) (xy 0.20701 -0.19685) (xy 0.21209 -0.20701) (xy 0.2159 -0.21717)
						(xy 0.21844 -0.22733) (xy 0.22225 -0.23876) (xy 0.22352 -0.24892) (xy 0.22606 -0.25908) (xy 0.22733 -0.27051)
						(xy 0.22733 -0.28067) (xy 0.2286 -0.2921) (xy 0.22733 -0.30353) (xy 0.22733 -0.31369) (xy 0.22606 -0.32512)
						(xy 0.22352 -0.33528) (xy 0.22225 -0.34544) (xy 0.21844 -0.35687) (xy 0.2159 -0.36703) (xy 0.21209 -0.37719)
						(xy 0.20701 -0.38735) (xy 0.2032 -0.39624) (xy 0.19812 -0.4064) (xy 0.17272 -0.44196) (xy 0.1651 -0.44958)
						(xy 0.1651 -0.7366) (xy 0.16256 -0.76835) (xy 0.1524 -0.8001) (xy 0.13716 -0.82804) (xy 0.11684 -0.85344)
						(xy 0.09144 -0.87376) (xy 0.0635 -0.889) (xy 0.03175 -0.89916)
					)
					(width 0)
					(fill yes)
				)
			)
		)
		(pad "78" smd custom
			(at -6.150102 4.100068 180)
			(size 0.1143 0.1143)
			(layers "B.Cu" "B.Mask" "B.Paste")
			(net "GND")
			(options
				(clearance outline)
				(anchor circle)
			)
			(primitives
				(gr_poly
					(pts
						(xy 0 -0.9017) (xy -0.03175 -0.89916) (xy -0.0635 -0.889) (xy -0.09144 -0.87376) (xy -0.11684 -0.85344)
						(xy -0.13716 -0.82804) (xy -0.1524 -0.8001) (xy -0.16256 -0.76835) (xy -0.1651 -0.7366) (xy -0.1651 0.13462)
						(xy -0.17272 0.14224) (xy -0.19812 0.1778) (xy -0.2032 0.18796) (xy -0.20701 0.19685) (xy -0.21209 0.20701)
						(xy -0.2159 0.21717) (xy -0.21844 0.22733) (xy -0.22225 0.23876) (xy -0.22352 0.24892) (xy -0.22606 0.25908)
						(xy -0.22733 0.27051) (xy -0.22733 0.28067) (xy -0.2286 0.2921) (xy -0.22733 0.30353) (xy -0.22733 0.31369)
						(xy -0.22606 0.32512) (xy -0.22352 0.33528) (xy -0.22225 0.34544) (xy -0.21844 0.35687) (xy -0.2159 0.36703)
						(xy -0.21209 0.37719) (xy -0.20701 0.38735) (xy -0.2032 0.39624) (xy -0.19812 0.4064) (xy -0.17272 0.44196)
						(xy -0.1651 0.44958) (xy -0.1651 0.7366) (xy -0.16256 0.76835) (xy -0.1524 0.8001) (xy -0.13716 0.82804)
						(xy -0.11684 0.85344) (xy -0.09144 0.87376) (xy -0.0635 0.889) (xy -0.03175 0.89916) (xy 0 0.9017)
						(xy 0.03175 0.89916) (xy 0.0635 0.889) (xy 0.09144 0.87376) (xy 0.11684 0.85344) (xy 0.13716 0.82804)
						(xy 0.1524 0.8001) (xy 0.16256 0.76835) (xy 0.1651 0.7366) (xy 0.1651 0.44958) (xy 0.17272 0.44196)
						(xy 0.19812 0.4064) (xy 0.2032 0.39624) (xy 0.20701 0.38735) (xy 0.21209 0.37719) (xy 0.2159 0.36703)
						(xy 0.21844 0.35687) (xy 0.22225 0.34544) (xy 0.22352 0.33528) (xy 0.22606 0.32512) (xy 0.22733 0.31369)
						(xy 0.22733 0.30353) (xy 0.2286 0.2921) (xy 0.22733 0.28067) (xy 0.22733 0.27051) (xy 0.22606 0.25908)
						(xy 0.22352 0.24892) (xy 0.22225 0.23876) (xy 0.21844 0.22733) (xy 0.2159 0.21717) (xy 0.21209 0.20701)
						(xy 0.20701 0.19685) (xy 0.2032 0.18796) (xy 0.19812 0.1778) (xy 0.17272 0.14224) (xy 0.1651 0.13462)
						(xy 0.1651 -0.7366) (xy 0.16256 -0.76835) (xy 0.1524 -0.8001) (xy 0.13716 -0.82804) (xy 0.11684 -0.85344)
						(xy 0.09144 -0.87376) (xy 0.0635 -0.889) (xy 0.03175 -0.89916)
					)
					(width 0)
					(fill yes)
				)
			)
		)
		(pad "79" smd custom
			(at -5.849874 -4.100068 180)
			(size 0.1143 0.1143)
			(layers "B.Cu" "B.Mask" "B.Paste")
			(net "GND")
			(options
				(clearance outline)
				(anchor circle)
			)
			(primitives
				(gr_poly
					(pts
						(xy 0 -0.9017) (xy -0.03175 -0.89916) (xy -0.0635 -0.889) (xy -0.09144 -0.87376) (xy -0.11684 -0.85344)
						(xy -0.13716 -0.82804) (xy -0.1524 -0.8001) (xy -0.16256 -0.76835) (xy -0.1651 -0.7366) (xy -0.1651 -0.19685)
						(xy -0.17272 -0.18923) (xy -0.17907 -0.18034) (xy -0.18669 -0.17145) (xy -0.19177 -0.16256) (xy -0.19812 -0.15367)
						(xy -0.20828 -0.13335) (xy -0.21971 -0.10287) (xy -0.22225 -0.09271) (xy -0.22479 -0.08128) (xy -0.22606 -0.07112)
						(xy -0.2286 -0.05969) (xy -0.2286 -0.01651) (xy -0.22606 -0.00508) (xy -0.22479 0.00508) (xy -0.22225 0.01651)
						(xy -0.21971 0.02667) (xy -0.20828 0.05715) (xy -0.19812 0.07747) (xy -0.19177 0.08636) (xy -0.18669 0.09525)
						(xy -0.17907 0.10414) (xy -0.17272 0.11303) (xy -0.1651 0.12065) (xy -0.1651 0.7366) (xy -0.16256 0.76835)
						(xy -0.1524 0.8001) (xy -0.13716 0.82804) (xy -0.11684 0.85344) (xy -0.09144 0.87376) (xy -0.0635 0.889)
						(xy -0.03175 0.89916) (xy 0 0.9017) (xy 0.03175 0.89916) (xy 0.0635 0.889) (xy 0.09144 0.87376)
						(xy 0.11684 0.85344) (xy 0.13716 0.82804) (xy 0.1524 0.8001) (xy 0.16256 0.76835) (xy 0.1651 0.7366)
						(xy 0.1651 0.11938) (xy 0.17272 0.11176) (xy 0.19812 0.0762) (xy 0.2032 0.06604) (xy 0.20701 0.05715)
						(xy 0.21209 0.04699) (xy 0.2159 0.03683) (xy 0.21844 0.02667) (xy 0.22225 0.01524) (xy 0.22352 0.00508)
						(xy 0.22606 -0.00508) (xy 0.22733 -0.01651) (xy 0.22733 -0.02667) (xy 0.2286 -0.0381) (xy 0.22733 -0.04953)
						(xy 0.22733 -0.05969) (xy 0.22606 -0.07112) (xy 0.22352 -0.08128) (xy 0.22225 -0.09144) (xy 0.21844 -0.10287)
						(xy 0.2159 -0.11303) (xy 0.21209 -0.12319) (xy 0.20701 -0.13335) (xy 0.2032 -0.14224) (xy 0.19812 -0.1524)
						(xy 0.17272 -0.18796) (xy 0.1651 -0.19558) (xy 0.1651 -0.7366) (xy 0.16256 -0.76835) (xy 0.1524 -0.8001)
						(xy 0.13716 -0.82804) (xy 0.11684 -0.85344) (xy 0.09144 -0.87376) (xy 0.0635 -0.889) (xy 0.03175 -0.89916)
					)
					(width 0)
					(fill yes)
				)
			)
		)
		(pad "80" smd custom
			(at -5.5499 4.100068 180)
			(size 0.1143 0.1143)
			(layers "B.Cu" "B.Mask" "B.Paste")
			(net "M_B_ECC6")
			(options
				(clearance outline)
				(anchor circle)
			)
			(primitives
				(gr_poly
					(pts
						(xy 0 -0.9017) (xy -0.03175 -0.89916) (xy -0.0635 -0.889) (xy -0.09144 -0.87376) (xy -0.11684 -0.85344)
						(xy -0.13716 -0.82804) (xy -0.1524 -0.8001) (xy -0.16256 -0.76835) (xy -0.1651 -0.7366) (xy -0.1651 -0.11938)
						(xy -0.17272 -0.11176) (xy -0.19812 -0.0762) (xy -0.2032 -0.06604) (xy -0.20701 -0.05715) (xy -0.21209 -0.04699)
						(xy -0.2159 -0.03683) (xy -0.21844 -0.02667) (xy -0.22225 -0.01524) (xy -0.22352 -0.00508) (xy -0.22606 0.00508)
						(xy -0.22733 0.01651) (xy -0.22733 0.02667) (xy -0.2286 0.0381) (xy -0.22733 0.04953) (xy -0.22733 0.05969)
						(xy -0.22606 0.07112) (xy -0.22352 0.08128) (xy -0.22225 0.09144) (xy -0.21844 0.10287) (xy -0.2159 0.11303)
						(xy -0.21209 0.12319) (xy -0.20701 0.13335) (xy -0.2032 0.14224) (xy -0.19812 0.1524) (xy -0.17272 0.18796)
						(xy -0.1651 0.19558) (xy -0.1651 0.7366) (xy -0.16256 0.76835) (xy -0.1524 0.8001) (xy -0.13716 0.82804)
						(xy -0.11684 0.85344) (xy -0.09144 0.87376) (xy -0.0635 0.889) (xy -0.03175 0.89916) (xy 0 0.9017)
						(xy 0.03175 0.89916) (xy 0.0635 0.889) (xy 0.09144 0.87376) (xy 0.11684 0.85344) (xy 0.13716 0.82804)
						(xy 0.1524 0.8001) (xy 0.16256 0.76835) (xy 0.1651 0.7366) (xy 0.1651 0.19685) (xy 0.17272 0.18923)
						(xy 0.17907 0.18034) (xy 0.18669 0.17145) (xy 0.19177 0.16256) (xy 0.19812 0.15367) (xy 0.20828 0.13335)
						(xy 0.21971 0.10287) (xy 0.22225 0.09271) (xy 0.22479 0.08128) (xy 0.22606 0.07112) (xy 0.2286 0.05969)
						(xy 0.2286 0.01651) (xy 0.22606 0.00508) (xy 0.22479 -0.00508) (xy 0.22225 -0.01651) (xy 0.21971 -0.02667)
						(xy 0.20828 -0.05715) (xy 0.19812 -0.07747) (xy 0.19177 -0.08636) (xy 0.18669 -0.09525) (xy 0.17907 -0.10414)
						(xy 0.17272 -0.11303) (xy 0.1651 -0.12065) (xy 0.1651 -0.7366) (xy 0.16256 -0.76835) (xy 0.1524 -0.8001)
						(xy 0.13716 -0.82804) (xy 0.11684 -0.85344) (xy 0.09144 -0.87376) (xy 0.0635 -0.889) (xy 0.03175 -0.89916)
					)
					(width 0)
					(fill yes)
				)
			)
		)
		(pad "81" smd custom
			(at -5.249926 -4.100068 180)
			(size 0.1143 0.1143)
			(layers "B.Cu" "B.Mask" "B.Paste")
			(net "M_B_ECC2")
			(options
				(clearance outline)
				(anchor circle)
			)
			(primitives
				(gr_poly
					(pts
						(xy 0 -0.9017) (xy -0.03175 -0.89916) (xy -0.0635 -0.889) (xy -0.09144 -0.87376) (xy -0.11684 -0.85344)
						(xy -0.13716 -0.82804) (xy -0.1524 -0.8001) (xy -0.16256 -0.76835) (xy -0.1651 -0.7366) (xy -0.1651 -0.44958)
						(xy -0.17272 -0.44196) (xy -0.19812 -0.4064) (xy -0.2032 -0.39624) (xy -0.20701 -0.38735) (xy -0.21209 -0.37719)
						(xy -0.2159 -0.36703) (xy -0.21844 -0.35687) (xy -0.22225 -0.34544) (xy -0.22352 -0.33528) (xy -0.22606 -0.32512)
						(xy -0.22733 -0.31369) (xy -0.22733 -0.30353) (xy -0.2286 -0.2921) (xy -0.22733 -0.28067) (xy -0.22733 -0.27051)
						(xy -0.22606 -0.25908) (xy -0.22352 -0.24892) (xy -0.22225 -0.23876) (xy -0.21844 -0.22733) (xy -0.2159 -0.21717)
						(xy -0.21209 -0.20701) (xy -0.20701 -0.19685) (xy -0.2032 -0.18796) (xy -0.19812 -0.1778) (xy -0.17272 -0.14224)
						(xy -0.1651 -0.13462) (xy -0.1651 0.7366) (xy -0.16256 0.76835) (xy -0.1524 0.8001) (xy -0.13716 0.82804)
						(xy -0.11684 0.85344) (xy -0.09144 0.87376) (xy -0.0635 0.889) (xy -0.03175 0.89916) (xy 0 0.9017)
						(xy 0.03175 0.89916) (xy 0.0635 0.889) (xy 0.09144 0.87376) (xy 0.11684 0.85344) (xy 0.13716 0.82804)
						(xy 0.1524 0.8001) (xy 0.16256 0.76835) (xy 0.1651 0.7366) (xy 0.1651 -0.13462) (xy 0.17272 -0.14224)
						(xy 0.19812 -0.1778) (xy 0.2032 -0.18796) (xy 0.20701 -0.19685) (xy 0.21209 -0.20701) (xy 0.2159 -0.21717)
						(xy 0.21844 -0.22733) (xy 0.22225 -0.23876) (xy 0.22352 -0.24892) (xy 0.22606 -0.25908) (xy 0.22733 -0.27051)
						(xy 0.22733 -0.28067) (xy 0.2286 -0.2921) (xy 0.22733 -0.30353) (xy 0.22733 -0.31369) (xy 0.22606 -0.32512)
						(xy 0.22352 -0.33528) (xy 0.22225 -0.34544) (xy 0.21844 -0.35687) (xy 0.2159 -0.36703) (xy 0.21209 -0.37719)
						(xy 0.20701 -0.38735) (xy 0.2032 -0.39624) (xy 0.19812 -0.4064) (xy 0.17272 -0.44196) (xy 0.1651 -0.44958)
						(xy 0.1651 -0.7366) (xy 0.16256 -0.76835) (xy 0.1524 -0.8001) (xy 0.13716 -0.82804) (xy 0.11684 -0.85344)
						(xy 0.09144 -0.87376) (xy 0.0635 -0.889) (xy 0.03175 -0.89916)
					)
					(width 0)
					(fill yes)
				)
			)
		)
		(pad "82" smd custom
			(at -4.949952 4.100068 180)
			(size 0.1143 0.1143)
			(layers "B.Cu" "B.Mask" "B.Paste")
			(net "M_B_ECC7")
			(options
				(clearance outline)
				(anchor circle)
			)
			(primitives
				(gr_poly
					(pts
						(xy 0 -0.9017) (xy -0.03175 -0.89916) (xy -0.0635 -0.889) (xy -0.09144 -0.87376) (xy -0.11684 -0.85344)
						(xy -0.13716 -0.82804) (xy -0.1524 -0.8001) (xy -0.16256 -0.76835) (xy -0.1651 -0.7366) (xy -0.1651 0.13462)
						(xy -0.17272 0.14224) (xy -0.19812 0.1778) (xy -0.2032 0.18796) (xy -0.20701 0.19685) (xy -0.21209 0.20701)
						(xy -0.2159 0.21717) (xy -0.21844 0.22733) (xy -0.22225 0.23876) (xy -0.22352 0.24892) (xy -0.22606 0.25908)
						(xy -0.22733 0.27051) (xy -0.22733 0.28067) (xy -0.2286 0.2921) (xy -0.22733 0.30353) (xy -0.22733 0.31369)
						(xy -0.22606 0.32512) (xy -0.22352 0.33528) (xy -0.22225 0.34544) (xy -0.21844 0.35687) (xy -0.2159 0.36703)
						(xy -0.21209 0.37719) (xy -0.20701 0.38735) (xy -0.2032 0.39624) (xy -0.19812 0.4064) (xy -0.17272 0.44196)
						(xy -0.1651 0.44958) (xy -0.1651 0.7366) (xy -0.16256 0.76835) (xy -0.1524 0.8001) (xy -0.13716 0.82804)
						(xy -0.11684 0.85344) (xy -0.09144 0.87376) (xy -0.0635 0.889) (xy -0.03175 0.89916) (xy 0 0.9017)
						(xy 0.03175 0.89916) (xy 0.0635 0.889) (xy 0.09144 0.87376) (xy 0.11684 0.85344) (xy 0.13716 0.82804)
						(xy 0.1524 0.8001) (xy 0.16256 0.76835) (xy 0.1651 0.7366) (xy 0.1651 0.44958) (xy 0.17272 0.44196)
						(xy 0.19812 0.4064) (xy 0.2032 0.39624) (xy 0.20701 0.38735) (xy 0.21209 0.37719) (xy 0.2159 0.36703)
						(xy 0.21844 0.35687) (xy 0.22225 0.34544) (xy 0.22352 0.33528) (xy 0.22606 0.32512) (xy 0.22733 0.31369)
						(xy 0.22733 0.30353) (xy 0.2286 0.2921) (xy 0.22733 0.28067) (xy 0.22733 0.27051) (xy 0.22606 0.25908)
						(xy 0.22352 0.24892) (xy 0.22225 0.23876) (xy 0.21844 0.22733) (xy 0.2159 0.21717) (xy 0.21209 0.20701)
						(xy 0.20701 0.19685) (xy 0.2032 0.18796) (xy 0.19812 0.1778) (xy 0.17272 0.14224) (xy 0.1651 0.13462)
						(xy 0.1651 -0.7366) (xy 0.16256 -0.76835) (xy 0.1524 -0.8001) (xy 0.13716 -0.82804) (xy 0.11684 -0.85344)
						(xy 0.09144 -0.87376) (xy 0.0635 -0.889) (xy 0.03175 -0.89916)
					)
					(width 0)
					(fill yes)
				)
			)
		)
		(pad "83" smd custom
			(at -4.649978 -4.100068 180)
			(size 0.1143 0.1143)
			(layers "B.Cu" "B.Mask" "B.Paste")
			(net "M_B_ECC3")
			(options
				(clearance outline)
				(anchor circle)
			)
			(primitives
				(gr_poly
					(pts
						(xy 0 -0.9017) (xy -0.03175 -0.89916) (xy -0.0635 -0.889) (xy -0.09144 -0.87376) (xy -0.11684 -0.85344)
						(xy -0.13716 -0.82804) (xy -0.1524 -0.8001) (xy -0.16256 -0.76835) (xy -0.1651 -0.7366) (xy -0.1651 -0.19685)
						(xy -0.17272 -0.18923) (xy -0.17907 -0.18034) (xy -0.18669 -0.17145) (xy -0.19177 -0.16256) (xy -0.19812 -0.15367)
						(xy -0.20828 -0.13335) (xy -0.21971 -0.10287) (xy -0.22225 -0.09271) (xy -0.22479 -0.08128) (xy -0.22606 -0.07112)
						(xy -0.2286 -0.05969) (xy -0.2286 -0.01651) (xy -0.22606 -0.00508) (xy -0.22479 0.00508) (xy -0.22225 0.01651)
						(xy -0.21971 0.02667) (xy -0.20828 0.05715) (xy -0.19812 0.07747) (xy -0.19177 0.08636) (xy -0.18669 0.09525)
						(xy -0.17907 0.10414) (xy -0.17272 0.11303) (xy -0.1651 0.12065) (xy -0.1651 0.7366) (xy -0.16256 0.76835)
						(xy -0.1524 0.8001) (xy -0.13716 0.82804) (xy -0.11684 0.85344) (xy -0.09144 0.87376) (xy -0.0635 0.889)
						(xy -0.03175 0.89916) (xy 0 0.9017) (xy 0.03175 0.89916) (xy 0.0635 0.889) (xy 0.09144 0.87376)
						(xy 0.11684 0.85344) (xy 0.13716 0.82804) (xy 0.1524 0.8001) (xy 0.16256 0.76835) (xy 0.1651 0.7366)
						(xy 0.1651 0.11938) (xy 0.17272 0.11176) (xy 0.19812 0.0762) (xy 0.2032 0.06604) (xy 0.20701 0.05715)
						(xy 0.21209 0.04699) (xy 0.2159 0.03683) (xy 0.21844 0.02667) (xy 0.22225 0.01524) (xy 0.22352 0.00508)
						(xy 0.22606 -0.00508) (xy 0.22733 -0.01651) (xy 0.22733 -0.02667) (xy 0.2286 -0.0381) (xy 0.22733 -0.04953)
						(xy 0.22733 -0.05969) (xy 0.22606 -0.07112) (xy 0.22352 -0.08128) (xy 0.22225 -0.09144) (xy 0.21844 -0.10287)
						(xy 0.2159 -0.11303) (xy 0.21209 -0.12319) (xy 0.20701 -0.13335) (xy 0.2032 -0.14224) (xy 0.19812 -0.1524)
						(xy 0.17272 -0.18796) (xy 0.1651 -0.19558) (xy 0.1651 -0.7366) (xy 0.16256 -0.76835) (xy 0.1524 -0.8001)
						(xy 0.13716 -0.82804) (xy 0.11684 -0.85344) (xy 0.09144 -0.87376) (xy 0.0635 -0.889) (xy 0.03175 -0.89916)
					)
					(width 0)
					(fill yes)
				)
			)
		)
		(pad "84" smd custom
			(at -4.350004 4.100068 180)
			(size 0.1143 0.1143)
			(layers "B.Cu" "B.Mask" "B.Paste")
			(net "DDR3_M_B_VREF_CA")
			(options
				(clearance outline)
				(anchor circle)
			)
			(primitives
				(gr_poly
					(pts
						(xy 0 -0.9017) (xy -0.03175 -0.89916) (xy -0.0635 -0.889) (xy -0.09144 -0.87376) (xy -0.11684 -0.85344)
						(xy -0.13716 -0.82804) (xy -0.1524 -0.8001) (xy -0.16256 -0.76835) (xy -0.1651 -0.7366) (xy -0.1651 -0.11938)
						(xy -0.17272 -0.11176) (xy -0.19812 -0.0762) (xy -0.2032 -0.06604) (xy -0.20701 -0.05715) (xy -0.21209 -0.04699)
						(xy -0.2159 -0.03683) (xy -0.21844 -0.02667) (xy -0.22225 -0.01524) (xy -0.22352 -0.00508) (xy -0.22606 0.00508)
						(xy -0.22733 0.01651) (xy -0.22733 0.02667) (xy -0.2286 0.0381) (xy -0.22733 0.04953) (xy -0.22733 0.05969)
						(xy -0.22606 0.07112) (xy -0.22352 0.08128) (xy -0.22225 0.09144) (xy -0.21844 0.10287) (xy -0.2159 0.11303)
						(xy -0.21209 0.12319) (xy -0.20701 0.13335) (xy -0.2032 0.14224) (xy -0.19812 0.1524) (xy -0.17272 0.18796)
						(xy -0.1651 0.19558) (xy -0.1651 0.7366) (xy -0.16256 0.76835) (xy -0.1524 0.8001) (xy -0.13716 0.82804)
						(xy -0.11684 0.85344) (xy -0.09144 0.87376) (xy -0.0635 0.889) (xy -0.03175 0.89916) (xy 0 0.9017)
						(xy 0.03175 0.89916) (xy 0.0635 0.889) (xy 0.09144 0.87376) (xy 0.11684 0.85344) (xy 0.13716 0.82804)
						(xy 0.1524 0.8001) (xy 0.16256 0.76835) (xy 0.1651 0.7366) (xy 0.1651 0.19685) (xy 0.17272 0.18923)
						(xy 0.17907 0.18034) (xy 0.18669 0.17145) (xy 0.19177 0.16256) (xy 0.19812 0.15367) (xy 0.20828 0.13335)
						(xy 0.21971 0.10287) (xy 0.22225 0.09271) (xy 0.22479 0.08128) (xy 0.22606 0.07112) (xy 0.2286 0.05969)
						(xy 0.2286 0.01651) (xy 0.22606 0.00508) (xy 0.22479 -0.00508) (xy 0.22225 -0.01651) (xy 0.21971 -0.02667)
						(xy 0.20828 -0.05715) (xy 0.19812 -0.07747) (xy 0.19177 -0.08636) (xy 0.18669 -0.09525) (xy 0.17907 -0.10414)
						(xy 0.17272 -0.11303) (xy 0.1651 -0.12065) (xy 0.1651 -0.7366) (xy 0.16256 -0.76835) (xy 0.1524 -0.8001)
						(xy 0.13716 -0.82804) (xy 0.11684 -0.85344) (xy 0.09144 -0.87376) (xy 0.0635 -0.889) (xy 0.03175 -0.89916)
					)
					(width 0)
					(fill yes)
				)
			)
		)
		(pad "85" smd custom
			(at -4.05003 -4.100068 180)
			(size 0.1143 0.1143)
			(layers "B.Cu" "B.Mask" "B.Paste")
			(net "PV_VDDR")
			(options
				(clearance outline)
				(anchor circle)
			)
			(primitives
				(gr_poly
					(pts
						(xy 0 -0.9017) (xy -0.03175 -0.89916) (xy -0.0635 -0.889) (xy -0.09144 -0.87376) (xy -0.11684 -0.85344)
						(xy -0.13716 -0.82804) (xy -0.1524 -0.8001) (xy -0.16256 -0.76835) (xy -0.1651 -0.7366) (xy -0.1651 -0.44958)
						(xy -0.17272 -0.44196) (xy -0.19812 -0.4064) (xy -0.2032 -0.39624) (xy -0.20701 -0.38735) (xy -0.21209 -0.37719)
						(xy -0.2159 -0.36703) (xy -0.21844 -0.35687) (xy -0.22225 -0.34544) (xy -0.22352 -0.33528) (xy -0.22606 -0.32512)
						(xy -0.22733 -0.31369) (xy -0.22733 -0.30353) (xy -0.2286 -0.2921) (xy -0.22733 -0.28067) (xy -0.22733 -0.27051)
						(xy -0.22606 -0.25908) (xy -0.22352 -0.24892) (xy -0.22225 -0.23876) (xy -0.21844 -0.22733) (xy -0.2159 -0.21717)
						(xy -0.21209 -0.20701) (xy -0.20701 -0.19685) (xy -0.2032 -0.18796) (xy -0.19812 -0.1778) (xy -0.17272 -0.14224)
						(xy -0.1651 -0.13462) (xy -0.1651 0.7366) (xy -0.16256 0.76835) (xy -0.1524 0.8001) (xy -0.13716 0.82804)
						(xy -0.11684 0.85344) (xy -0.09144 0.87376) (xy -0.0635 0.889) (xy -0.03175 0.89916) (xy 0 0.9017)
						(xy 0.03175 0.89916) (xy 0.0635 0.889) (xy 0.09144 0.87376) (xy 0.11684 0.85344) (xy 0.13716 0.82804)
						(xy 0.1524 0.8001) (xy 0.16256 0.76835) (xy 0.1651 0.7366) (xy 0.1651 -0.13462) (xy 0.17272 -0.14224)
						(xy 0.19812 -0.1778) (xy 0.2032 -0.18796) (xy 0.20701 -0.19685) (xy 0.21209 -0.20701) (xy 0.2159 -0.21717)
						(xy 0.21844 -0.22733) (xy 0.22225 -0.23876) (xy 0.22352 -0.24892) (xy 0.22606 -0.25908) (xy 0.22733 -0.27051)
						(xy 0.22733 -0.28067) (xy 0.2286 -0.2921) (xy 0.22733 -0.30353) (xy 0.22733 -0.31369) (xy 0.22606 -0.32512)
						(xy 0.22352 -0.33528) (xy 0.22225 -0.34544) (xy 0.21844 -0.35687) (xy 0.2159 -0.36703) (xy 0.21209 -0.37719)
						(xy 0.20701 -0.38735) (xy 0.2032 -0.39624) (xy 0.19812 -0.4064) (xy 0.17272 -0.44196) (xy 0.1651 -0.44958)
						(xy 0.1651 -0.7366) (xy 0.16256 -0.76835) (xy 0.1524 -0.8001) (xy 0.13716 -0.82804) (xy 0.11684 -0.85344)
						(xy 0.09144 -0.87376) (xy 0.0635 -0.889) (xy 0.03175 -0.89916)
					)
					(width 0)
					(fill yes)
				)
			)
		)
		(pad "86" smd custom
			(at -3.750056 4.100068 180)
			(size 0.1143 0.1143)
			(layers "B.Cu" "B.Mask" "B.Paste")
			(net "PV_VDDR")
			(options
				(clearance outline)
				(anchor circle)
			)
			(primitives
				(gr_poly
					(pts
						(xy 0 -0.9017) (xy -0.03175 -0.89916) (xy -0.0635 -0.889) (xy -0.09144 -0.87376) (xy -0.11684 -0.85344)
						(xy -0.13716 -0.82804) (xy -0.1524 -0.8001) (xy -0.16256 -0.76835) (xy -0.1651 -0.7366) (xy -0.1651 0.13462)
						(xy -0.17272 0.14224) (xy -0.19812 0.1778) (xy -0.2032 0.18796) (xy -0.20701 0.19685) (xy -0.21209 0.20701)
						(xy -0.2159 0.21717) (xy -0.21844 0.22733) (xy -0.22225 0.23876) (xy -0.22352 0.24892) (xy -0.22606 0.25908)
						(xy -0.22733 0.27051) (xy -0.22733 0.28067) (xy -0.2286 0.2921) (xy -0.22733 0.30353) (xy -0.22733 0.31369)
						(xy -0.22606 0.32512) (xy -0.22352 0.33528) (xy -0.22225 0.34544) (xy -0.21844 0.35687) (xy -0.2159 0.36703)
						(xy -0.21209 0.37719) (xy -0.20701 0.38735) (xy -0.2032 0.39624) (xy -0.19812 0.4064) (xy -0.17272 0.44196)
						(xy -0.1651 0.44958) (xy -0.1651 0.7366) (xy -0.16256 0.76835) (xy -0.1524 0.8001) (xy -0.13716 0.82804)
						(xy -0.11684 0.85344) (xy -0.09144 0.87376) (xy -0.0635 0.889) (xy -0.03175 0.89916) (xy 0 0.9017)
						(xy 0.03175 0.89916) (xy 0.0635 0.889) (xy 0.09144 0.87376) (xy 0.11684 0.85344) (xy 0.13716 0.82804)
						(xy 0.1524 0.8001) (xy 0.16256 0.76835) (xy 0.1651 0.7366) (xy 0.1651 0.44958) (xy 0.17272 0.44196)
						(xy 0.19812 0.4064) (xy 0.2032 0.39624) (xy 0.20701 0.38735) (xy 0.21209 0.37719) (xy 0.2159 0.36703)
						(xy 0.21844 0.35687) (xy 0.22225 0.34544) (xy 0.22352 0.33528) (xy 0.22606 0.32512) (xy 0.22733 0.31369)
						(xy 0.22733 0.30353) (xy 0.2286 0.2921) (xy 0.22733 0.28067) (xy 0.22733 0.27051) (xy 0.22606 0.25908)
						(xy 0.22352 0.24892) (xy 0.22225 0.23876) (xy 0.21844 0.22733) (xy 0.2159 0.21717) (xy 0.21209 0.20701)
						(xy 0.20701 0.19685) (xy 0.2032 0.18796) (xy 0.19812 0.1778) (xy 0.17272 0.14224) (xy 0.1651 0.13462)
						(xy 0.1651 -0.7366) (xy 0.16256 -0.76835) (xy 0.1524 -0.8001) (xy 0.13716 -0.82804) (xy 0.11684 -0.85344)
						(xy 0.09144 -0.87376) (xy 0.0635 -0.889) (xy 0.03175 -0.89916)
					)
					(width 0)
					(fill yes)
				)
			)
		)
		(pad "87" smd custom
			(at -3.450082 -4.100068 180)
			(size 0.1143 0.1143)
			(layers "B.Cu" "B.Mask" "B.Paste")
			(net "M_B_CKE0")
			(options
				(clearance outline)
				(anchor circle)
			)
			(primitives
				(gr_poly
					(pts
						(xy 0 -0.9017) (xy -0.03175 -0.89916) (xy -0.0635 -0.889) (xy -0.09144 -0.87376) (xy -0.11684 -0.85344)
						(xy -0.13716 -0.82804) (xy -0.1524 -0.8001) (xy -0.16256 -0.76835) (xy -0.1651 -0.7366) (xy -0.1651 -0.19685)
						(xy -0.17272 -0.18923) (xy -0.17907 -0.18034) (xy -0.18669 -0.17145) (xy -0.19177 -0.16256) (xy -0.19812 -0.15367)
						(xy -0.20828 -0.13335) (xy -0.21971 -0.10287) (xy -0.22225 -0.09271) (xy -0.22479 -0.08128) (xy -0.22606 -0.07112)
						(xy -0.2286 -0.05969) (xy -0.2286 -0.01651) (xy -0.22606 -0.00508) (xy -0.22479 0.00508) (xy -0.22225 0.01651)
						(xy -0.21971 0.02667) (xy -0.20828 0.05715) (xy -0.19812 0.07747) (xy -0.19177 0.08636) (xy -0.18669 0.09525)
						(xy -0.17907 0.10414) (xy -0.17272 0.11303) (xy -0.1651 0.12065) (xy -0.1651 0.7366) (xy -0.16256 0.76835)
						(xy -0.1524 0.8001) (xy -0.13716 0.82804) (xy -0.11684 0.85344) (xy -0.09144 0.87376) (xy -0.0635 0.889)
						(xy -0.03175 0.89916) (xy 0 0.9017) (xy 0.03175 0.89916) (xy 0.0635 0.889) (xy 0.09144 0.87376)
						(xy 0.11684 0.85344) (xy 0.13716 0.82804) (xy 0.1524 0.8001) (xy 0.16256 0.76835) (xy 0.1651 0.7366)
						(xy 0.1651 0.11938) (xy 0.17272 0.11176) (xy 0.19812 0.0762) (xy 0.2032 0.06604) (xy 0.20701 0.05715)
						(xy 0.21209 0.04699) (xy 0.2159 0.03683) (xy 0.21844 0.02667) (xy 0.22225 0.01524) (xy 0.22352 0.00508)
						(xy 0.22606 -0.00508) (xy 0.22733 -0.01651) (xy 0.22733 -0.02667) (xy 0.2286 -0.0381) (xy 0.22733 -0.04953)
						(xy 0.22733 -0.05969) (xy 0.22606 -0.07112) (xy 0.22352 -0.08128) (xy 0.22225 -0.09144) (xy 0.21844 -0.10287)
						(xy 0.2159 -0.11303) (xy 0.21209 -0.12319) (xy 0.20701 -0.13335) (xy 0.2032 -0.14224) (xy 0.19812 -0.1524)
						(xy 0.17272 -0.18796) (xy 0.1651 -0.19558) (xy 0.1651 -0.7366) (xy 0.16256 -0.76835) (xy 0.1524 -0.8001)
						(xy 0.13716 -0.82804) (xy 0.11684 -0.85344) (xy 0.09144 -0.87376) (xy 0.0635 -0.889) (xy 0.03175 -0.89916)
					)
					(width 0)
					(fill yes)
				)
			)
		)
		(pad "88" smd custom
			(at -3.150108 4.100068 180)
			(size 0.1143 0.1143)
			(layers "B.Cu" "B.Mask" "B.Paste")
			(net "M_B_MA15")
			(options
				(clearance outline)
				(anchor circle)
			)
			(primitives
				(gr_poly
					(pts
						(xy 0 -0.9017) (xy -0.03175 -0.89916) (xy -0.0635 -0.889) (xy -0.09144 -0.87376) (xy -0.11684 -0.85344)
						(xy -0.13716 -0.82804) (xy -0.1524 -0.8001) (xy -0.16256 -0.76835) (xy -0.1651 -0.7366) (xy -0.1651 -0.11938)
						(xy -0.17272 -0.11176) (xy -0.19812 -0.0762) (xy -0.2032 -0.06604) (xy -0.20701 -0.05715) (xy -0.21209 -0.04699)
						(xy -0.2159 -0.03683) (xy -0.21844 -0.02667) (xy -0.22225 -0.01524) (xy -0.22352 -0.00508) (xy -0.22606 0.00508)
						(xy -0.22733 0.01651) (xy -0.22733 0.02667) (xy -0.2286 0.0381) (xy -0.22733 0.04953) (xy -0.22733 0.05969)
						(xy -0.22606 0.07112) (xy -0.22352 0.08128) (xy -0.22225 0.09144) (xy -0.21844 0.10287) (xy -0.2159 0.11303)
						(xy -0.21209 0.12319) (xy -0.20701 0.13335) (xy -0.2032 0.14224) (xy -0.19812 0.1524) (xy -0.17272 0.18796)
						(xy -0.1651 0.19558) (xy -0.1651 0.7366) (xy -0.16256 0.76835) (xy -0.1524 0.8001) (xy -0.13716 0.82804)
						(xy -0.11684 0.85344) (xy -0.09144 0.87376) (xy -0.0635 0.889) (xy -0.03175 0.89916) (xy 0 0.9017)
						(xy 0.03175 0.89916) (xy 0.0635 0.889) (xy 0.09144 0.87376) (xy 0.11684 0.85344) (xy 0.13716 0.82804)
						(xy 0.1524 0.8001) (xy 0.16256 0.76835) (xy 0.1651 0.7366) (xy 0.1651 0.19685) (xy 0.17272 0.18923)
						(xy 0.17907 0.18034) (xy 0.18669 0.17145) (xy 0.19177 0.16256) (xy 0.19812 0.15367) (xy 0.20828 0.13335)
						(xy 0.21971 0.10287) (xy 0.22225 0.09271) (xy 0.22479 0.08128) (xy 0.22606 0.07112) (xy 0.2286 0.05969)
						(xy 0.2286 0.01651) (xy 0.22606 0.00508) (xy 0.22479 -0.00508) (xy 0.22225 -0.01651) (xy 0.21971 -0.02667)
						(xy 0.20828 -0.05715) (xy 0.19812 -0.07747) (xy 0.19177 -0.08636) (xy 0.18669 -0.09525) (xy 0.17907 -0.10414)
						(xy 0.17272 -0.11303) (xy 0.1651 -0.12065) (xy 0.1651 -0.7366) (xy 0.16256 -0.76835) (xy 0.1524 -0.8001)
						(xy 0.13716 -0.82804) (xy 0.11684 -0.85344) (xy 0.09144 -0.87376) (xy 0.0635 -0.889) (xy 0.03175 -0.89916)
					)
					(width 0)
					(fill yes)
				)
			)
		)
		(pad "89" smd custom
			(at -2.84988 -4.100068 180)
			(size 0.1143 0.1143)
			(layers "B.Cu" "B.Mask" "B.Paste")
			(net "M_B_CKE1")
			(options
				(clearance outline)
				(anchor circle)
			)
			(primitives
				(gr_poly
					(pts
						(xy 0 -0.9017) (xy -0.03175 -0.89916) (xy -0.0635 -0.889) (xy -0.09144 -0.87376) (xy -0.11684 -0.85344)
						(xy -0.13716 -0.82804) (xy -0.1524 -0.8001) (xy -0.16256 -0.76835) (xy -0.1651 -0.7366) (xy -0.1651 -0.44958)
						(xy -0.17272 -0.44196) (xy -0.19812 -0.4064) (xy -0.2032 -0.39624) (xy -0.20701 -0.38735) (xy -0.21209 -0.37719)
						(xy -0.2159 -0.36703) (xy -0.21844 -0.35687) (xy -0.22225 -0.34544) (xy -0.22352 -0.33528) (xy -0.22606 -0.32512)
						(xy -0.22733 -0.31369) (xy -0.22733 -0.30353) (xy -0.2286 -0.2921) (xy -0.22733 -0.28067) (xy -0.22733 -0.27051)
						(xy -0.22606 -0.25908) (xy -0.22352 -0.24892) (xy -0.22225 -0.23876) (xy -0.21844 -0.22733) (xy -0.2159 -0.21717)
						(xy -0.21209 -0.20701) (xy -0.20701 -0.19685) (xy -0.2032 -0.18796) (xy -0.19812 -0.1778) (xy -0.17272 -0.14224)
						(xy -0.1651 -0.13462) (xy -0.1651 0.7366) (xy -0.16256 0.76835) (xy -0.1524 0.8001) (xy -0.13716 0.82804)
						(xy -0.11684 0.85344) (xy -0.09144 0.87376) (xy -0.0635 0.889) (xy -0.03175 0.89916) (xy 0 0.9017)
						(xy 0.03175 0.89916) (xy 0.0635 0.889) (xy 0.09144 0.87376) (xy 0.11684 0.85344) (xy 0.13716 0.82804)
						(xy 0.1524 0.8001) (xy 0.16256 0.76835) (xy 0.1651 0.7366) (xy 0.1651 -0.13462) (xy 0.17272 -0.14224)
						(xy 0.19812 -0.1778) (xy 0.2032 -0.18796) (xy 0.20701 -0.19685) (xy 0.21209 -0.20701) (xy 0.2159 -0.21717)
						(xy 0.21844 -0.22733) (xy 0.22225 -0.23876) (xy 0.22352 -0.24892) (xy 0.22606 -0.25908) (xy 0.22733 -0.27051)
						(xy 0.22733 -0.28067) (xy 0.2286 -0.2921) (xy 0.22733 -0.30353) (xy 0.22733 -0.31369) (xy 0.22606 -0.32512)
						(xy 0.22352 -0.33528) (xy 0.22225 -0.34544) (xy 0.21844 -0.35687) (xy 0.2159 -0.36703) (xy 0.21209 -0.37719)
						(xy 0.20701 -0.38735) (xy 0.2032 -0.39624) (xy 0.19812 -0.4064) (xy 0.17272 -0.44196) (xy 0.1651 -0.44958)
						(xy 0.1651 -0.7366) (xy 0.16256 -0.76835) (xy 0.1524 -0.8001) (xy 0.13716 -0.82804) (xy 0.11684 -0.85344)
						(xy 0.09144 -0.87376) (xy 0.0635 -0.889) (xy 0.03175 -0.89916)
					)
					(width 0)
					(fill yes)
				)
			)
		)
		(pad "90" smd custom
			(at -2.549906 4.100068 180)
			(size 0.1143 0.1143)
			(layers "B.Cu" "B.Mask" "B.Paste")
			(net "M_B_MA14")
			(options
				(clearance outline)
				(anchor circle)
			)
			(primitives
				(gr_poly
					(pts
						(xy 0 -0.9017) (xy -0.03175 -0.89916) (xy -0.0635 -0.889) (xy -0.09144 -0.87376) (xy -0.11684 -0.85344)
						(xy -0.13716 -0.82804) (xy -0.1524 -0.8001) (xy -0.16256 -0.76835) (xy -0.1651 -0.7366) (xy -0.1651 0.13462)
						(xy -0.17272 0.14224) (xy -0.19812 0.1778) (xy -0.2032 0.18796) (xy -0.20701 0.19685) (xy -0.21209 0.20701)
						(xy -0.2159 0.21717) (xy -0.21844 0.22733) (xy -0.22225 0.23876) (xy -0.22352 0.24892) (xy -0.22606 0.25908)
						(xy -0.22733 0.27051) (xy -0.22733 0.28067) (xy -0.2286 0.2921) (xy -0.22733 0.30353) (xy -0.22733 0.31369)
						(xy -0.22606 0.32512) (xy -0.22352 0.33528) (xy -0.22225 0.34544) (xy -0.21844 0.35687) (xy -0.2159 0.36703)
						(xy -0.21209 0.37719) (xy -0.20701 0.38735) (xy -0.2032 0.39624) (xy -0.19812 0.4064) (xy -0.17272 0.44196)
						(xy -0.1651 0.44958) (xy -0.1651 0.7366) (xy -0.16256 0.76835) (xy -0.1524 0.8001) (xy -0.13716 0.82804)
						(xy -0.11684 0.85344) (xy -0.09144 0.87376) (xy -0.0635 0.889) (xy -0.03175 0.89916) (xy 0 0.9017)
						(xy 0.03175 0.89916) (xy 0.0635 0.889) (xy 0.09144 0.87376) (xy 0.11684 0.85344) (xy 0.13716 0.82804)
						(xy 0.1524 0.8001) (xy 0.16256 0.76835) (xy 0.1651 0.7366) (xy 0.1651 0.44958) (xy 0.17272 0.44196)
						(xy 0.19812 0.4064) (xy 0.2032 0.39624) (xy 0.20701 0.38735) (xy 0.21209 0.37719) (xy 0.2159 0.36703)
						(xy 0.21844 0.35687) (xy 0.22225 0.34544) (xy 0.22352 0.33528) (xy 0.22606 0.32512) (xy 0.22733 0.31369)
						(xy 0.22733 0.30353) (xy 0.2286 0.2921) (xy 0.22733 0.28067) (xy 0.22733 0.27051) (xy 0.22606 0.25908)
						(xy 0.22352 0.24892) (xy 0.22225 0.23876) (xy 0.21844 0.22733) (xy 0.2159 0.21717) (xy 0.21209 0.20701)
						(xy 0.20701 0.19685) (xy 0.2032 0.18796) (xy 0.19812 0.1778) (xy 0.17272 0.14224) (xy 0.1651 0.13462)
						(xy 0.1651 -0.7366) (xy 0.16256 -0.76835) (xy 0.1524 -0.8001) (xy 0.13716 -0.82804) (xy 0.11684 -0.85344)
						(xy 0.09144 -0.87376) (xy 0.0635 -0.889) (xy 0.03175 -0.89916)
					)
					(width 0)
					(fill yes)
				)
			)
		)
		(pad "91" smd custom
			(at -2.249932 -4.100068 180)
			(size 0.1143 0.1143)
			(layers "B.Cu" "B.Mask" "B.Paste")
			(net "M_B_BS2")
			(options
				(clearance outline)
				(anchor circle)
			)
			(primitives
				(gr_poly
					(pts
						(xy 0 -0.9017) (xy -0.03175 -0.89916) (xy -0.0635 -0.889) (xy -0.09144 -0.87376) (xy -0.11684 -0.85344)
						(xy -0.13716 -0.82804) (xy -0.1524 -0.8001) (xy -0.16256 -0.76835) (xy -0.1651 -0.7366) (xy -0.1651 -0.19685)
						(xy -0.17272 -0.18923) (xy -0.17907 -0.18034) (xy -0.18669 -0.17145) (xy -0.19177 -0.16256) (xy -0.19812 -0.15367)
						(xy -0.20828 -0.13335) (xy -0.21971 -0.10287) (xy -0.22225 -0.09271) (xy -0.22479 -0.08128) (xy -0.22606 -0.07112)
						(xy -0.2286 -0.05969) (xy -0.2286 -0.01651) (xy -0.22606 -0.00508) (xy -0.22479 0.00508) (xy -0.22225 0.01651)
						(xy -0.21971 0.02667) (xy -0.20828 0.05715) (xy -0.19812 0.07747) (xy -0.19177 0.08636) (xy -0.18669 0.09525)
						(xy -0.17907 0.10414) (xy -0.17272 0.11303) (xy -0.1651 0.12065) (xy -0.1651 0.7366) (xy -0.16256 0.76835)
						(xy -0.1524 0.8001) (xy -0.13716 0.82804) (xy -0.11684 0.85344) (xy -0.09144 0.87376) (xy -0.0635 0.889)
						(xy -0.03175 0.89916) (xy 0 0.9017) (xy 0.03175 0.89916) (xy 0.0635 0.889) (xy 0.09144 0.87376)
						(xy 0.11684 0.85344) (xy 0.13716 0.82804) (xy 0.1524 0.8001) (xy 0.16256 0.76835) (xy 0.1651 0.7366)
						(xy 0.1651 0.11938) (xy 0.17272 0.11176) (xy 0.19812 0.0762) (xy 0.2032 0.06604) (xy 0.20701 0.05715)
						(xy 0.21209 0.04699) (xy 0.2159 0.03683) (xy 0.21844 0.02667) (xy 0.22225 0.01524) (xy 0.22352 0.00508)
						(xy 0.22606 -0.00508) (xy 0.22733 -0.01651) (xy 0.22733 -0.02667) (xy 0.2286 -0.0381) (xy 0.22733 -0.04953)
						(xy 0.22733 -0.05969) (xy 0.22606 -0.07112) (xy 0.22352 -0.08128) (xy 0.22225 -0.09144) (xy 0.21844 -0.10287)
						(xy 0.2159 -0.11303) (xy 0.21209 -0.12319) (xy 0.20701 -0.13335) (xy 0.2032 -0.14224) (xy 0.19812 -0.1524)
						(xy 0.17272 -0.18796) (xy 0.1651 -0.19558) (xy 0.1651 -0.7366) (xy 0.16256 -0.76835) (xy 0.1524 -0.8001)
						(xy 0.13716 -0.82804) (xy 0.11684 -0.85344) (xy 0.09144 -0.87376) (xy 0.0635 -0.889) (xy 0.03175 -0.89916)
					)
					(width 0)
					(fill yes)
				)
			)
		)
		(pad "92" smd custom
			(at -1.949958 4.100068 180)
			(size 0.1143 0.1143)
			(layers "B.Cu" "B.Mask" "B.Paste")
			(net "M_B_MA9")
			(options
				(clearance outline)
				(anchor circle)
			)
			(primitives
				(gr_poly
					(pts
						(xy 0 -0.9017) (xy -0.03175 -0.89916) (xy -0.0635 -0.889) (xy -0.09144 -0.87376) (xy -0.11684 -0.85344)
						(xy -0.13716 -0.82804) (xy -0.1524 -0.8001) (xy -0.16256 -0.76835) (xy -0.1651 -0.7366) (xy -0.1651 -0.11938)
						(xy -0.17272 -0.11176) (xy -0.19812 -0.0762) (xy -0.2032 -0.06604) (xy -0.20701 -0.05715) (xy -0.21209 -0.04699)
						(xy -0.2159 -0.03683) (xy -0.21844 -0.02667) (xy -0.22225 -0.01524) (xy -0.22352 -0.00508) (xy -0.22606 0.00508)
						(xy -0.22733 0.01651) (xy -0.22733 0.02667) (xy -0.2286 0.0381) (xy -0.22733 0.04953) (xy -0.22733 0.05969)
						(xy -0.22606 0.07112) (xy -0.22352 0.08128) (xy -0.22225 0.09144) (xy -0.21844 0.10287) (xy -0.2159 0.11303)
						(xy -0.21209 0.12319) (xy -0.20701 0.13335) (xy -0.2032 0.14224) (xy -0.19812 0.1524) (xy -0.17272 0.18796)
						(xy -0.1651 0.19558) (xy -0.1651 0.7366) (xy -0.16256 0.76835) (xy -0.1524 0.8001) (xy -0.13716 0.82804)
						(xy -0.11684 0.85344) (xy -0.09144 0.87376) (xy -0.0635 0.889) (xy -0.03175 0.89916) (xy 0 0.9017)
						(xy 0.03175 0.89916) (xy 0.0635 0.889) (xy 0.09144 0.87376) (xy 0.11684 0.85344) (xy 0.13716 0.82804)
						(xy 0.1524 0.8001) (xy 0.16256 0.76835) (xy 0.1651 0.7366) (xy 0.1651 0.19685) (xy 0.17272 0.18923)
						(xy 0.17907 0.18034) (xy 0.18669 0.17145) (xy 0.19177 0.16256) (xy 0.19812 0.15367) (xy 0.20828 0.13335)
						(xy 0.21971 0.10287) (xy 0.22225 0.09271) (xy 0.22479 0.08128) (xy 0.22606 0.07112) (xy 0.2286 0.05969)
						(xy 0.2286 0.01651) (xy 0.22606 0.00508) (xy 0.22479 -0.00508) (xy 0.22225 -0.01651) (xy 0.21971 -0.02667)
						(xy 0.20828 -0.05715) (xy 0.19812 -0.07747) (xy 0.19177 -0.08636) (xy 0.18669 -0.09525) (xy 0.17907 -0.10414)
						(xy 0.17272 -0.11303) (xy 0.1651 -0.12065) (xy 0.1651 -0.7366) (xy 0.16256 -0.76835) (xy 0.1524 -0.8001)
						(xy 0.13716 -0.82804) (xy 0.11684 -0.85344) (xy 0.09144 -0.87376) (xy 0.0635 -0.889) (xy 0.03175 -0.89916)
					)
					(width 0)
					(fill yes)
				)
			)
		)
		(pad "93" smd custom
			(at -1.649984 -4.100068 180)
			(size 0.1143 0.1143)
			(layers "B.Cu" "B.Mask" "B.Paste")
			(net "PV_VDDR")
			(options
				(clearance outline)
				(anchor circle)
			)
			(primitives
				(gr_poly
					(pts
						(xy 0 -0.9017) (xy -0.03175 -0.89916) (xy -0.0635 -0.889) (xy -0.09144 -0.87376) (xy -0.11684 -0.85344)
						(xy -0.13716 -0.82804) (xy -0.1524 -0.8001) (xy -0.16256 -0.76835) (xy -0.1651 -0.7366) (xy -0.1651 -0.44958)
						(xy -0.17272 -0.44196) (xy -0.19812 -0.4064) (xy -0.2032 -0.39624) (xy -0.20701 -0.38735) (xy -0.21209 -0.37719)
						(xy -0.2159 -0.36703) (xy -0.21844 -0.35687) (xy -0.22225 -0.34544) (xy -0.22352 -0.33528) (xy -0.22606 -0.32512)
						(xy -0.22733 -0.31369) (xy -0.22733 -0.30353) (xy -0.2286 -0.2921) (xy -0.22733 -0.28067) (xy -0.22733 -0.27051)
						(xy -0.22606 -0.25908) (xy -0.22352 -0.24892) (xy -0.22225 -0.23876) (xy -0.21844 -0.22733) (xy -0.2159 -0.21717)
						(xy -0.21209 -0.20701) (xy -0.20701 -0.19685) (xy -0.2032 -0.18796) (xy -0.19812 -0.1778) (xy -0.17272 -0.14224)
						(xy -0.1651 -0.13462) (xy -0.1651 0.7366) (xy -0.16256 0.76835) (xy -0.1524 0.8001) (xy -0.13716 0.82804)
						(xy -0.11684 0.85344) (xy -0.09144 0.87376) (xy -0.0635 0.889) (xy -0.03175 0.89916) (xy 0 0.9017)
						(xy 0.03175 0.89916) (xy 0.0635 0.889) (xy 0.09144 0.87376) (xy 0.11684 0.85344) (xy 0.13716 0.82804)
						(xy 0.1524 0.8001) (xy 0.16256 0.76835) (xy 0.1651 0.7366) (xy 0.1651 -0.13462) (xy 0.17272 -0.14224)
						(xy 0.19812 -0.1778) (xy 0.2032 -0.18796) (xy 0.20701 -0.19685) (xy 0.21209 -0.20701) (xy 0.2159 -0.21717)
						(xy 0.21844 -0.22733) (xy 0.22225 -0.23876) (xy 0.22352 -0.24892) (xy 0.22606 -0.25908) (xy 0.22733 -0.27051)
						(xy 0.22733 -0.28067) (xy 0.2286 -0.2921) (xy 0.22733 -0.30353) (xy 0.22733 -0.31369) (xy 0.22606 -0.32512)
						(xy 0.22352 -0.33528) (xy 0.22225 -0.34544) (xy 0.21844 -0.35687) (xy 0.2159 -0.36703) (xy 0.21209 -0.37719)
						(xy 0.20701 -0.38735) (xy 0.2032 -0.39624) (xy 0.19812 -0.4064) (xy 0.17272 -0.44196) (xy 0.1651 -0.44958)
						(xy 0.1651 -0.7366) (xy 0.16256 -0.76835) (xy 0.1524 -0.8001) (xy 0.13716 -0.82804) (xy 0.11684 -0.85344)
						(xy 0.09144 -0.87376) (xy 0.0635 -0.889) (xy 0.03175 -0.89916)
					)
					(width 0)
					(fill yes)
				)
			)
		)
		(pad "94" smd custom
			(at -1.35001 4.100068 180)
			(size 0.1143 0.1143)
			(layers "B.Cu" "B.Mask" "B.Paste")
			(net "PV_VDDR")
			(options
				(clearance outline)
				(anchor circle)
			)
			(primitives
				(gr_poly
					(pts
						(xy 0 -0.9017) (xy -0.03175 -0.89916) (xy -0.0635 -0.889) (xy -0.09144 -0.87376) (xy -0.11684 -0.85344)
						(xy -0.13716 -0.82804) (xy -0.1524 -0.8001) (xy -0.16256 -0.76835) (xy -0.1651 -0.7366) (xy -0.1651 0.13462)
						(xy -0.17272 0.14224) (xy -0.19812 0.1778) (xy -0.2032 0.18796) (xy -0.20701 0.19685) (xy -0.21209 0.20701)
						(xy -0.2159 0.21717) (xy -0.21844 0.22733) (xy -0.22225 0.23876) (xy -0.22352 0.24892) (xy -0.22606 0.25908)
						(xy -0.22733 0.27051) (xy -0.22733 0.28067) (xy -0.2286 0.2921) (xy -0.22733 0.30353) (xy -0.22733 0.31369)
						(xy -0.22606 0.32512) (xy -0.22352 0.33528) (xy -0.22225 0.34544) (xy -0.21844 0.35687) (xy -0.2159 0.36703)
						(xy -0.21209 0.37719) (xy -0.20701 0.38735) (xy -0.2032 0.39624) (xy -0.19812 0.4064) (xy -0.17272 0.44196)
						(xy -0.1651 0.44958) (xy -0.1651 0.7366) (xy -0.16256 0.76835) (xy -0.1524 0.8001) (xy -0.13716 0.82804)
						(xy -0.11684 0.85344) (xy -0.09144 0.87376) (xy -0.0635 0.889) (xy -0.03175 0.89916) (xy 0 0.9017)
						(xy 0.03175 0.89916) (xy 0.0635 0.889) (xy 0.09144 0.87376) (xy 0.11684 0.85344) (xy 0.13716 0.82804)
						(xy 0.1524 0.8001) (xy 0.16256 0.76835) (xy 0.1651 0.7366) (xy 0.1651 0.44958) (xy 0.17272 0.44196)
						(xy 0.19812 0.4064) (xy 0.2032 0.39624) (xy 0.20701 0.38735) (xy 0.21209 0.37719) (xy 0.2159 0.36703)
						(xy 0.21844 0.35687) (xy 0.22225 0.34544) (xy 0.22352 0.33528) (xy 0.22606 0.32512) (xy 0.22733 0.31369)
						(xy 0.22733 0.30353) (xy 0.2286 0.2921) (xy 0.22733 0.28067) (xy 0.22733 0.27051) (xy 0.22606 0.25908)
						(xy 0.22352 0.24892) (xy 0.22225 0.23876) (xy 0.21844 0.22733) (xy 0.2159 0.21717) (xy 0.21209 0.20701)
						(xy 0.20701 0.19685) (xy 0.2032 0.18796) (xy 0.19812 0.1778) (xy 0.17272 0.14224) (xy 0.1651 0.13462)
						(xy 0.1651 -0.7366) (xy 0.16256 -0.76835) (xy 0.1524 -0.8001) (xy 0.13716 -0.82804) (xy 0.11684 -0.85344)
						(xy 0.09144 -0.87376) (xy 0.0635 -0.889) (xy 0.03175 -0.89916)
					)
					(width 0)
					(fill yes)
				)
			)
		)
		(pad "95" smd custom
			(at -1.050036 -4.100068 180)
			(size 0.1143 0.1143)
			(layers "B.Cu" "B.Mask" "B.Paste")
			(net "M_B_MA12")
			(options
				(clearance outline)
				(anchor circle)
			)
			(primitives
				(gr_poly
					(pts
						(xy 0 -0.9017) (xy -0.03175 -0.89916) (xy -0.0635 -0.889) (xy -0.09144 -0.87376) (xy -0.11684 -0.85344)
						(xy -0.13716 -0.82804) (xy -0.1524 -0.8001) (xy -0.16256 -0.76835) (xy -0.1651 -0.7366) (xy -0.1651 -0.19685)
						(xy -0.17272 -0.18923) (xy -0.17907 -0.18034) (xy -0.18669 -0.17145) (xy -0.19177 -0.16256) (xy -0.19812 -0.15367)
						(xy -0.20828 -0.13335) (xy -0.21971 -0.10287) (xy -0.22225 -0.09271) (xy -0.22479 -0.08128) (xy -0.22606 -0.07112)
						(xy -0.2286 -0.05969) (xy -0.2286 -0.01651) (xy -0.22606 -0.00508) (xy -0.22479 0.00508) (xy -0.22225 0.01651)
						(xy -0.21971 0.02667) (xy -0.20828 0.05715) (xy -0.19812 0.07747) (xy -0.19177 0.08636) (xy -0.18669 0.09525)
						(xy -0.17907 0.10414) (xy -0.17272 0.11303) (xy -0.1651 0.12065) (xy -0.1651 0.7366) (xy -0.16256 0.76835)
						(xy -0.1524 0.8001) (xy -0.13716 0.82804) (xy -0.11684 0.85344) (xy -0.09144 0.87376) (xy -0.0635 0.889)
						(xy -0.03175 0.89916) (xy 0 0.9017) (xy 0.03175 0.89916) (xy 0.0635 0.889) (xy 0.09144 0.87376)
						(xy 0.11684 0.85344) (xy 0.13716 0.82804) (xy 0.1524 0.8001) (xy 0.16256 0.76835) (xy 0.1651 0.7366)
						(xy 0.1651 0.11938) (xy 0.17272 0.11176) (xy 0.19812 0.0762) (xy 0.2032 0.06604) (xy 0.20701 0.05715)
						(xy 0.21209 0.04699) (xy 0.2159 0.03683) (xy 0.21844 0.02667) (xy 0.22225 0.01524) (xy 0.22352 0.00508)
						(xy 0.22606 -0.00508) (xy 0.22733 -0.01651) (xy 0.22733 -0.02667) (xy 0.2286 -0.0381) (xy 0.22733 -0.04953)
						(xy 0.22733 -0.05969) (xy 0.22606 -0.07112) (xy 0.22352 -0.08128) (xy 0.22225 -0.09144) (xy 0.21844 -0.10287)
						(xy 0.2159 -0.11303) (xy 0.21209 -0.12319) (xy 0.20701 -0.13335) (xy 0.2032 -0.14224) (xy 0.19812 -0.1524)
						(xy 0.17272 -0.18796) (xy 0.1651 -0.19558) (xy 0.1651 -0.7366) (xy 0.16256 -0.76835) (xy 0.1524 -0.8001)
						(xy 0.13716 -0.82804) (xy 0.11684 -0.85344) (xy 0.09144 -0.87376) (xy 0.0635 -0.889) (xy 0.03175 -0.89916)
					)
					(width 0)
					(fill yes)
				)
			)
		)
		(pad "96" smd custom
			(at -0.750062 4.100068 180)
			(size 0.1143 0.1143)
			(layers "B.Cu" "B.Mask" "B.Paste")
			(net "M_B_MA11")
			(options
				(clearance outline)
				(anchor circle)
			)
			(primitives
				(gr_poly
					(pts
						(xy 0 -0.9017) (xy -0.03175 -0.89916) (xy -0.0635 -0.889) (xy -0.09144 -0.87376) (xy -0.11684 -0.85344)
						(xy -0.13716 -0.82804) (xy -0.1524 -0.8001) (xy -0.16256 -0.76835) (xy -0.1651 -0.7366) (xy -0.1651 -0.11938)
						(xy -0.17272 -0.11176) (xy -0.19812 -0.0762) (xy -0.2032 -0.06604) (xy -0.20701 -0.05715) (xy -0.21209 -0.04699)
						(xy -0.2159 -0.03683) (xy -0.21844 -0.02667) (xy -0.22225 -0.01524) (xy -0.22352 -0.00508) (xy -0.22606 0.00508)
						(xy -0.22733 0.01651) (xy -0.22733 0.02667) (xy -0.2286 0.0381) (xy -0.22733 0.04953) (xy -0.22733 0.05969)
						(xy -0.22606 0.07112) (xy -0.22352 0.08128) (xy -0.22225 0.09144) (xy -0.21844 0.10287) (xy -0.2159 0.11303)
						(xy -0.21209 0.12319) (xy -0.20701 0.13335) (xy -0.2032 0.14224) (xy -0.19812 0.1524) (xy -0.17272 0.18796)
						(xy -0.1651 0.19558) (xy -0.1651 0.7366) (xy -0.16256 0.76835) (xy -0.1524 0.8001) (xy -0.13716 0.82804)
						(xy -0.11684 0.85344) (xy -0.09144 0.87376) (xy -0.0635 0.889) (xy -0.03175 0.89916) (xy 0 0.9017)
						(xy 0.03175 0.89916) (xy 0.0635 0.889) (xy 0.09144 0.87376) (xy 0.11684 0.85344) (xy 0.13716 0.82804)
						(xy 0.1524 0.8001) (xy 0.16256 0.76835) (xy 0.1651 0.7366) (xy 0.1651 0.19685) (xy 0.17272 0.18923)
						(xy 0.17907 0.18034) (xy 0.18669 0.17145) (xy 0.19177 0.16256) (xy 0.19812 0.15367) (xy 0.20828 0.13335)
						(xy 0.21971 0.10287) (xy 0.22225 0.09271) (xy 0.22479 0.08128) (xy 0.22606 0.07112) (xy 0.2286 0.05969)
						(xy 0.2286 0.01651) (xy 0.22606 0.00508) (xy 0.22479 -0.00508) (xy 0.22225 -0.01651) (xy 0.21971 -0.02667)
						(xy 0.20828 -0.05715) (xy 0.19812 -0.07747) (xy 0.19177 -0.08636) (xy 0.18669 -0.09525) (xy 0.17907 -0.10414)
						(xy 0.17272 -0.11303) (xy 0.1651 -0.12065) (xy 0.1651 -0.7366) (xy 0.16256 -0.76835) (xy 0.1524 -0.8001)
						(xy 0.13716 -0.82804) (xy 0.11684 -0.85344) (xy 0.09144 -0.87376) (xy 0.0635 -0.889) (xy 0.03175 -0.89916)
					)
					(width 0)
					(fill yes)
				)
			)
		)
		(pad "97" smd custom
			(at -0.450088 -4.100068 180)
			(size 0.1143 0.1143)
			(layers "B.Cu" "B.Mask" "B.Paste")
			(net "M_B_MA8")
			(options
				(clearance outline)
				(anchor circle)
			)
			(primitives
				(gr_poly
					(pts
						(xy 0 -0.9017) (xy -0.03175 -0.89916) (xy -0.0635 -0.889) (xy -0.09144 -0.87376) (xy -0.11684 -0.85344)
						(xy -0.13716 -0.82804) (xy -0.1524 -0.8001) (xy -0.16256 -0.76835) (xy -0.1651 -0.7366) (xy -0.1651 -0.44958)
						(xy -0.17272 -0.44196) (xy -0.19812 -0.4064) (xy -0.2032 -0.39624) (xy -0.20701 -0.38735) (xy -0.21209 -0.37719)
						(xy -0.2159 -0.36703) (xy -0.21844 -0.35687) (xy -0.22225 -0.34544) (xy -0.22352 -0.33528) (xy -0.22606 -0.32512)
						(xy -0.22733 -0.31369) (xy -0.22733 -0.30353) (xy -0.2286 -0.2921) (xy -0.22733 -0.28067) (xy -0.22733 -0.27051)
						(xy -0.22606 -0.25908) (xy -0.22352 -0.24892) (xy -0.22225 -0.23876) (xy -0.21844 -0.22733) (xy -0.2159 -0.21717)
						(xy -0.21209 -0.20701) (xy -0.20701 -0.19685) (xy -0.2032 -0.18796) (xy -0.19812 -0.1778) (xy -0.17272 -0.14224)
						(xy -0.1651 -0.13462) (xy -0.1651 0.7366) (xy -0.16256 0.76835) (xy -0.1524 0.8001) (xy -0.13716 0.82804)
						(xy -0.11684 0.85344) (xy -0.09144 0.87376) (xy -0.0635 0.889) (xy -0.03175 0.89916) (xy 0 0.9017)
						(xy 0.03175 0.89916) (xy 0.0635 0.889) (xy 0.09144 0.87376) (xy 0.11684 0.85344) (xy 0.13716 0.82804)
						(xy 0.1524 0.8001) (xy 0.16256 0.76835) (xy 0.1651 0.7366) (xy 0.1651 -0.13462) (xy 0.17272 -0.14224)
						(xy 0.19812 -0.1778) (xy 0.2032 -0.18796) (xy 0.20701 -0.19685) (xy 0.21209 -0.20701) (xy 0.2159 -0.21717)
						(xy 0.21844 -0.22733) (xy 0.22225 -0.23876) (xy 0.22352 -0.24892) (xy 0.22606 -0.25908) (xy 0.22733 -0.27051)
						(xy 0.22733 -0.28067) (xy 0.2286 -0.2921) (xy 0.22733 -0.30353) (xy 0.22733 -0.31369) (xy 0.22606 -0.32512)
						(xy 0.22352 -0.33528) (xy 0.22225 -0.34544) (xy 0.21844 -0.35687) (xy 0.2159 -0.36703) (xy 0.21209 -0.37719)
						(xy 0.20701 -0.38735) (xy 0.2032 -0.39624) (xy 0.19812 -0.4064) (xy 0.17272 -0.44196) (xy 0.1651 -0.44958)
						(xy 0.1651 -0.7366) (xy 0.16256 -0.76835) (xy 0.1524 -0.8001) (xy 0.13716 -0.82804) (xy 0.11684 -0.85344)
						(xy 0.09144 -0.87376) (xy 0.0635 -0.889) (xy 0.03175 -0.89916)
					)
					(width 0)
					(fill yes)
				)
			)
		)
		(pad "98" smd custom
			(at -0.150114 4.100068 180)
			(size 0.1143 0.1143)
			(layers "B.Cu" "B.Mask" "B.Paste")
			(net "M_B_MA7")
			(options
				(clearance outline)
				(anchor circle)
			)
			(primitives
				(gr_poly
					(pts
						(xy 0 -0.9017) (xy -0.03175 -0.89916) (xy -0.0635 -0.889) (xy -0.09144 -0.87376) (xy -0.11684 -0.85344)
						(xy -0.13716 -0.82804) (xy -0.1524 -0.8001) (xy -0.16256 -0.76835) (xy -0.1651 -0.7366) (xy -0.1651 0.13462)
						(xy -0.17272 0.14224) (xy -0.19812 0.1778) (xy -0.2032 0.18796) (xy -0.20701 0.19685) (xy -0.21209 0.20701)
						(xy -0.2159 0.21717) (xy -0.21844 0.22733) (xy -0.22225 0.23876) (xy -0.22352 0.24892) (xy -0.22606 0.25908)
						(xy -0.22733 0.27051) (xy -0.22733 0.28067) (xy -0.2286 0.2921) (xy -0.22733 0.30353) (xy -0.22733 0.31369)
						(xy -0.22606 0.32512) (xy -0.22352 0.33528) (xy -0.22225 0.34544) (xy -0.21844 0.35687) (xy -0.2159 0.36703)
						(xy -0.21209 0.37719) (xy -0.20701 0.38735) (xy -0.2032 0.39624) (xy -0.19812 0.4064) (xy -0.17272 0.44196)
						(xy -0.1651 0.44958) (xy -0.1651 0.7366) (xy -0.16256 0.76835) (xy -0.1524 0.8001) (xy -0.13716 0.82804)
						(xy -0.11684 0.85344) (xy -0.09144 0.87376) (xy -0.0635 0.889) (xy -0.03175 0.89916) (xy 0 0.9017)
						(xy 0.03175 0.89916) (xy 0.0635 0.889) (xy 0.09144 0.87376) (xy 0.11684 0.85344) (xy 0.13716 0.82804)
						(xy 0.1524 0.8001) (xy 0.16256 0.76835) (xy 0.1651 0.7366) (xy 0.1651 0.44958) (xy 0.17272 0.44196)
						(xy 0.19812 0.4064) (xy 0.2032 0.39624) (xy 0.20701 0.38735) (xy 0.21209 0.37719) (xy 0.2159 0.36703)
						(xy 0.21844 0.35687) (xy 0.22225 0.34544) (xy 0.22352 0.33528) (xy 0.22606 0.32512) (xy 0.22733 0.31369)
						(xy 0.22733 0.30353) (xy 0.2286 0.2921) (xy 0.22733 0.28067) (xy 0.22733 0.27051) (xy 0.22606 0.25908)
						(xy 0.22352 0.24892) (xy 0.22225 0.23876) (xy 0.21844 0.22733) (xy 0.2159 0.21717) (xy 0.21209 0.20701)
						(xy 0.20701 0.19685) (xy 0.2032 0.18796) (xy 0.19812 0.1778) (xy 0.17272 0.14224) (xy 0.1651 0.13462)
						(xy 0.1651 -0.7366) (xy 0.16256 -0.76835) (xy 0.1524 -0.8001) (xy 0.13716 -0.82804) (xy 0.11684 -0.85344)
						(xy 0.09144 -0.87376) (xy 0.0635 -0.889) (xy 0.03175 -0.89916)
					)
					(width 0)
					(fill yes)
				)
			)
		)
		(pad "99" smd custom
			(at 0.150114 -4.100068 180)
			(size 0.1143 0.1143)
			(layers "B.Cu" "B.Mask" "B.Paste")
			(net "M_B_MA5")
			(options
				(clearance outline)
				(anchor circle)
			)
			(primitives
				(gr_poly
					(pts
						(xy 0 -0.9017) (xy -0.03175 -0.89916) (xy -0.0635 -0.889) (xy -0.09144 -0.87376) (xy -0.11684 -0.85344)
						(xy -0.13716 -0.82804) (xy -0.1524 -0.8001) (xy -0.16256 -0.76835) (xy -0.1651 -0.7366) (xy -0.1651 -0.19685)
						(xy -0.17272 -0.18923) (xy -0.17907 -0.18034) (xy -0.18669 -0.17145) (xy -0.19177 -0.16256) (xy -0.19812 -0.15367)
						(xy -0.20828 -0.13335) (xy -0.21971 -0.10287) (xy -0.22225 -0.09271) (xy -0.22479 -0.08128) (xy -0.22606 -0.07112)
						(xy -0.2286 -0.05969) (xy -0.2286 -0.01651) (xy -0.22606 -0.00508) (xy -0.22479 0.00508) (xy -0.22225 0.01651)
						(xy -0.21971 0.02667) (xy -0.20828 0.05715) (xy -0.19812 0.07747) (xy -0.19177 0.08636) (xy -0.18669 0.09525)
						(xy -0.17907 0.10414) (xy -0.17272 0.11303) (xy -0.1651 0.12065) (xy -0.1651 0.7366) (xy -0.16256 0.76835)
						(xy -0.1524 0.8001) (xy -0.13716 0.82804) (xy -0.11684 0.85344) (xy -0.09144 0.87376) (xy -0.0635 0.889)
						(xy -0.03175 0.89916) (xy 0 0.9017) (xy 0.03175 0.89916) (xy 0.0635 0.889) (xy 0.09144 0.87376)
						(xy 0.11684 0.85344) (xy 0.13716 0.82804) (xy 0.1524 0.8001) (xy 0.16256 0.76835) (xy 0.1651 0.7366)
						(xy 0.1651 0.11938) (xy 0.17272 0.11176) (xy 0.19812 0.0762) (xy 0.2032 0.06604) (xy 0.20701 0.05715)
						(xy 0.21209 0.04699) (xy 0.2159 0.03683) (xy 0.21844 0.02667) (xy 0.22225 0.01524) (xy 0.22352 0.00508)
						(xy 0.22606 -0.00508) (xy 0.22733 -0.01651) (xy 0.22733 -0.02667) (xy 0.2286 -0.0381) (xy 0.22733 -0.04953)
						(xy 0.22733 -0.05969) (xy 0.22606 -0.07112) (xy 0.22352 -0.08128) (xy 0.22225 -0.09144) (xy 0.21844 -0.10287)
						(xy 0.2159 -0.11303) (xy 0.21209 -0.12319) (xy 0.20701 -0.13335) (xy 0.2032 -0.14224) (xy 0.19812 -0.1524)
						(xy 0.17272 -0.18796) (xy 0.1651 -0.19558) (xy 0.1651 -0.7366) (xy 0.16256 -0.76835) (xy 0.1524 -0.8001)
						(xy 0.13716 -0.82804) (xy 0.11684 -0.85344) (xy 0.09144 -0.87376) (xy 0.0635 -0.889) (xy 0.03175 -0.89916)
					)
					(width 0)
					(fill yes)
				)
			)
		)
		(pad "100" smd custom
			(at 0.450088 4.100068 180)
			(size 0.1143 0.1143)
			(layers "B.Cu" "B.Mask" "B.Paste")
			(net "M_B_MA6")
			(options
				(clearance outline)
				(anchor circle)
			)
			(primitives
				(gr_poly
					(pts
						(xy 0 -0.9017) (xy -0.03175 -0.89916) (xy -0.0635 -0.889) (xy -0.09144 -0.87376) (xy -0.11684 -0.85344)
						(xy -0.13716 -0.82804) (xy -0.1524 -0.8001) (xy -0.16256 -0.76835) (xy -0.1651 -0.7366) (xy -0.1651 -0.11938)
						(xy -0.17272 -0.11176) (xy -0.19812 -0.0762) (xy -0.2032 -0.06604) (xy -0.20701 -0.05715) (xy -0.21209 -0.04699)
						(xy -0.2159 -0.03683) (xy -0.21844 -0.02667) (xy -0.22225 -0.01524) (xy -0.22352 -0.00508) (xy -0.22606 0.00508)
						(xy -0.22733 0.01651) (xy -0.22733 0.02667) (xy -0.2286 0.0381) (xy -0.22733 0.04953) (xy -0.22733 0.05969)
						(xy -0.22606 0.07112) (xy -0.22352 0.08128) (xy -0.22225 0.09144) (xy -0.21844 0.10287) (xy -0.2159 0.11303)
						(xy -0.21209 0.12319) (xy -0.20701 0.13335) (xy -0.2032 0.14224) (xy -0.19812 0.1524) (xy -0.17272 0.18796)
						(xy -0.1651 0.19558) (xy -0.1651 0.7366) (xy -0.16256 0.76835) (xy -0.1524 0.8001) (xy -0.13716 0.82804)
						(xy -0.11684 0.85344) (xy -0.09144 0.87376) (xy -0.0635 0.889) (xy -0.03175 0.89916) (xy 0 0.9017)
						(xy 0.03175 0.89916) (xy 0.0635 0.889) (xy 0.09144 0.87376) (xy 0.11684 0.85344) (xy 0.13716 0.82804)
						(xy 0.1524 0.8001) (xy 0.16256 0.76835) (xy 0.1651 0.7366) (xy 0.1651 0.19685) (xy 0.17272 0.18923)
						(xy 0.17907 0.18034) (xy 0.18669 0.17145) (xy 0.19177 0.16256) (xy 0.19812 0.15367) (xy 0.20828 0.13335)
						(xy 0.21971 0.10287) (xy 0.22225 0.09271) (xy 0.22479 0.08128) (xy 0.22606 0.07112) (xy 0.2286 0.05969)
						(xy 0.2286 0.01651) (xy 0.22606 0.00508) (xy 0.22479 -0.00508) (xy 0.22225 -0.01651) (xy 0.21971 -0.02667)
						(xy 0.20828 -0.05715) (xy 0.19812 -0.07747) (xy 0.19177 -0.08636) (xy 0.18669 -0.09525) (xy 0.17907 -0.10414)
						(xy 0.17272 -0.11303) (xy 0.1651 -0.12065) (xy 0.1651 -0.7366) (xy 0.16256 -0.76835) (xy 0.1524 -0.8001)
						(xy 0.13716 -0.82804) (xy 0.11684 -0.85344) (xy 0.09144 -0.87376) (xy 0.0635 -0.889) (xy 0.03175 -0.89916)
					)
					(width 0)
					(fill yes)
				)
			)
		)
		(pad "101" smd custom
			(at 0.750062 -4.100068 180)
			(size 0.1143 0.1143)
			(layers "B.Cu" "B.Mask" "B.Paste")
			(net "PV_VDDR")
			(options
				(clearance outline)
				(anchor circle)
			)
			(primitives
				(gr_poly
					(pts
						(xy 0 -0.9017) (xy -0.03175 -0.89916) (xy -0.0635 -0.889) (xy -0.09144 -0.87376) (xy -0.11684 -0.85344)
						(xy -0.13716 -0.82804) (xy -0.1524 -0.8001) (xy -0.16256 -0.76835) (xy -0.1651 -0.7366) (xy -0.1651 -0.44958)
						(xy -0.17272 -0.44196) (xy -0.19812 -0.4064) (xy -0.2032 -0.39624) (xy -0.20701 -0.38735) (xy -0.21209 -0.37719)
						(xy -0.2159 -0.36703) (xy -0.21844 -0.35687) (xy -0.22225 -0.34544) (xy -0.22352 -0.33528) (xy -0.22606 -0.32512)
						(xy -0.22733 -0.31369) (xy -0.22733 -0.30353) (xy -0.2286 -0.2921) (xy -0.22733 -0.28067) (xy -0.22733 -0.27051)
						(xy -0.22606 -0.25908) (xy -0.22352 -0.24892) (xy -0.22225 -0.23876) (xy -0.21844 -0.22733) (xy -0.2159 -0.21717)
						(xy -0.21209 -0.20701) (xy -0.20701 -0.19685) (xy -0.2032 -0.18796) (xy -0.19812 -0.1778) (xy -0.17272 -0.14224)
						(xy -0.1651 -0.13462) (xy -0.1651 0.7366) (xy -0.16256 0.76835) (xy -0.1524 0.8001) (xy -0.13716 0.82804)
						(xy -0.11684 0.85344) (xy -0.09144 0.87376) (xy -0.0635 0.889) (xy -0.03175 0.89916) (xy 0 0.9017)
						(xy 0.03175 0.89916) (xy 0.0635 0.889) (xy 0.09144 0.87376) (xy 0.11684 0.85344) (xy 0.13716 0.82804)
						(xy 0.1524 0.8001) (xy 0.16256 0.76835) (xy 0.1651 0.7366) (xy 0.1651 -0.13462) (xy 0.17272 -0.14224)
						(xy 0.19812 -0.1778) (xy 0.2032 -0.18796) (xy 0.20701 -0.19685) (xy 0.21209 -0.20701) (xy 0.2159 -0.21717)
						(xy 0.21844 -0.22733) (xy 0.22225 -0.23876) (xy 0.22352 -0.24892) (xy 0.22606 -0.25908) (xy 0.22733 -0.27051)
						(xy 0.22733 -0.28067) (xy 0.2286 -0.2921) (xy 0.22733 -0.30353) (xy 0.22733 -0.31369) (xy 0.22606 -0.32512)
						(xy 0.22352 -0.33528) (xy 0.22225 -0.34544) (xy 0.21844 -0.35687) (xy 0.2159 -0.36703) (xy 0.21209 -0.37719)
						(xy 0.20701 -0.38735) (xy 0.2032 -0.39624) (xy 0.19812 -0.4064) (xy 0.17272 -0.44196) (xy 0.1651 -0.44958)
						(xy 0.1651 -0.7366) (xy 0.16256 -0.76835) (xy 0.1524 -0.8001) (xy 0.13716 -0.82804) (xy 0.11684 -0.85344)
						(xy 0.09144 -0.87376) (xy 0.0635 -0.889) (xy 0.03175 -0.89916)
					)
					(width 0)
					(fill yes)
				)
			)
		)
		(pad "102" smd custom
			(at 1.050036 4.100068 180)
			(size 0.1143 0.1143)
			(layers "B.Cu" "B.Mask" "B.Paste")
			(net "PV_VDDR")
			(options
				(clearance outline)
				(anchor circle)
			)
			(primitives
				(gr_poly
					(pts
						(xy 0 -0.9017) (xy -0.03175 -0.89916) (xy -0.0635 -0.889) (xy -0.09144 -0.87376) (xy -0.11684 -0.85344)
						(xy -0.13716 -0.82804) (xy -0.1524 -0.8001) (xy -0.16256 -0.76835) (xy -0.1651 -0.7366) (xy -0.1651 0.13462)
						(xy -0.17272 0.14224) (xy -0.19812 0.1778) (xy -0.2032 0.18796) (xy -0.20701 0.19685) (xy -0.21209 0.20701)
						(xy -0.2159 0.21717) (xy -0.21844 0.22733) (xy -0.22225 0.23876) (xy -0.22352 0.24892) (xy -0.22606 0.25908)
						(xy -0.22733 0.27051) (xy -0.22733 0.28067) (xy -0.2286 0.2921) (xy -0.22733 0.30353) (xy -0.22733 0.31369)
						(xy -0.22606 0.32512) (xy -0.22352 0.33528) (xy -0.22225 0.34544) (xy -0.21844 0.35687) (xy -0.2159 0.36703)
						(xy -0.21209 0.37719) (xy -0.20701 0.38735) (xy -0.2032 0.39624) (xy -0.19812 0.4064) (xy -0.17272 0.44196)
						(xy -0.1651 0.44958) (xy -0.1651 0.7366) (xy -0.16256 0.76835) (xy -0.1524 0.8001) (xy -0.13716 0.82804)
						(xy -0.11684 0.85344) (xy -0.09144 0.87376) (xy -0.0635 0.889) (xy -0.03175 0.89916) (xy 0 0.9017)
						(xy 0.03175 0.89916) (xy 0.0635 0.889) (xy 0.09144 0.87376) (xy 0.11684 0.85344) (xy 0.13716 0.82804)
						(xy 0.1524 0.8001) (xy 0.16256 0.76835) (xy 0.1651 0.7366) (xy 0.1651 0.44958) (xy 0.17272 0.44196)
						(xy 0.19812 0.4064) (xy 0.2032 0.39624) (xy 0.20701 0.38735) (xy 0.21209 0.37719) (xy 0.2159 0.36703)
						(xy 0.21844 0.35687) (xy 0.22225 0.34544) (xy 0.22352 0.33528) (xy 0.22606 0.32512) (xy 0.22733 0.31369)
						(xy 0.22733 0.30353) (xy 0.2286 0.2921) (xy 0.22733 0.28067) (xy 0.22733 0.27051) (xy 0.22606 0.25908)
						(xy 0.22352 0.24892) (xy 0.22225 0.23876) (xy 0.21844 0.22733) (xy 0.2159 0.21717) (xy 0.21209 0.20701)
						(xy 0.20701 0.19685) (xy 0.2032 0.18796) (xy 0.19812 0.1778) (xy 0.17272 0.14224) (xy 0.1651 0.13462)
						(xy 0.1651 -0.7366) (xy 0.16256 -0.76835) (xy 0.1524 -0.8001) (xy 0.13716 -0.82804) (xy 0.11684 -0.85344)
						(xy 0.09144 -0.87376) (xy 0.0635 -0.889) (xy 0.03175 -0.89916)
					)
					(width 0)
					(fill yes)
				)
			)
		)
		(pad "103" smd custom
			(at 1.35001 -4.100068 180)
			(size 0.1143 0.1143)
			(layers "B.Cu" "B.Mask" "B.Paste")
			(net "M_B_MA3")
			(options
				(clearance outline)
				(anchor circle)
			)
			(primitives
				(gr_poly
					(pts
						(xy 0 -0.9017) (xy -0.03175 -0.89916) (xy -0.0635 -0.889) (xy -0.09144 -0.87376) (xy -0.11684 -0.85344)
						(xy -0.13716 -0.82804) (xy -0.1524 -0.8001) (xy -0.16256 -0.76835) (xy -0.1651 -0.7366) (xy -0.1651 -0.19685)
						(xy -0.17272 -0.18923) (xy -0.17907 -0.18034) (xy -0.18669 -0.17145) (xy -0.19177 -0.16256) (xy -0.19812 -0.15367)
						(xy -0.20828 -0.13335) (xy -0.21971 -0.10287) (xy -0.22225 -0.09271) (xy -0.22479 -0.08128) (xy -0.22606 -0.07112)
						(xy -0.2286 -0.05969) (xy -0.2286 -0.01651) (xy -0.22606 -0.00508) (xy -0.22479 0.00508) (xy -0.22225 0.01651)
						(xy -0.21971 0.02667) (xy -0.20828 0.05715) (xy -0.19812 0.07747) (xy -0.19177 0.08636) (xy -0.18669 0.09525)
						(xy -0.17907 0.10414) (xy -0.17272 0.11303) (xy -0.1651 0.12065) (xy -0.1651 0.7366) (xy -0.16256 0.76835)
						(xy -0.1524 0.8001) (xy -0.13716 0.82804) (xy -0.11684 0.85344) (xy -0.09144 0.87376) (xy -0.0635 0.889)
						(xy -0.03175 0.89916) (xy 0 0.9017) (xy 0.03175 0.89916) (xy 0.0635 0.889) (xy 0.09144 0.87376)
						(xy 0.11684 0.85344) (xy 0.13716 0.82804) (xy 0.1524 0.8001) (xy 0.16256 0.76835) (xy 0.1651 0.7366)
						(xy 0.1651 0.11938) (xy 0.17272 0.11176) (xy 0.19812 0.0762) (xy 0.2032 0.06604) (xy 0.20701 0.05715)
						(xy 0.21209 0.04699) (xy 0.2159 0.03683) (xy 0.21844 0.02667) (xy 0.22225 0.01524) (xy 0.22352 0.00508)
						(xy 0.22606 -0.00508) (xy 0.22733 -0.01651) (xy 0.22733 -0.02667) (xy 0.2286 -0.0381) (xy 0.22733 -0.04953)
						(xy 0.22733 -0.05969) (xy 0.22606 -0.07112) (xy 0.22352 -0.08128) (xy 0.22225 -0.09144) (xy 0.21844 -0.10287)
						(xy 0.2159 -0.11303) (xy 0.21209 -0.12319) (xy 0.20701 -0.13335) (xy 0.2032 -0.14224) (xy 0.19812 -0.1524)
						(xy 0.17272 -0.18796) (xy 0.1651 -0.19558) (xy 0.1651 -0.7366) (xy 0.16256 -0.76835) (xy 0.1524 -0.8001)
						(xy 0.13716 -0.82804) (xy 0.11684 -0.85344) (xy 0.09144 -0.87376) (xy 0.0635 -0.889) (xy 0.03175 -0.89916)
					)
					(width 0)
					(fill yes)
				)
			)
		)
		(pad "104" smd custom
			(at 1.649984 4.100068 180)
			(size 0.1143 0.1143)
			(layers "B.Cu" "B.Mask" "B.Paste")
			(net "M_B_MA4")
			(options
				(clearance outline)
				(anchor circle)
			)
			(primitives
				(gr_poly
					(pts
						(xy 0 -0.9017) (xy -0.03175 -0.89916) (xy -0.0635 -0.889) (xy -0.09144 -0.87376) (xy -0.11684 -0.85344)
						(xy -0.13716 -0.82804) (xy -0.1524 -0.8001) (xy -0.16256 -0.76835) (xy -0.1651 -0.7366) (xy -0.1651 -0.11938)
						(xy -0.17272 -0.11176) (xy -0.19812 -0.0762) (xy -0.2032 -0.06604) (xy -0.20701 -0.05715) (xy -0.21209 -0.04699)
						(xy -0.2159 -0.03683) (xy -0.21844 -0.02667) (xy -0.22225 -0.01524) (xy -0.22352 -0.00508) (xy -0.22606 0.00508)
						(xy -0.22733 0.01651) (xy -0.22733 0.02667) (xy -0.2286 0.0381) (xy -0.22733 0.04953) (xy -0.22733 0.05969)
						(xy -0.22606 0.07112) (xy -0.22352 0.08128) (xy -0.22225 0.09144) (xy -0.21844 0.10287) (xy -0.2159 0.11303)
						(xy -0.21209 0.12319) (xy -0.20701 0.13335) (xy -0.2032 0.14224) (xy -0.19812 0.1524) (xy -0.17272 0.18796)
						(xy -0.1651 0.19558) (xy -0.1651 0.7366) (xy -0.16256 0.76835) (xy -0.1524 0.8001) (xy -0.13716 0.82804)
						(xy -0.11684 0.85344) (xy -0.09144 0.87376) (xy -0.0635 0.889) (xy -0.03175 0.89916) (xy 0 0.9017)
						(xy 0.03175 0.89916) (xy 0.0635 0.889) (xy 0.09144 0.87376) (xy 0.11684 0.85344) (xy 0.13716 0.82804)
						(xy 0.1524 0.8001) (xy 0.16256 0.76835) (xy 0.1651 0.7366) (xy 0.1651 0.19685) (xy 0.17272 0.18923)
						(xy 0.17907 0.18034) (xy 0.18669 0.17145) (xy 0.19177 0.16256) (xy 0.19812 0.15367) (xy 0.20828 0.13335)
						(xy 0.21971 0.10287) (xy 0.22225 0.09271) (xy 0.22479 0.08128) (xy 0.22606 0.07112) (xy 0.2286 0.05969)
						(xy 0.2286 0.01651) (xy 0.22606 0.00508) (xy 0.22479 -0.00508) (xy 0.22225 -0.01651) (xy 0.21971 -0.02667)
						(xy 0.20828 -0.05715) (xy 0.19812 -0.07747) (xy 0.19177 -0.08636) (xy 0.18669 -0.09525) (xy 0.17907 -0.10414)
						(xy 0.17272 -0.11303) (xy 0.1651 -0.12065) (xy 0.1651 -0.7366) (xy 0.16256 -0.76835) (xy 0.1524 -0.8001)
						(xy 0.13716 -0.82804) (xy 0.11684 -0.85344) (xy 0.09144 -0.87376) (xy 0.0635 -0.889) (xy 0.03175 -0.89916)
					)
					(width 0)
					(fill yes)
				)
			)
		)
		(pad "105" smd custom
			(at 1.949958 -4.100068 180)
			(size 0.1143 0.1143)
			(layers "B.Cu" "B.Mask" "B.Paste")
			(net "M_B_MA1")
			(options
				(clearance outline)
				(anchor circle)
			)
			(primitives
				(gr_poly
					(pts
						(xy 0 -0.9017) (xy -0.03175 -0.89916) (xy -0.0635 -0.889) (xy -0.09144 -0.87376) (xy -0.11684 -0.85344)
						(xy -0.13716 -0.82804) (xy -0.1524 -0.8001) (xy -0.16256 -0.76835) (xy -0.1651 -0.7366) (xy -0.1651 -0.44958)
						(xy -0.17272 -0.44196) (xy -0.19812 -0.4064) (xy -0.2032 -0.39624) (xy -0.20701 -0.38735) (xy -0.21209 -0.37719)
						(xy -0.2159 -0.36703) (xy -0.21844 -0.35687) (xy -0.22225 -0.34544) (xy -0.22352 -0.33528) (xy -0.22606 -0.32512)
						(xy -0.22733 -0.31369) (xy -0.22733 -0.30353) (xy -0.2286 -0.2921) (xy -0.22733 -0.28067) (xy -0.22733 -0.27051)
						(xy -0.22606 -0.25908) (xy -0.22352 -0.24892) (xy -0.22225 -0.23876) (xy -0.21844 -0.22733) (xy -0.2159 -0.21717)
						(xy -0.21209 -0.20701) (xy -0.20701 -0.19685) (xy -0.2032 -0.18796) (xy -0.19812 -0.1778) (xy -0.17272 -0.14224)
						(xy -0.1651 -0.13462) (xy -0.1651 0.7366) (xy -0.16256 0.76835) (xy -0.1524 0.8001) (xy -0.13716 0.82804)
						(xy -0.11684 0.85344) (xy -0.09144 0.87376) (xy -0.0635 0.889) (xy -0.03175 0.89916) (xy 0 0.9017)
						(xy 0.03175 0.89916) (xy 0.0635 0.889) (xy 0.09144 0.87376) (xy 0.11684 0.85344) (xy 0.13716 0.82804)
						(xy 0.1524 0.8001) (xy 0.16256 0.76835) (xy 0.1651 0.7366) (xy 0.1651 -0.13462) (xy 0.17272 -0.14224)
						(xy 0.19812 -0.1778) (xy 0.2032 -0.18796) (xy 0.20701 -0.19685) (xy 0.21209 -0.20701) (xy 0.2159 -0.21717)
						(xy 0.21844 -0.22733) (xy 0.22225 -0.23876) (xy 0.22352 -0.24892) (xy 0.22606 -0.25908) (xy 0.22733 -0.27051)
						(xy 0.22733 -0.28067) (xy 0.2286 -0.2921) (xy 0.22733 -0.30353) (xy 0.22733 -0.31369) (xy 0.22606 -0.32512)
						(xy 0.22352 -0.33528) (xy 0.22225 -0.34544) (xy 0.21844 -0.35687) (xy 0.2159 -0.36703) (xy 0.21209 -0.37719)
						(xy 0.20701 -0.38735) (xy 0.2032 -0.39624) (xy 0.19812 -0.4064) (xy 0.17272 -0.44196) (xy 0.1651 -0.44958)
						(xy 0.1651 -0.7366) (xy 0.16256 -0.76835) (xy 0.1524 -0.8001) (xy 0.13716 -0.82804) (xy 0.11684 -0.85344)
						(xy 0.09144 -0.87376) (xy 0.0635 -0.889) (xy 0.03175 -0.89916)
					)
					(width 0)
					(fill yes)
				)
			)
		)
		(pad "106" smd custom
			(at 2.249932 4.100068 180)
			(size 0.1143 0.1143)
			(layers "B.Cu" "B.Mask" "B.Paste")
			(net "M_B_MA2")
			(options
				(clearance outline)
				(anchor circle)
			)
			(primitives
				(gr_poly
					(pts
						(xy 0 -0.9017) (xy -0.03175 -0.89916) (xy -0.0635 -0.889) (xy -0.09144 -0.87376) (xy -0.11684 -0.85344)
						(xy -0.13716 -0.82804) (xy -0.1524 -0.8001) (xy -0.16256 -0.76835) (xy -0.1651 -0.7366) (xy -0.1651 0.13462)
						(xy -0.17272 0.14224) (xy -0.19812 0.1778) (xy -0.2032 0.18796) (xy -0.20701 0.19685) (xy -0.21209 0.20701)
						(xy -0.2159 0.21717) (xy -0.21844 0.22733) (xy -0.22225 0.23876) (xy -0.22352 0.24892) (xy -0.22606 0.25908)
						(xy -0.22733 0.27051) (xy -0.22733 0.28067) (xy -0.2286 0.2921) (xy -0.22733 0.30353) (xy -0.22733 0.31369)
						(xy -0.22606 0.32512) (xy -0.22352 0.33528) (xy -0.22225 0.34544) (xy -0.21844 0.35687) (xy -0.2159 0.36703)
						(xy -0.21209 0.37719) (xy -0.20701 0.38735) (xy -0.2032 0.39624) (xy -0.19812 0.4064) (xy -0.17272 0.44196)
						(xy -0.1651 0.44958) (xy -0.1651 0.7366) (xy -0.16256 0.76835) (xy -0.1524 0.8001) (xy -0.13716 0.82804)
						(xy -0.11684 0.85344) (xy -0.09144 0.87376) (xy -0.0635 0.889) (xy -0.03175 0.89916) (xy 0 0.9017)
						(xy 0.03175 0.89916) (xy 0.0635 0.889) (xy 0.09144 0.87376) (xy 0.11684 0.85344) (xy 0.13716 0.82804)
						(xy 0.1524 0.8001) (xy 0.16256 0.76835) (xy 0.1651 0.7366) (xy 0.1651 0.44958) (xy 0.17272 0.44196)
						(xy 0.19812 0.4064) (xy 0.2032 0.39624) (xy 0.20701 0.38735) (xy 0.21209 0.37719) (xy 0.2159 0.36703)
						(xy 0.21844 0.35687) (xy 0.22225 0.34544) (xy 0.22352 0.33528) (xy 0.22606 0.32512) (xy 0.22733 0.31369)
						(xy 0.22733 0.30353) (xy 0.2286 0.2921) (xy 0.22733 0.28067) (xy 0.22733 0.27051) (xy 0.22606 0.25908)
						(xy 0.22352 0.24892) (xy 0.22225 0.23876) (xy 0.21844 0.22733) (xy 0.2159 0.21717) (xy 0.21209 0.20701)
						(xy 0.20701 0.19685) (xy 0.2032 0.18796) (xy 0.19812 0.1778) (xy 0.17272 0.14224) (xy 0.1651 0.13462)
						(xy 0.1651 -0.7366) (xy 0.16256 -0.76835) (xy 0.1524 -0.8001) (xy 0.13716 -0.82804) (xy 0.11684 -0.85344)
						(xy 0.09144 -0.87376) (xy 0.0635 -0.889) (xy 0.03175 -0.89916)
					)
					(width 0)
					(fill yes)
				)
			)
		)
		(pad "107" smd custom
			(at 2.549906 -4.100068 180)
			(size 0.1143 0.1143)
			(layers "B.Cu" "B.Mask" "B.Paste")
			(net "M_B_MA0")
			(options
				(clearance outline)
				(anchor circle)
			)
			(primitives
				(gr_poly
					(pts
						(xy 0 -0.9017) (xy -0.03175 -0.89916) (xy -0.0635 -0.889) (xy -0.09144 -0.87376) (xy -0.11684 -0.85344)
						(xy -0.13716 -0.82804) (xy -0.1524 -0.8001) (xy -0.16256 -0.76835) (xy -0.1651 -0.7366) (xy -0.1651 -0.19685)
						(xy -0.17272 -0.18923) (xy -0.17907 -0.18034) (xy -0.18669 -0.17145) (xy -0.19177 -0.16256) (xy -0.19812 -0.15367)
						(xy -0.20828 -0.13335) (xy -0.21971 -0.10287) (xy -0.22225 -0.09271) (xy -0.22479 -0.08128) (xy -0.22606 -0.07112)
						(xy -0.2286 -0.05969) (xy -0.2286 -0.01651) (xy -0.22606 -0.00508) (xy -0.22479 0.00508) (xy -0.22225 0.01651)
						(xy -0.21971 0.02667) (xy -0.20828 0.05715) (xy -0.19812 0.07747) (xy -0.19177 0.08636) (xy -0.18669 0.09525)
						(xy -0.17907 0.10414) (xy -0.17272 0.11303) (xy -0.1651 0.12065) (xy -0.1651 0.7366) (xy -0.16256 0.76835)
						(xy -0.1524 0.8001) (xy -0.13716 0.82804) (xy -0.11684 0.85344) (xy -0.09144 0.87376) (xy -0.0635 0.889)
						(xy -0.03175 0.89916) (xy 0 0.9017) (xy 0.03175 0.89916) (xy 0.0635 0.889) (xy 0.09144 0.87376)
						(xy 0.11684 0.85344) (xy 0.13716 0.82804) (xy 0.1524 0.8001) (xy 0.16256 0.76835) (xy 0.1651 0.7366)
						(xy 0.1651 0.11938) (xy 0.17272 0.11176) (xy 0.19812 0.0762) (xy 0.2032 0.06604) (xy 0.20701 0.05715)
						(xy 0.21209 0.04699) (xy 0.2159 0.03683) (xy 0.21844 0.02667) (xy 0.22225 0.01524) (xy 0.22352 0.00508)
						(xy 0.22606 -0.00508) (xy 0.22733 -0.01651) (xy 0.22733 -0.02667) (xy 0.2286 -0.0381) (xy 0.22733 -0.04953)
						(xy 0.22733 -0.05969) (xy 0.22606 -0.07112) (xy 0.22352 -0.08128) (xy 0.22225 -0.09144) (xy 0.21844 -0.10287)
						(xy 0.2159 -0.11303) (xy 0.21209 -0.12319) (xy 0.20701 -0.13335) (xy 0.2032 -0.14224) (xy 0.19812 -0.1524)
						(xy 0.17272 -0.18796) (xy 0.1651 -0.19558) (xy 0.1651 -0.7366) (xy 0.16256 -0.76835) (xy 0.1524 -0.8001)
						(xy 0.13716 -0.82804) (xy 0.11684 -0.85344) (xy 0.09144 -0.87376) (xy 0.0635 -0.889) (xy 0.03175 -0.89916)
					)
					(width 0)
					(fill yes)
				)
			)
		)
		(pad "108" smd custom
			(at 2.84988 4.100068 180)
			(size 0.1143 0.1143)
			(layers "B.Cu" "B.Mask" "B.Paste")
			(net "M_B_BS1")
			(options
				(clearance outline)
				(anchor circle)
			)
			(primitives
				(gr_poly
					(pts
						(xy 0 -0.9017) (xy -0.03175 -0.89916) (xy -0.0635 -0.889) (xy -0.09144 -0.87376) (xy -0.11684 -0.85344)
						(xy -0.13716 -0.82804) (xy -0.1524 -0.8001) (xy -0.16256 -0.76835) (xy -0.1651 -0.7366) (xy -0.1651 -0.11938)
						(xy -0.17272 -0.11176) (xy -0.19812 -0.0762) (xy -0.2032 -0.06604) (xy -0.20701 -0.05715) (xy -0.21209 -0.04699)
						(xy -0.2159 -0.03683) (xy -0.21844 -0.02667) (xy -0.22225 -0.01524) (xy -0.22352 -0.00508) (xy -0.22606 0.00508)
						(xy -0.22733 0.01651) (xy -0.22733 0.02667) (xy -0.2286 0.0381) (xy -0.22733 0.04953) (xy -0.22733 0.05969)
						(xy -0.22606 0.07112) (xy -0.22352 0.08128) (xy -0.22225 0.09144) (xy -0.21844 0.10287) (xy -0.2159 0.11303)
						(xy -0.21209 0.12319) (xy -0.20701 0.13335) (xy -0.2032 0.14224) (xy -0.19812 0.1524) (xy -0.17272 0.18796)
						(xy -0.1651 0.19558) (xy -0.1651 0.7366) (xy -0.16256 0.76835) (xy -0.1524 0.8001) (xy -0.13716 0.82804)
						(xy -0.11684 0.85344) (xy -0.09144 0.87376) (xy -0.0635 0.889) (xy -0.03175 0.89916) (xy 0 0.9017)
						(xy 0.03175 0.89916) (xy 0.0635 0.889) (xy 0.09144 0.87376) (xy 0.11684 0.85344) (xy 0.13716 0.82804)
						(xy 0.1524 0.8001) (xy 0.16256 0.76835) (xy 0.1651 0.7366) (xy 0.1651 0.19685) (xy 0.17272 0.18923)
						(xy 0.17907 0.18034) (xy 0.18669 0.17145) (xy 0.19177 0.16256) (xy 0.19812 0.15367) (xy 0.20828 0.13335)
						(xy 0.21971 0.10287) (xy 0.22225 0.09271) (xy 0.22479 0.08128) (xy 0.22606 0.07112) (xy 0.2286 0.05969)
						(xy 0.2286 0.01651) (xy 0.22606 0.00508) (xy 0.22479 -0.00508) (xy 0.22225 -0.01651) (xy 0.21971 -0.02667)
						(xy 0.20828 -0.05715) (xy 0.19812 -0.07747) (xy 0.19177 -0.08636) (xy 0.18669 -0.09525) (xy 0.17907 -0.10414)
						(xy 0.17272 -0.11303) (xy 0.1651 -0.12065) (xy 0.1651 -0.7366) (xy 0.16256 -0.76835) (xy 0.1524 -0.8001)
						(xy 0.13716 -0.82804) (xy 0.11684 -0.85344) (xy 0.09144 -0.87376) (xy 0.0635 -0.889) (xy 0.03175 -0.89916)
					)
					(width 0)
					(fill yes)
				)
			)
		)
		(pad "109" smd custom
			(at 3.150108 -4.100068 180)
			(size 0.1143 0.1143)
			(layers "B.Cu" "B.Mask" "B.Paste")
			(net "PV_VDDR")
			(options
				(clearance outline)
				(anchor circle)
			)
			(primitives
				(gr_poly
					(pts
						(xy 0 -0.9017) (xy -0.03175 -0.89916) (xy -0.0635 -0.889) (xy -0.09144 -0.87376) (xy -0.11684 -0.85344)
						(xy -0.13716 -0.82804) (xy -0.1524 -0.8001) (xy -0.16256 -0.76835) (xy -0.1651 -0.7366) (xy -0.1651 -0.44958)
						(xy -0.17272 -0.44196) (xy -0.19812 -0.4064) (xy -0.2032 -0.39624) (xy -0.20701 -0.38735) (xy -0.21209 -0.37719)
						(xy -0.2159 -0.36703) (xy -0.21844 -0.35687) (xy -0.22225 -0.34544) (xy -0.22352 -0.33528) (xy -0.22606 -0.32512)
						(xy -0.22733 -0.31369) (xy -0.22733 -0.30353) (xy -0.2286 -0.2921) (xy -0.22733 -0.28067) (xy -0.22733 -0.27051)
						(xy -0.22606 -0.25908) (xy -0.22352 -0.24892) (xy -0.22225 -0.23876) (xy -0.21844 -0.22733) (xy -0.2159 -0.21717)
						(xy -0.21209 -0.20701) (xy -0.20701 -0.19685) (xy -0.2032 -0.18796) (xy -0.19812 -0.1778) (xy -0.17272 -0.14224)
						(xy -0.1651 -0.13462) (xy -0.1651 0.7366) (xy -0.16256 0.76835) (xy -0.1524 0.8001) (xy -0.13716 0.82804)
						(xy -0.11684 0.85344) (xy -0.09144 0.87376) (xy -0.0635 0.889) (xy -0.03175 0.89916) (xy 0 0.9017)
						(xy 0.03175 0.89916) (xy 0.0635 0.889) (xy 0.09144 0.87376) (xy 0.11684 0.85344) (xy 0.13716 0.82804)
						(xy 0.1524 0.8001) (xy 0.16256 0.76835) (xy 0.1651 0.7366) (xy 0.1651 -0.13462) (xy 0.17272 -0.14224)
						(xy 0.19812 -0.1778) (xy 0.2032 -0.18796) (xy 0.20701 -0.19685) (xy 0.21209 -0.20701) (xy 0.2159 -0.21717)
						(xy 0.21844 -0.22733) (xy 0.22225 -0.23876) (xy 0.22352 -0.24892) (xy 0.22606 -0.25908) (xy 0.22733 -0.27051)
						(xy 0.22733 -0.28067) (xy 0.2286 -0.2921) (xy 0.22733 -0.30353) (xy 0.22733 -0.31369) (xy 0.22606 -0.32512)
						(xy 0.22352 -0.33528) (xy 0.22225 -0.34544) (xy 0.21844 -0.35687) (xy 0.2159 -0.36703) (xy 0.21209 -0.37719)
						(xy 0.20701 -0.38735) (xy 0.2032 -0.39624) (xy 0.19812 -0.4064) (xy 0.17272 -0.44196) (xy 0.1651 -0.44958)
						(xy 0.1651 -0.7366) (xy 0.16256 -0.76835) (xy 0.1524 -0.8001) (xy 0.13716 -0.82804) (xy 0.11684 -0.85344)
						(xy 0.09144 -0.87376) (xy 0.0635 -0.889) (xy 0.03175 -0.89916)
					)
					(width 0)
					(fill yes)
				)
			)
		)
		(pad "110" smd custom
			(at 3.450082 4.100068 180)
			(size 0.1143 0.1143)
			(layers "B.Cu" "B.Mask" "B.Paste")
			(net "PV_VDDR")
			(options
				(clearance outline)
				(anchor circle)
			)
			(primitives
				(gr_poly
					(pts
						(xy 0 -0.9017) (xy -0.03175 -0.89916) (xy -0.0635 -0.889) (xy -0.09144 -0.87376) (xy -0.11684 -0.85344)
						(xy -0.13716 -0.82804) (xy -0.1524 -0.8001) (xy -0.16256 -0.76835) (xy -0.1651 -0.7366) (xy -0.1651 0.13462)
						(xy -0.17272 0.14224) (xy -0.19812 0.1778) (xy -0.2032 0.18796) (xy -0.20701 0.19685) (xy -0.21209 0.20701)
						(xy -0.2159 0.21717) (xy -0.21844 0.22733) (xy -0.22225 0.23876) (xy -0.22352 0.24892) (xy -0.22606 0.25908)
						(xy -0.22733 0.27051) (xy -0.22733 0.28067) (xy -0.2286 0.2921) (xy -0.22733 0.30353) (xy -0.22733 0.31369)
						(xy -0.22606 0.32512) (xy -0.22352 0.33528) (xy -0.22225 0.34544) (xy -0.21844 0.35687) (xy -0.2159 0.36703)
						(xy -0.21209 0.37719) (xy -0.20701 0.38735) (xy -0.2032 0.39624) (xy -0.19812 0.4064) (xy -0.17272 0.44196)
						(xy -0.1651 0.44958) (xy -0.1651 0.7366) (xy -0.16256 0.76835) (xy -0.1524 0.8001) (xy -0.13716 0.82804)
						(xy -0.11684 0.85344) (xy -0.09144 0.87376) (xy -0.0635 0.889) (xy -0.03175 0.89916) (xy 0 0.9017)
						(xy 0.03175 0.89916) (xy 0.0635 0.889) (xy 0.09144 0.87376) (xy 0.11684 0.85344) (xy 0.13716 0.82804)
						(xy 0.1524 0.8001) (xy 0.16256 0.76835) (xy 0.1651 0.7366) (xy 0.1651 0.44958) (xy 0.17272 0.44196)
						(xy 0.19812 0.4064) (xy 0.2032 0.39624) (xy 0.20701 0.38735) (xy 0.21209 0.37719) (xy 0.2159 0.36703)
						(xy 0.21844 0.35687) (xy 0.22225 0.34544) (xy 0.22352 0.33528) (xy 0.22606 0.32512) (xy 0.22733 0.31369)
						(xy 0.22733 0.30353) (xy 0.2286 0.2921) (xy 0.22733 0.28067) (xy 0.22733 0.27051) (xy 0.22606 0.25908)
						(xy 0.22352 0.24892) (xy 0.22225 0.23876) (xy 0.21844 0.22733) (xy 0.2159 0.21717) (xy 0.21209 0.20701)
						(xy 0.20701 0.19685) (xy 0.2032 0.18796) (xy 0.19812 0.1778) (xy 0.17272 0.14224) (xy 0.1651 0.13462)
						(xy 0.1651 -0.7366) (xy 0.16256 -0.76835) (xy 0.1524 -0.8001) (xy 0.13716 -0.82804) (xy 0.11684 -0.85344)
						(xy 0.09144 -0.87376) (xy 0.0635 -0.889) (xy 0.03175 -0.89916)
					)
					(width 0)
					(fill yes)
				)
			)
		)
		(pad "111" smd custom
			(at 3.750056 -4.100068 180)
			(size 0.1143 0.1143)
			(layers "B.Cu" "B.Mask" "B.Paste")
			(net "M_B_CK_DP0")
			(options
				(clearance outline)
				(anchor circle)
			)
			(primitives
				(gr_poly
					(pts
						(xy 0 -0.9017) (xy -0.03175 -0.89916) (xy -0.0635 -0.889) (xy -0.09144 -0.87376) (xy -0.11684 -0.85344)
						(xy -0.13716 -0.82804) (xy -0.1524 -0.8001) (xy -0.16256 -0.76835) (xy -0.1651 -0.7366) (xy -0.1651 -0.19685)
						(xy -0.17272 -0.18923) (xy -0.17907 -0.18034) (xy -0.18669 -0.17145) (xy -0.19177 -0.16256) (xy -0.19812 -0.15367)
						(xy -0.20828 -0.13335) (xy -0.21971 -0.10287) (xy -0.22225 -0.09271) (xy -0.22479 -0.08128) (xy -0.22606 -0.07112)
						(xy -0.2286 -0.05969) (xy -0.2286 -0.01651) (xy -0.22606 -0.00508) (xy -0.22479 0.00508) (xy -0.22225 0.01651)
						(xy -0.21971 0.02667) (xy -0.20828 0.05715) (xy -0.19812 0.07747) (xy -0.19177 0.08636) (xy -0.18669 0.09525)
						(xy -0.17907 0.10414) (xy -0.17272 0.11303) (xy -0.1651 0.12065) (xy -0.1651 0.7366) (xy -0.16256 0.76835)
						(xy -0.1524 0.8001) (xy -0.13716 0.82804) (xy -0.11684 0.85344) (xy -0.09144 0.87376) (xy -0.0635 0.889)
						(xy -0.03175 0.89916) (xy 0 0.9017) (xy 0.03175 0.89916) (xy 0.0635 0.889) (xy 0.09144 0.87376)
						(xy 0.11684 0.85344) (xy 0.13716 0.82804) (xy 0.1524 0.8001) (xy 0.16256 0.76835) (xy 0.1651 0.7366)
						(xy 0.1651 0.11938) (xy 0.17272 0.11176) (xy 0.19812 0.0762) (xy 0.2032 0.06604) (xy 0.20701 0.05715)
						(xy 0.21209 0.04699) (xy 0.2159 0.03683) (xy 0.21844 0.02667) (xy 0.22225 0.01524) (xy 0.22352 0.00508)
						(xy 0.22606 -0.00508) (xy 0.22733 -0.01651) (xy 0.22733 -0.02667) (xy 0.2286 -0.0381) (xy 0.22733 -0.04953)
						(xy 0.22733 -0.05969) (xy 0.22606 -0.07112) (xy 0.22352 -0.08128) (xy 0.22225 -0.09144) (xy 0.21844 -0.10287)
						(xy 0.2159 -0.11303) (xy 0.21209 -0.12319) (xy 0.20701 -0.13335) (xy 0.2032 -0.14224) (xy 0.19812 -0.1524)
						(xy 0.17272 -0.18796) (xy 0.1651 -0.19558) (xy 0.1651 -0.7366) (xy 0.16256 -0.76835) (xy 0.1524 -0.8001)
						(xy 0.13716 -0.82804) (xy 0.11684 -0.85344) (xy 0.09144 -0.87376) (xy 0.0635 -0.889) (xy 0.03175 -0.89916)
					)
					(width 0)
					(fill yes)
				)
			)
		)
		(pad "112" smd custom
			(at 4.05003 4.100068 180)
			(size 0.1143 0.1143)
			(layers "B.Cu" "B.Mask" "B.Paste")
			(net "M_B_CK_DP1")
			(options
				(clearance outline)
				(anchor circle)
			)
			(primitives
				(gr_poly
					(pts
						(xy 0 -0.9017) (xy -0.03175 -0.89916) (xy -0.0635 -0.889) (xy -0.09144 -0.87376) (xy -0.11684 -0.85344)
						(xy -0.13716 -0.82804) (xy -0.1524 -0.8001) (xy -0.16256 -0.76835) (xy -0.1651 -0.7366) (xy -0.1651 -0.11938)
						(xy -0.17272 -0.11176) (xy -0.19812 -0.0762) (xy -0.2032 -0.06604) (xy -0.20701 -0.05715) (xy -0.21209 -0.04699)
						(xy -0.2159 -0.03683) (xy -0.21844 -0.02667) (xy -0.22225 -0.01524) (xy -0.22352 -0.00508) (xy -0.22606 0.00508)
						(xy -0.22733 0.01651) (xy -0.22733 0.02667) (xy -0.2286 0.0381) (xy -0.22733 0.04953) (xy -0.22733 0.05969)
						(xy -0.22606 0.07112) (xy -0.22352 0.08128) (xy -0.22225 0.09144) (xy -0.21844 0.10287) (xy -0.2159 0.11303)
						(xy -0.21209 0.12319) (xy -0.20701 0.13335) (xy -0.2032 0.14224) (xy -0.19812 0.1524) (xy -0.17272 0.18796)
						(xy -0.1651 0.19558) (xy -0.1651 0.7366) (xy -0.16256 0.76835) (xy -0.1524 0.8001) (xy -0.13716 0.82804)
						(xy -0.11684 0.85344) (xy -0.09144 0.87376) (xy -0.0635 0.889) (xy -0.03175 0.89916) (xy 0 0.9017)
						(xy 0.03175 0.89916) (xy 0.0635 0.889) (xy 0.09144 0.87376) (xy 0.11684 0.85344) (xy 0.13716 0.82804)
						(xy 0.1524 0.8001) (xy 0.16256 0.76835) (xy 0.1651 0.7366) (xy 0.1651 0.19685) (xy 0.17272 0.18923)
						(xy 0.17907 0.18034) (xy 0.18669 0.17145) (xy 0.19177 0.16256) (xy 0.19812 0.15367) (xy 0.20828 0.13335)
						(xy 0.21971 0.10287) (xy 0.22225 0.09271) (xy 0.22479 0.08128) (xy 0.22606 0.07112) (xy 0.2286 0.05969)
						(xy 0.2286 0.01651) (xy 0.22606 0.00508) (xy 0.22479 -0.00508) (xy 0.22225 -0.01651) (xy 0.21971 -0.02667)
						(xy 0.20828 -0.05715) (xy 0.19812 -0.07747) (xy 0.19177 -0.08636) (xy 0.18669 -0.09525) (xy 0.17907 -0.10414)
						(xy 0.17272 -0.11303) (xy 0.1651 -0.12065) (xy 0.1651 -0.7366) (xy 0.16256 -0.76835) (xy 0.1524 -0.8001)
						(xy 0.13716 -0.82804) (xy 0.11684 -0.85344) (xy 0.09144 -0.87376) (xy 0.0635 -0.889) (xy 0.03175 -0.89916)
					)
					(width 0)
					(fill yes)
				)
			)
		)
		(pad "113" smd custom
			(at 4.350004 -4.100068 180)
			(size 0.1143 0.1143)
			(layers "B.Cu" "B.Mask" "B.Paste")
			(net "M_B_CK_DN0")
			(options
				(clearance outline)
				(anchor circle)
			)
			(primitives
				(gr_poly
					(pts
						(xy 0 -0.9017) (xy -0.03175 -0.89916) (xy -0.0635 -0.889) (xy -0.09144 -0.87376) (xy -0.11684 -0.85344)
						(xy -0.13716 -0.82804) (xy -0.1524 -0.8001) (xy -0.16256 -0.76835) (xy -0.1651 -0.7366) (xy -0.1651 -0.44958)
						(xy -0.17272 -0.44196) (xy -0.19812 -0.4064) (xy -0.2032 -0.39624) (xy -0.20701 -0.38735) (xy -0.21209 -0.37719)
						(xy -0.2159 -0.36703) (xy -0.21844 -0.35687) (xy -0.22225 -0.34544) (xy -0.22352 -0.33528) (xy -0.22606 -0.32512)
						(xy -0.22733 -0.31369) (xy -0.22733 -0.30353) (xy -0.2286 -0.2921) (xy -0.22733 -0.28067) (xy -0.22733 -0.27051)
						(xy -0.22606 -0.25908) (xy -0.22352 -0.24892) (xy -0.22225 -0.23876) (xy -0.21844 -0.22733) (xy -0.2159 -0.21717)
						(xy -0.21209 -0.20701) (xy -0.20701 -0.19685) (xy -0.2032 -0.18796) (xy -0.19812 -0.1778) (xy -0.17272 -0.14224)
						(xy -0.1651 -0.13462) (xy -0.1651 0.7366) (xy -0.16256 0.76835) (xy -0.1524 0.8001) (xy -0.13716 0.82804)
						(xy -0.11684 0.85344) (xy -0.09144 0.87376) (xy -0.0635 0.889) (xy -0.03175 0.89916) (xy 0 0.9017)
						(xy 0.03175 0.89916) (xy 0.0635 0.889) (xy 0.09144 0.87376) (xy 0.11684 0.85344) (xy 0.13716 0.82804)
						(xy 0.1524 0.8001) (xy 0.16256 0.76835) (xy 0.1651 0.7366) (xy 0.1651 -0.13462) (xy 0.17272 -0.14224)
						(xy 0.19812 -0.1778) (xy 0.2032 -0.18796) (xy 0.20701 -0.19685) (xy 0.21209 -0.20701) (xy 0.2159 -0.21717)
						(xy 0.21844 -0.22733) (xy 0.22225 -0.23876) (xy 0.22352 -0.24892) (xy 0.22606 -0.25908) (xy 0.22733 -0.27051)
						(xy 0.22733 -0.28067) (xy 0.2286 -0.2921) (xy 0.22733 -0.30353) (xy 0.22733 -0.31369) (xy 0.22606 -0.32512)
						(xy 0.22352 -0.33528) (xy 0.22225 -0.34544) (xy 0.21844 -0.35687) (xy 0.2159 -0.36703) (xy 0.21209 -0.37719)
						(xy 0.20701 -0.38735) (xy 0.2032 -0.39624) (xy 0.19812 -0.4064) (xy 0.17272 -0.44196) (xy 0.1651 -0.44958)
						(xy 0.1651 -0.7366) (xy 0.16256 -0.76835) (xy 0.1524 -0.8001) (xy 0.13716 -0.82804) (xy 0.11684 -0.85344)
						(xy 0.09144 -0.87376) (xy 0.0635 -0.889) (xy 0.03175 -0.89916)
					)
					(width 0)
					(fill yes)
				)
			)
		)
		(pad "114" smd custom
			(at 4.649978 4.100068 180)
			(size 0.1143 0.1143)
			(layers "B.Cu" "B.Mask" "B.Paste")
			(net "M_B_CK_DN1")
			(options
				(clearance outline)
				(anchor circle)
			)
			(primitives
				(gr_poly
					(pts
						(xy 0 -0.9017) (xy -0.03175 -0.89916) (xy -0.0635 -0.889) (xy -0.09144 -0.87376) (xy -0.11684 -0.85344)
						(xy -0.13716 -0.82804) (xy -0.1524 -0.8001) (xy -0.16256 -0.76835) (xy -0.1651 -0.7366) (xy -0.1651 0.13462)
						(xy -0.17272 0.14224) (xy -0.19812 0.1778) (xy -0.2032 0.18796) (xy -0.20701 0.19685) (xy -0.21209 0.20701)
						(xy -0.2159 0.21717) (xy -0.21844 0.22733) (xy -0.22225 0.23876) (xy -0.22352 0.24892) (xy -0.22606 0.25908)
						(xy -0.22733 0.27051) (xy -0.22733 0.28067) (xy -0.2286 0.2921) (xy -0.22733 0.30353) (xy -0.22733 0.31369)
						(xy -0.22606 0.32512) (xy -0.22352 0.33528) (xy -0.22225 0.34544) (xy -0.21844 0.35687) (xy -0.2159 0.36703)
						(xy -0.21209 0.37719) (xy -0.20701 0.38735) (xy -0.2032 0.39624) (xy -0.19812 0.4064) (xy -0.17272 0.44196)
						(xy -0.1651 0.44958) (xy -0.1651 0.7366) (xy -0.16256 0.76835) (xy -0.1524 0.8001) (xy -0.13716 0.82804)
						(xy -0.11684 0.85344) (xy -0.09144 0.87376) (xy -0.0635 0.889) (xy -0.03175 0.89916) (xy 0 0.9017)
						(xy 0.03175 0.89916) (xy 0.0635 0.889) (xy 0.09144 0.87376) (xy 0.11684 0.85344) (xy 0.13716 0.82804)
						(xy 0.1524 0.8001) (xy 0.16256 0.76835) (xy 0.1651 0.7366) (xy 0.1651 0.44958) (xy 0.17272 0.44196)
						(xy 0.19812 0.4064) (xy 0.2032 0.39624) (xy 0.20701 0.38735) (xy 0.21209 0.37719) (xy 0.2159 0.36703)
						(xy 0.21844 0.35687) (xy 0.22225 0.34544) (xy 0.22352 0.33528) (xy 0.22606 0.32512) (xy 0.22733 0.31369)
						(xy 0.22733 0.30353) (xy 0.2286 0.2921) (xy 0.22733 0.28067) (xy 0.22733 0.27051) (xy 0.22606 0.25908)
						(xy 0.22352 0.24892) (xy 0.22225 0.23876) (xy 0.21844 0.22733) (xy 0.2159 0.21717) (xy 0.21209 0.20701)
						(xy 0.20701 0.19685) (xy 0.2032 0.18796) (xy 0.19812 0.1778) (xy 0.17272 0.14224) (xy 0.1651 0.13462)
						(xy 0.1651 -0.7366) (xy 0.16256 -0.76835) (xy 0.1524 -0.8001) (xy 0.13716 -0.82804) (xy 0.11684 -0.85344)
						(xy 0.09144 -0.87376) (xy 0.0635 -0.889) (xy 0.03175 -0.89916)
					)
					(width 0)
					(fill yes)
				)
			)
		)
		(pad "115" smd custom
			(at 4.949952 -4.100068 180)
			(size 0.1143 0.1143)
			(layers "B.Cu" "B.Mask" "B.Paste")
			(net "PV_VDDR")
			(options
				(clearance outline)
				(anchor circle)
			)
			(primitives
				(gr_poly
					(pts
						(xy 0 -0.9017) (xy -0.03175 -0.89916) (xy -0.0635 -0.889) (xy -0.09144 -0.87376) (xy -0.11684 -0.85344)
						(xy -0.13716 -0.82804) (xy -0.1524 -0.8001) (xy -0.16256 -0.76835) (xy -0.1651 -0.7366) (xy -0.1651 -0.19685)
						(xy -0.17272 -0.18923) (xy -0.17907 -0.18034) (xy -0.18669 -0.17145) (xy -0.19177 -0.16256) (xy -0.19812 -0.15367)
						(xy -0.20828 -0.13335) (xy -0.21971 -0.10287) (xy -0.22225 -0.09271) (xy -0.22479 -0.08128) (xy -0.22606 -0.07112)
						(xy -0.2286 -0.05969) (xy -0.2286 -0.01651) (xy -0.22606 -0.00508) (xy -0.22479 0.00508) (xy -0.22225 0.01651)
						(xy -0.21971 0.02667) (xy -0.20828 0.05715) (xy -0.19812 0.07747) (xy -0.19177 0.08636) (xy -0.18669 0.09525)
						(xy -0.17907 0.10414) (xy -0.17272 0.11303) (xy -0.1651 0.12065) (xy -0.1651 0.7366) (xy -0.16256 0.76835)
						(xy -0.1524 0.8001) (xy -0.13716 0.82804) (xy -0.11684 0.85344) (xy -0.09144 0.87376) (xy -0.0635 0.889)
						(xy -0.03175 0.89916) (xy 0 0.9017) (xy 0.03175 0.89916) (xy 0.0635 0.889) (xy 0.09144 0.87376)
						(xy 0.11684 0.85344) (xy 0.13716 0.82804) (xy 0.1524 0.8001) (xy 0.16256 0.76835) (xy 0.1651 0.7366)
						(xy 0.1651 0.11938) (xy 0.17272 0.11176) (xy 0.19812 0.0762) (xy 0.2032 0.06604) (xy 0.20701 0.05715)
						(xy 0.21209 0.04699) (xy 0.2159 0.03683) (xy 0.21844 0.02667) (xy 0.22225 0.01524) (xy 0.22352 0.00508)
						(xy 0.22606 -0.00508) (xy 0.22733 -0.01651) (xy 0.22733 -0.02667) (xy 0.2286 -0.0381) (xy 0.22733 -0.04953)
						(xy 0.22733 -0.05969) (xy 0.22606 -0.07112) (xy 0.22352 -0.08128) (xy 0.22225 -0.09144) (xy 0.21844 -0.10287)
						(xy 0.2159 -0.11303) (xy 0.21209 -0.12319) (xy 0.20701 -0.13335) (xy 0.2032 -0.14224) (xy 0.19812 -0.1524)
						(xy 0.17272 -0.18796) (xy 0.1651 -0.19558) (xy 0.1651 -0.7366) (xy 0.16256 -0.76835) (xy 0.1524 -0.8001)
						(xy 0.13716 -0.82804) (xy 0.11684 -0.85344) (xy 0.09144 -0.87376) (xy 0.0635 -0.889) (xy 0.03175 -0.89916)
					)
					(width 0)
					(fill yes)
				)
			)
		)
		(pad "116" smd custom
			(at 5.249926 4.100068 180)
			(size 0.1143 0.1143)
			(layers "B.Cu" "B.Mask" "B.Paste")
			(net "PV_VDDR")
			(options
				(clearance outline)
				(anchor circle)
			)
			(primitives
				(gr_poly
					(pts
						(xy 0 -0.9017) (xy -0.03175 -0.89916) (xy -0.0635 -0.889) (xy -0.09144 -0.87376) (xy -0.11684 -0.85344)
						(xy -0.13716 -0.82804) (xy -0.1524 -0.8001) (xy -0.16256 -0.76835) (xy -0.1651 -0.7366) (xy -0.1651 -0.11938)
						(xy -0.17272 -0.11176) (xy -0.19812 -0.0762) (xy -0.2032 -0.06604) (xy -0.20701 -0.05715) (xy -0.21209 -0.04699)
						(xy -0.2159 -0.03683) (xy -0.21844 -0.02667) (xy -0.22225 -0.01524) (xy -0.22352 -0.00508) (xy -0.22606 0.00508)
						(xy -0.22733 0.01651) (xy -0.22733 0.02667) (xy -0.2286 0.0381) (xy -0.22733 0.04953) (xy -0.22733 0.05969)
						(xy -0.22606 0.07112) (xy -0.22352 0.08128) (xy -0.22225 0.09144) (xy -0.21844 0.10287) (xy -0.2159 0.11303)
						(xy -0.21209 0.12319) (xy -0.20701 0.13335) (xy -0.2032 0.14224) (xy -0.19812 0.1524) (xy -0.17272 0.18796)
						(xy -0.1651 0.19558) (xy -0.1651 0.7366) (xy -0.16256 0.76835) (xy -0.1524 0.8001) (xy -0.13716 0.82804)
						(xy -0.11684 0.85344) (xy -0.09144 0.87376) (xy -0.0635 0.889) (xy -0.03175 0.89916) (xy 0 0.9017)
						(xy 0.03175 0.89916) (xy 0.0635 0.889) (xy 0.09144 0.87376) (xy 0.11684 0.85344) (xy 0.13716 0.82804)
						(xy 0.1524 0.8001) (xy 0.16256 0.76835) (xy 0.1651 0.7366) (xy 0.1651 0.19685) (xy 0.17272 0.18923)
						(xy 0.17907 0.18034) (xy 0.18669 0.17145) (xy 0.19177 0.16256) (xy 0.19812 0.15367) (xy 0.20828 0.13335)
						(xy 0.21971 0.10287) (xy 0.22225 0.09271) (xy 0.22479 0.08128) (xy 0.22606 0.07112) (xy 0.2286 0.05969)
						(xy 0.2286 0.01651) (xy 0.22606 0.00508) (xy 0.22479 -0.00508) (xy 0.22225 -0.01651) (xy 0.21971 -0.02667)
						(xy 0.20828 -0.05715) (xy 0.19812 -0.07747) (xy 0.19177 -0.08636) (xy 0.18669 -0.09525) (xy 0.17907 -0.10414)
						(xy 0.17272 -0.11303) (xy 0.1651 -0.12065) (xy 0.1651 -0.7366) (xy 0.16256 -0.76835) (xy 0.1524 -0.8001)
						(xy 0.13716 -0.82804) (xy 0.11684 -0.85344) (xy 0.09144 -0.87376) (xy 0.0635 -0.889) (xy 0.03175 -0.89916)
					)
					(width 0)
					(fill yes)
				)
			)
		)
		(pad "117" smd custom
			(at 5.5499 -4.100068 180)
			(size 0.1143 0.1143)
			(layers "B.Cu" "B.Mask" "B.Paste")
			(net "M_B_MA10")
			(options
				(clearance outline)
				(anchor circle)
			)
			(primitives
				(gr_poly
					(pts
						(xy 0 -0.9017) (xy -0.03175 -0.89916) (xy -0.0635 -0.889) (xy -0.09144 -0.87376) (xy -0.11684 -0.85344)
						(xy -0.13716 -0.82804) (xy -0.1524 -0.8001) (xy -0.16256 -0.76835) (xy -0.1651 -0.7366) (xy -0.1651 -0.44958)
						(xy -0.17272 -0.44196) (xy -0.19812 -0.4064) (xy -0.2032 -0.39624) (xy -0.20701 -0.38735) (xy -0.21209 -0.37719)
						(xy -0.2159 -0.36703) (xy -0.21844 -0.35687) (xy -0.22225 -0.34544) (xy -0.22352 -0.33528) (xy -0.22606 -0.32512)
						(xy -0.22733 -0.31369) (xy -0.22733 -0.30353) (xy -0.2286 -0.2921) (xy -0.22733 -0.28067) (xy -0.22733 -0.27051)
						(xy -0.22606 -0.25908) (xy -0.22352 -0.24892) (xy -0.22225 -0.23876) (xy -0.21844 -0.22733) (xy -0.2159 -0.21717)
						(xy -0.21209 -0.20701) (xy -0.20701 -0.19685) (xy -0.2032 -0.18796) (xy -0.19812 -0.1778) (xy -0.17272 -0.14224)
						(xy -0.1651 -0.13462) (xy -0.1651 0.7366) (xy -0.16256 0.76835) (xy -0.1524 0.8001) (xy -0.13716 0.82804)
						(xy -0.11684 0.85344) (xy -0.09144 0.87376) (xy -0.0635 0.889) (xy -0.03175 0.89916) (xy 0 0.9017)
						(xy 0.03175 0.89916) (xy 0.0635 0.889) (xy 0.09144 0.87376) (xy 0.11684 0.85344) (xy 0.13716 0.82804)
						(xy 0.1524 0.8001) (xy 0.16256 0.76835) (xy 0.1651 0.7366) (xy 0.1651 -0.13462) (xy 0.17272 -0.14224)
						(xy 0.19812 -0.1778) (xy 0.2032 -0.18796) (xy 0.20701 -0.19685) (xy 0.21209 -0.20701) (xy 0.2159 -0.21717)
						(xy 0.21844 -0.22733) (xy 0.22225 -0.23876) (xy 0.22352 -0.24892) (xy 0.22606 -0.25908) (xy 0.22733 -0.27051)
						(xy 0.22733 -0.28067) (xy 0.2286 -0.2921) (xy 0.22733 -0.30353) (xy 0.22733 -0.31369) (xy 0.22606 -0.32512)
						(xy 0.22352 -0.33528) (xy 0.22225 -0.34544) (xy 0.21844 -0.35687) (xy 0.2159 -0.36703) (xy 0.21209 -0.37719)
						(xy 0.20701 -0.38735) (xy 0.2032 -0.39624) (xy 0.19812 -0.4064) (xy 0.17272 -0.44196) (xy 0.1651 -0.44958)
						(xy 0.1651 -0.7366) (xy 0.16256 -0.76835) (xy 0.1524 -0.8001) (xy 0.13716 -0.82804) (xy 0.11684 -0.85344)
						(xy 0.09144 -0.87376) (xy 0.0635 -0.889) (xy 0.03175 -0.89916)
					)
					(width 0)
					(fill yes)
				)
			)
		)
		(pad "118" smd custom
			(at 5.849874 4.100068 180)
			(size 0.1143 0.1143)
			(layers "B.Cu" "B.Mask" "B.Paste")
			(net "Net_8")
			(options
				(clearance outline)
				(anchor circle)
			)
			(primitives
				(gr_poly
					(pts
						(xy 0 -0.9017) (xy -0.03175 -0.89916) (xy -0.0635 -0.889) (xy -0.09144 -0.87376) (xy -0.11684 -0.85344)
						(xy -0.13716 -0.82804) (xy -0.1524 -0.8001) (xy -0.16256 -0.76835) (xy -0.1651 -0.7366) (xy -0.1651 0.13462)
						(xy -0.17272 0.14224) (xy -0.19812 0.1778) (xy -0.2032 0.18796) (xy -0.20701 0.19685) (xy -0.21209 0.20701)
						(xy -0.2159 0.21717) (xy -0.21844 0.22733) (xy -0.22225 0.23876) (xy -0.22352 0.24892) (xy -0.22606 0.25908)
						(xy -0.22733 0.27051) (xy -0.22733 0.28067) (xy -0.2286 0.2921) (xy -0.22733 0.30353) (xy -0.22733 0.31369)
						(xy -0.22606 0.32512) (xy -0.22352 0.33528) (xy -0.22225 0.34544) (xy -0.21844 0.35687) (xy -0.2159 0.36703)
						(xy -0.21209 0.37719) (xy -0.20701 0.38735) (xy -0.2032 0.39624) (xy -0.19812 0.4064) (xy -0.17272 0.44196)
						(xy -0.1651 0.44958) (xy -0.1651 0.7366) (xy -0.16256 0.76835) (xy -0.1524 0.8001) (xy -0.13716 0.82804)
						(xy -0.11684 0.85344) (xy -0.09144 0.87376) (xy -0.0635 0.889) (xy -0.03175 0.89916) (xy 0 0.9017)
						(xy 0.03175 0.89916) (xy 0.0635 0.889) (xy 0.09144 0.87376) (xy 0.11684 0.85344) (xy 0.13716 0.82804)
						(xy 0.1524 0.8001) (xy 0.16256 0.76835) (xy 0.1651 0.7366) (xy 0.1651 0.44958) (xy 0.17272 0.44196)
						(xy 0.19812 0.4064) (xy 0.2032 0.39624) (xy 0.20701 0.38735) (xy 0.21209 0.37719) (xy 0.2159 0.36703)
						(xy 0.21844 0.35687) (xy 0.22225 0.34544) (xy 0.22352 0.33528) (xy 0.22606 0.32512) (xy 0.22733 0.31369)
						(xy 0.22733 0.30353) (xy 0.2286 0.2921) (xy 0.22733 0.28067) (xy 0.22733 0.27051) (xy 0.22606 0.25908)
						(xy 0.22352 0.24892) (xy 0.22225 0.23876) (xy 0.21844 0.22733) (xy 0.2159 0.21717) (xy 0.21209 0.20701)
						(xy 0.20701 0.19685) (xy 0.2032 0.18796) (xy 0.19812 0.1778) (xy 0.17272 0.14224) (xy 0.1651 0.13462)
						(xy 0.1651 -0.7366) (xy 0.16256 -0.76835) (xy 0.1524 -0.8001) (xy 0.13716 -0.82804) (xy 0.11684 -0.85344)
						(xy 0.09144 -0.87376) (xy 0.0635 -0.889) (xy 0.03175 -0.89916)
					)
					(width 0)
					(fill yes)
				)
			)
		)
		(pad "119" smd custom
			(at 6.150102 -4.100068 180)
			(size 0.1143 0.1143)
			(layers "B.Cu" "B.Mask" "B.Paste")
			(net "M_B_BS0")
			(options
				(clearance outline)
				(anchor circle)
			)
			(primitives
				(gr_poly
					(pts
						(xy 0 -0.9017) (xy -0.03175 -0.89916) (xy -0.0635 -0.889) (xy -0.09144 -0.87376) (xy -0.11684 -0.85344)
						(xy -0.13716 -0.82804) (xy -0.1524 -0.8001) (xy -0.16256 -0.76835) (xy -0.1651 -0.7366) (xy -0.1651 -0.19685)
						(xy -0.17272 -0.18923) (xy -0.17907 -0.18034) (xy -0.18669 -0.17145) (xy -0.19177 -0.16256) (xy -0.19812 -0.15367)
						(xy -0.20828 -0.13335) (xy -0.21971 -0.10287) (xy -0.22225 -0.09271) (xy -0.22479 -0.08128) (xy -0.22606 -0.07112)
						(xy -0.2286 -0.05969) (xy -0.2286 -0.01651) (xy -0.22606 -0.00508) (xy -0.22479 0.00508) (xy -0.22225 0.01651)
						(xy -0.21971 0.02667) (xy -0.20828 0.05715) (xy -0.19812 0.07747) (xy -0.19177 0.08636) (xy -0.18669 0.09525)
						(xy -0.17907 0.10414) (xy -0.17272 0.11303) (xy -0.1651 0.12065) (xy -0.1651 0.7366) (xy -0.16256 0.76835)
						(xy -0.1524 0.8001) (xy -0.13716 0.82804) (xy -0.11684 0.85344) (xy -0.09144 0.87376) (xy -0.0635 0.889)
						(xy -0.03175 0.89916) (xy 0 0.9017) (xy 0.03175 0.89916) (xy 0.0635 0.889) (xy 0.09144 0.87376)
						(xy 0.11684 0.85344) (xy 0.13716 0.82804) (xy 0.1524 0.8001) (xy 0.16256 0.76835) (xy 0.1651 0.7366)
						(xy 0.1651 0.11938) (xy 0.17272 0.11176) (xy 0.19812 0.0762) (xy 0.2032 0.06604) (xy 0.20701 0.05715)
						(xy 0.21209 0.04699) (xy 0.2159 0.03683) (xy 0.21844 0.02667) (xy 0.22225 0.01524) (xy 0.22352 0.00508)
						(xy 0.22606 -0.00508) (xy 0.22733 -0.01651) (xy 0.22733 -0.02667) (xy 0.2286 -0.0381) (xy 0.22733 -0.04953)
						(xy 0.22733 -0.05969) (xy 0.22606 -0.07112) (xy 0.22352 -0.08128) (xy 0.22225 -0.09144) (xy 0.21844 -0.10287)
						(xy 0.2159 -0.11303) (xy 0.21209 -0.12319) (xy 0.20701 -0.13335) (xy 0.2032 -0.14224) (xy 0.19812 -0.1524)
						(xy 0.17272 -0.18796) (xy 0.1651 -0.19558) (xy 0.1651 -0.7366) (xy 0.16256 -0.76835) (xy 0.1524 -0.8001)
						(xy 0.13716 -0.82804) (xy 0.11684 -0.85344) (xy 0.09144 -0.87376) (xy 0.0635 -0.889) (xy 0.03175 -0.89916)
					)
					(width 0)
					(fill yes)
				)
			)
		)
		(pad "120" smd custom
			(at 6.450076 4.100068 180)
			(size 0.1143 0.1143)
			(layers "B.Cu" "B.Mask" "B.Paste")
			(net "Net_7")
			(options
				(clearance outline)
				(anchor circle)
			)
			(primitives
				(gr_poly
					(pts
						(xy 0 -0.9017) (xy -0.03175 -0.89916) (xy -0.0635 -0.889) (xy -0.09144 -0.87376) (xy -0.11684 -0.85344)
						(xy -0.13716 -0.82804) (xy -0.1524 -0.8001) (xy -0.16256 -0.76835) (xy -0.1651 -0.7366) (xy -0.1651 -0.11938)
						(xy -0.17272 -0.11176) (xy -0.19812 -0.0762) (xy -0.2032 -0.06604) (xy -0.20701 -0.05715) (xy -0.21209 -0.04699)
						(xy -0.2159 -0.03683) (xy -0.21844 -0.02667) (xy -0.22225 -0.01524) (xy -0.22352 -0.00508) (xy -0.22606 0.00508)
						(xy -0.22733 0.01651) (xy -0.22733 0.02667) (xy -0.2286 0.0381) (xy -0.22733 0.04953) (xy -0.22733 0.05969)
						(xy -0.22606 0.07112) (xy -0.22352 0.08128) (xy -0.22225 0.09144) (xy -0.21844 0.10287) (xy -0.2159 0.11303)
						(xy -0.21209 0.12319) (xy -0.20701 0.13335) (xy -0.2032 0.14224) (xy -0.19812 0.1524) (xy -0.17272 0.18796)
						(xy -0.1651 0.19558) (xy -0.1651 0.7366) (xy -0.16256 0.76835) (xy -0.1524 0.8001) (xy -0.13716 0.82804)
						(xy -0.11684 0.85344) (xy -0.09144 0.87376) (xy -0.0635 0.889) (xy -0.03175 0.89916) (xy 0 0.9017)
						(xy 0.03175 0.89916) (xy 0.0635 0.889) (xy 0.09144 0.87376) (xy 0.11684 0.85344) (xy 0.13716 0.82804)
						(xy 0.1524 0.8001) (xy 0.16256 0.76835) (xy 0.1651 0.7366) (xy 0.1651 0.19685) (xy 0.17272 0.18923)
						(xy 0.17907 0.18034) (xy 0.18669 0.17145) (xy 0.19177 0.16256) (xy 0.19812 0.15367) (xy 0.20828 0.13335)
						(xy 0.21971 0.10287) (xy 0.22225 0.09271) (xy 0.22479 0.08128) (xy 0.22606 0.07112) (xy 0.2286 0.05969)
						(xy 0.2286 0.01651) (xy 0.22606 0.00508) (xy 0.22479 -0.00508) (xy 0.22225 -0.01651) (xy 0.21971 -0.02667)
						(xy 0.20828 -0.05715) (xy 0.19812 -0.07747) (xy 0.19177 -0.08636) (xy 0.18669 -0.09525) (xy 0.17907 -0.10414)
						(xy 0.17272 -0.11303) (xy 0.1651 -0.12065) (xy 0.1651 -0.7366) (xy 0.16256 -0.76835) (xy 0.1524 -0.8001)
						(xy 0.13716 -0.82804) (xy 0.11684 -0.85344) (xy 0.09144 -0.87376) (xy 0.0635 -0.889) (xy 0.03175 -0.89916)
					)
					(width 0)
					(fill yes)
				)
			)
		)
		(pad "121" smd custom
			(at 6.75005 -4.100068 180)
			(size 0.1143 0.1143)
			(layers "B.Cu" "B.Mask" "B.Paste")
			(net "M_B_WE#")
			(options
				(clearance outline)
				(anchor circle)
			)
			(primitives
				(gr_poly
					(pts
						(xy 0 -0.9017) (xy -0.03175 -0.89916) (xy -0.0635 -0.889) (xy -0.09144 -0.87376) (xy -0.11684 -0.85344)
						(xy -0.13716 -0.82804) (xy -0.1524 -0.8001) (xy -0.16256 -0.76835) (xy -0.1651 -0.7366) (xy -0.1651 -0.44958)
						(xy -0.17272 -0.44196) (xy -0.19812 -0.4064) (xy -0.2032 -0.39624) (xy -0.20701 -0.38735) (xy -0.21209 -0.37719)
						(xy -0.2159 -0.36703) (xy -0.21844 -0.35687) (xy -0.22225 -0.34544) (xy -0.22352 -0.33528) (xy -0.22606 -0.32512)
						(xy -0.22733 -0.31369) (xy -0.22733 -0.30353) (xy -0.2286 -0.2921) (xy -0.22733 -0.28067) (xy -0.22733 -0.27051)
						(xy -0.22606 -0.25908) (xy -0.22352 -0.24892) (xy -0.22225 -0.23876) (xy -0.21844 -0.22733) (xy -0.2159 -0.21717)
						(xy -0.21209 -0.20701) (xy -0.20701 -0.19685) (xy -0.2032 -0.18796) (xy -0.19812 -0.1778) (xy -0.17272 -0.14224)
						(xy -0.1651 -0.13462) (xy -0.1651 0.7366) (xy -0.16256 0.76835) (xy -0.1524 0.8001) (xy -0.13716 0.82804)
						(xy -0.11684 0.85344) (xy -0.09144 0.87376) (xy -0.0635 0.889) (xy -0.03175 0.89916) (xy 0 0.9017)
						(xy 0.03175 0.89916) (xy 0.0635 0.889) (xy 0.09144 0.87376) (xy 0.11684 0.85344) (xy 0.13716 0.82804)
						(xy 0.1524 0.8001) (xy 0.16256 0.76835) (xy 0.1651 0.7366) (xy 0.1651 -0.13462) (xy 0.17272 -0.14224)
						(xy 0.19812 -0.1778) (xy 0.2032 -0.18796) (xy 0.20701 -0.19685) (xy 0.21209 -0.20701) (xy 0.2159 -0.21717)
						(xy 0.21844 -0.22733) (xy 0.22225 -0.23876) (xy 0.22352 -0.24892) (xy 0.22606 -0.25908) (xy 0.22733 -0.27051)
						(xy 0.22733 -0.28067) (xy 0.2286 -0.2921) (xy 0.22733 -0.30353) (xy 0.22733 -0.31369) (xy 0.22606 -0.32512)
						(xy 0.22352 -0.33528) (xy 0.22225 -0.34544) (xy 0.21844 -0.35687) (xy 0.2159 -0.36703) (xy 0.21209 -0.37719)
						(xy 0.20701 -0.38735) (xy 0.2032 -0.39624) (xy 0.19812 -0.4064) (xy 0.17272 -0.44196) (xy 0.1651 -0.44958)
						(xy 0.1651 -0.7366) (xy 0.16256 -0.76835) (xy 0.1524 -0.8001) (xy 0.13716 -0.82804) (xy 0.11684 -0.85344)
						(xy 0.09144 -0.87376) (xy 0.0635 -0.889) (xy 0.03175 -0.89916)
					)
					(width 0)
					(fill yes)
				)
			)
		)
		(pad "122" smd custom
			(at 7.050024 4.100068 180)
			(size 0.1143 0.1143)
			(layers "B.Cu" "B.Mask" "B.Paste")
			(net "M_B_RAS#")
			(options
				(clearance outline)
				(anchor circle)
			)
			(primitives
				(gr_poly
					(pts
						(xy 0 -0.9017) (xy -0.03175 -0.89916) (xy -0.0635 -0.889) (xy -0.09144 -0.87376) (xy -0.11684 -0.85344)
						(xy -0.13716 -0.82804) (xy -0.1524 -0.8001) (xy -0.16256 -0.76835) (xy -0.1651 -0.7366) (xy -0.1651 0.13462)
						(xy -0.17272 0.14224) (xy -0.19812 0.1778) (xy -0.2032 0.18796) (xy -0.20701 0.19685) (xy -0.21209 0.20701)
						(xy -0.2159 0.21717) (xy -0.21844 0.22733) (xy -0.22225 0.23876) (xy -0.22352 0.24892) (xy -0.22606 0.25908)
						(xy -0.22733 0.27051) (xy -0.22733 0.28067) (xy -0.2286 0.2921) (xy -0.22733 0.30353) (xy -0.22733 0.31369)
						(xy -0.22606 0.32512) (xy -0.22352 0.33528) (xy -0.22225 0.34544) (xy -0.21844 0.35687) (xy -0.2159 0.36703)
						(xy -0.21209 0.37719) (xy -0.20701 0.38735) (xy -0.2032 0.39624) (xy -0.19812 0.4064) (xy -0.17272 0.44196)
						(xy -0.1651 0.44958) (xy -0.1651 0.7366) (xy -0.16256 0.76835) (xy -0.1524 0.8001) (xy -0.13716 0.82804)
						(xy -0.11684 0.85344) (xy -0.09144 0.87376) (xy -0.0635 0.889) (xy -0.03175 0.89916) (xy 0 0.9017)
						(xy 0.03175 0.89916) (xy 0.0635 0.889) (xy 0.09144 0.87376) (xy 0.11684 0.85344) (xy 0.13716 0.82804)
						(xy 0.1524 0.8001) (xy 0.16256 0.76835) (xy 0.1651 0.7366) (xy 0.1651 0.44958) (xy 0.17272 0.44196)
						(xy 0.19812 0.4064) (xy 0.2032 0.39624) (xy 0.20701 0.38735) (xy 0.21209 0.37719) (xy 0.2159 0.36703)
						(xy 0.21844 0.35687) (xy 0.22225 0.34544) (xy 0.22352 0.33528) (xy 0.22606 0.32512) (xy 0.22733 0.31369)
						(xy 0.22733 0.30353) (xy 0.2286 0.2921) (xy 0.22733 0.28067) (xy 0.22733 0.27051) (xy 0.22606 0.25908)
						(xy 0.22352 0.24892) (xy 0.22225 0.23876) (xy 0.21844 0.22733) (xy 0.2159 0.21717) (xy 0.21209 0.20701)
						(xy 0.20701 0.19685) (xy 0.2032 0.18796) (xy 0.19812 0.1778) (xy 0.17272 0.14224) (xy 0.1651 0.13462)
						(xy 0.1651 -0.7366) (xy 0.16256 -0.76835) (xy 0.1524 -0.8001) (xy 0.13716 -0.82804) (xy 0.11684 -0.85344)
						(xy 0.09144 -0.87376) (xy 0.0635 -0.889) (xy 0.03175 -0.89916)
					)
					(width 0)
					(fill yes)
				)
			)
		)
		(pad "123" smd custom
			(at 7.349998 -4.100068 180)
			(size 0.1143 0.1143)
			(layers "B.Cu" "B.Mask" "B.Paste")
			(net "PV_VDDR")
			(options
				(clearance outline)
				(anchor circle)
			)
			(primitives
				(gr_poly
					(pts
						(xy 0 -0.9017) (xy -0.03175 -0.89916) (xy -0.0635 -0.889) (xy -0.09144 -0.87376) (xy -0.11684 -0.85344)
						(xy -0.13716 -0.82804) (xy -0.1524 -0.8001) (xy -0.16256 -0.76835) (xy -0.1651 -0.7366) (xy -0.1651 -0.19685)
						(xy -0.17272 -0.18923) (xy -0.17907 -0.18034) (xy -0.18669 -0.17145) (xy -0.19177 -0.16256) (xy -0.19812 -0.15367)
						(xy -0.20828 -0.13335) (xy -0.21971 -0.10287) (xy -0.22225 -0.09271) (xy -0.22479 -0.08128) (xy -0.22606 -0.07112)
						(xy -0.2286 -0.05969) (xy -0.2286 -0.01651) (xy -0.22606 -0.00508) (xy -0.22479 0.00508) (xy -0.22225 0.01651)
						(xy -0.21971 0.02667) (xy -0.20828 0.05715) (xy -0.19812 0.07747) (xy -0.19177 0.08636) (xy -0.18669 0.09525)
						(xy -0.17907 0.10414) (xy -0.17272 0.11303) (xy -0.1651 0.12065) (xy -0.1651 0.7366) (xy -0.16256 0.76835)
						(xy -0.1524 0.8001) (xy -0.13716 0.82804) (xy -0.11684 0.85344) (xy -0.09144 0.87376) (xy -0.0635 0.889)
						(xy -0.03175 0.89916) (xy 0 0.9017) (xy 0.03175 0.89916) (xy 0.0635 0.889) (xy 0.09144 0.87376)
						(xy 0.11684 0.85344) (xy 0.13716 0.82804) (xy 0.1524 0.8001) (xy 0.16256 0.76835) (xy 0.1651 0.7366)
						(xy 0.1651 0.11938) (xy 0.17272 0.11176) (xy 0.19812 0.0762) (xy 0.2032 0.06604) (xy 0.20701 0.05715)
						(xy 0.21209 0.04699) (xy 0.2159 0.03683) (xy 0.21844 0.02667) (xy 0.22225 0.01524) (xy 0.22352 0.00508)
						(xy 0.22606 -0.00508) (xy 0.22733 -0.01651) (xy 0.22733 -0.02667) (xy 0.2286 -0.0381) (xy 0.22733 -0.04953)
						(xy 0.22733 -0.05969) (xy 0.22606 -0.07112) (xy 0.22352 -0.08128) (xy 0.22225 -0.09144) (xy 0.21844 -0.10287)
						(xy 0.2159 -0.11303) (xy 0.21209 -0.12319) (xy 0.20701 -0.13335) (xy 0.2032 -0.14224) (xy 0.19812 -0.1524)
						(xy 0.17272 -0.18796) (xy 0.1651 -0.19558) (xy 0.1651 -0.7366) (xy 0.16256 -0.76835) (xy 0.1524 -0.8001)
						(xy 0.13716 -0.82804) (xy 0.11684 -0.85344) (xy 0.09144 -0.87376) (xy 0.0635 -0.889) (xy 0.03175 -0.89916)
					)
					(width 0)
					(fill yes)
				)
			)
		)
		(pad "124" smd custom
			(at 7.649972 4.100068 180)
			(size 0.1143 0.1143)
			(layers "B.Cu" "B.Mask" "B.Paste")
			(net "PV_VDDR")
			(options
				(clearance outline)
				(anchor circle)
			)
			(primitives
				(gr_poly
					(pts
						(xy 0 -0.9017) (xy -0.03175 -0.89916) (xy -0.0635 -0.889) (xy -0.09144 -0.87376) (xy -0.11684 -0.85344)
						(xy -0.13716 -0.82804) (xy -0.1524 -0.8001) (xy -0.16256 -0.76835) (xy -0.1651 -0.7366) (xy -0.1651 -0.11938)
						(xy -0.17272 -0.11176) (xy -0.19812 -0.0762) (xy -0.2032 -0.06604) (xy -0.20701 -0.05715) (xy -0.21209 -0.04699)
						(xy -0.2159 -0.03683) (xy -0.21844 -0.02667) (xy -0.22225 -0.01524) (xy -0.22352 -0.00508) (xy -0.22606 0.00508)
						(xy -0.22733 0.01651) (xy -0.22733 0.02667) (xy -0.2286 0.0381) (xy -0.22733 0.04953) (xy -0.22733 0.05969)
						(xy -0.22606 0.07112) (xy -0.22352 0.08128) (xy -0.22225 0.09144) (xy -0.21844 0.10287) (xy -0.2159 0.11303)
						(xy -0.21209 0.12319) (xy -0.20701 0.13335) (xy -0.2032 0.14224) (xy -0.19812 0.1524) (xy -0.17272 0.18796)
						(xy -0.1651 0.19558) (xy -0.1651 0.7366) (xy -0.16256 0.76835) (xy -0.1524 0.8001) (xy -0.13716 0.82804)
						(xy -0.11684 0.85344) (xy -0.09144 0.87376) (xy -0.0635 0.889) (xy -0.03175 0.89916) (xy 0 0.9017)
						(xy 0.03175 0.89916) (xy 0.0635 0.889) (xy 0.09144 0.87376) (xy 0.11684 0.85344) (xy 0.13716 0.82804)
						(xy 0.1524 0.8001) (xy 0.16256 0.76835) (xy 0.1651 0.7366) (xy 0.1651 0.19685) (xy 0.17272 0.18923)
						(xy 0.17907 0.18034) (xy 0.18669 0.17145) (xy 0.19177 0.16256) (xy 0.19812 0.15367) (xy 0.20828 0.13335)
						(xy 0.21971 0.10287) (xy 0.22225 0.09271) (xy 0.22479 0.08128) (xy 0.22606 0.07112) (xy 0.2286 0.05969)
						(xy 0.2286 0.01651) (xy 0.22606 0.00508) (xy 0.22479 -0.00508) (xy 0.22225 -0.01651) (xy 0.21971 -0.02667)
						(xy 0.20828 -0.05715) (xy 0.19812 -0.07747) (xy 0.19177 -0.08636) (xy 0.18669 -0.09525) (xy 0.17907 -0.10414)
						(xy 0.17272 -0.11303) (xy 0.1651 -0.12065) (xy 0.1651 -0.7366) (xy 0.16256 -0.76835) (xy 0.1524 -0.8001)
						(xy 0.13716 -0.82804) (xy 0.11684 -0.85344) (xy 0.09144 -0.87376) (xy 0.0635 -0.889) (xy 0.03175 -0.89916)
					)
					(width 0)
					(fill yes)
				)
			)
		)
		(pad "125" smd custom
			(at 7.949946 -4.100068 180)
			(size 0.1143 0.1143)
			(layers "B.Cu" "B.Mask" "B.Paste")
			(net "M_B_CAS#")
			(options
				(clearance outline)
				(anchor circle)
			)
			(primitives
				(gr_poly
					(pts
						(xy 0 -0.9017) (xy -0.03175 -0.89916) (xy -0.0635 -0.889) (xy -0.09144 -0.87376) (xy -0.11684 -0.85344)
						(xy -0.13716 -0.82804) (xy -0.1524 -0.8001) (xy -0.16256 -0.76835) (xy -0.1651 -0.7366) (xy -0.1651 -0.44958)
						(xy -0.17272 -0.44196) (xy -0.19812 -0.4064) (xy -0.2032 -0.39624) (xy -0.20701 -0.38735) (xy -0.21209 -0.37719)
						(xy -0.2159 -0.36703) (xy -0.21844 -0.35687) (xy -0.22225 -0.34544) (xy -0.22352 -0.33528) (xy -0.22606 -0.32512)
						(xy -0.22733 -0.31369) (xy -0.22733 -0.30353) (xy -0.2286 -0.2921) (xy -0.22733 -0.28067) (xy -0.22733 -0.27051)
						(xy -0.22606 -0.25908) (xy -0.22352 -0.24892) (xy -0.22225 -0.23876) (xy -0.21844 -0.22733) (xy -0.2159 -0.21717)
						(xy -0.21209 -0.20701) (xy -0.20701 -0.19685) (xy -0.2032 -0.18796) (xy -0.19812 -0.1778) (xy -0.17272 -0.14224)
						(xy -0.1651 -0.13462) (xy -0.1651 0.7366) (xy -0.16256 0.76835) (xy -0.1524 0.8001) (xy -0.13716 0.82804)
						(xy -0.11684 0.85344) (xy -0.09144 0.87376) (xy -0.0635 0.889) (xy -0.03175 0.89916) (xy 0 0.9017)
						(xy 0.03175 0.89916) (xy 0.0635 0.889) (xy 0.09144 0.87376) (xy 0.11684 0.85344) (xy 0.13716 0.82804)
						(xy 0.1524 0.8001) (xy 0.16256 0.76835) (xy 0.1651 0.7366) (xy 0.1651 -0.13462) (xy 0.17272 -0.14224)
						(xy 0.19812 -0.1778) (xy 0.2032 -0.18796) (xy 0.20701 -0.19685) (xy 0.21209 -0.20701) (xy 0.2159 -0.21717)
						(xy 0.21844 -0.22733) (xy 0.22225 -0.23876) (xy 0.22352 -0.24892) (xy 0.22606 -0.25908) (xy 0.22733 -0.27051)
						(xy 0.22733 -0.28067) (xy 0.2286 -0.2921) (xy 0.22733 -0.30353) (xy 0.22733 -0.31369) (xy 0.22606 -0.32512)
						(xy 0.22352 -0.33528) (xy 0.22225 -0.34544) (xy 0.21844 -0.35687) (xy 0.2159 -0.36703) (xy 0.21209 -0.37719)
						(xy 0.20701 -0.38735) (xy 0.2032 -0.39624) (xy 0.19812 -0.4064) (xy 0.17272 -0.44196) (xy 0.1651 -0.44958)
						(xy 0.1651 -0.7366) (xy 0.16256 -0.76835) (xy 0.1524 -0.8001) (xy 0.13716 -0.82804) (xy 0.11684 -0.85344)
						(xy 0.09144 -0.87376) (xy 0.0635 -0.889) (xy 0.03175 -0.89916)
					)
					(width 0)
					(fill yes)
				)
			)
		)
		(pad "126" smd custom
			(at 8.24992 4.100068 180)
			(size 0.1143 0.1143)
			(layers "B.Cu" "B.Mask" "B.Paste")
			(net "M_B_ODT0")
			(options
				(clearance outline)
				(anchor circle)
			)
			(primitives
				(gr_poly
					(pts
						(xy 0 -0.9017) (xy -0.03175 -0.89916) (xy -0.0635 -0.889) (xy -0.09144 -0.87376) (xy -0.11684 -0.85344)
						(xy -0.13716 -0.82804) (xy -0.1524 -0.8001) (xy -0.16256 -0.76835) (xy -0.1651 -0.7366) (xy -0.1651 0.13462)
						(xy -0.17272 0.14224) (xy -0.19812 0.1778) (xy -0.2032 0.18796) (xy -0.20701 0.19685) (xy -0.21209 0.20701)
						(xy -0.2159 0.21717) (xy -0.21844 0.22733) (xy -0.22225 0.23876) (xy -0.22352 0.24892) (xy -0.22606 0.25908)
						(xy -0.22733 0.27051) (xy -0.22733 0.28067) (xy -0.2286 0.2921) (xy -0.22733 0.30353) (xy -0.22733 0.31369)
						(xy -0.22606 0.32512) (xy -0.22352 0.33528) (xy -0.22225 0.34544) (xy -0.21844 0.35687) (xy -0.2159 0.36703)
						(xy -0.21209 0.37719) (xy -0.20701 0.38735) (xy -0.2032 0.39624) (xy -0.19812 0.4064) (xy -0.17272 0.44196)
						(xy -0.1651 0.44958) (xy -0.1651 0.7366) (xy -0.16256 0.76835) (xy -0.1524 0.8001) (xy -0.13716 0.82804)
						(xy -0.11684 0.85344) (xy -0.09144 0.87376) (xy -0.0635 0.889) (xy -0.03175 0.89916) (xy 0 0.9017)
						(xy 0.03175 0.89916) (xy 0.0635 0.889) (xy 0.09144 0.87376) (xy 0.11684 0.85344) (xy 0.13716 0.82804)
						(xy 0.1524 0.8001) (xy 0.16256 0.76835) (xy 0.1651 0.7366) (xy 0.1651 0.44958) (xy 0.17272 0.44196)
						(xy 0.19812 0.4064) (xy 0.2032 0.39624) (xy 0.20701 0.38735) (xy 0.21209 0.37719) (xy 0.2159 0.36703)
						(xy 0.21844 0.35687) (xy 0.22225 0.34544) (xy 0.22352 0.33528) (xy 0.22606 0.32512) (xy 0.22733 0.31369)
						(xy 0.22733 0.30353) (xy 0.2286 0.2921) (xy 0.22733 0.28067) (xy 0.22733 0.27051) (xy 0.22606 0.25908)
						(xy 0.22352 0.24892) (xy 0.22225 0.23876) (xy 0.21844 0.22733) (xy 0.2159 0.21717) (xy 0.21209 0.20701)
						(xy 0.20701 0.19685) (xy 0.2032 0.18796) (xy 0.19812 0.1778) (xy 0.17272 0.14224) (xy 0.1651 0.13462)
						(xy 0.1651 -0.7366) (xy 0.16256 -0.76835) (xy 0.1524 -0.8001) (xy 0.13716 -0.82804) (xy 0.11684 -0.85344)
						(xy 0.09144 -0.87376) (xy 0.0635 -0.889) (xy 0.03175 -0.89916)
					)
					(width 0)
					(fill yes)
				)
			)
		)
		(pad "127" smd custom
			(at 8.549894 -4.100068 180)
			(size 0.1143 0.1143)
			(layers "B.Cu" "B.Mask" "B.Paste")
			(net "M_B_CS_N0")
			(options
				(clearance outline)
				(anchor circle)
			)
			(primitives
				(gr_poly
					(pts
						(xy 0 -0.9017) (xy -0.03175 -0.89916) (xy -0.0635 -0.889) (xy -0.09144 -0.87376) (xy -0.11684 -0.85344)
						(xy -0.13716 -0.82804) (xy -0.1524 -0.8001) (xy -0.16256 -0.76835) (xy -0.1651 -0.7366) (xy -0.1651 -0.19685)
						(xy -0.17272 -0.18923) (xy -0.17907 -0.18034) (xy -0.18669 -0.17145) (xy -0.19177 -0.16256) (xy -0.19812 -0.15367)
						(xy -0.20828 -0.13335) (xy -0.21971 -0.10287) (xy -0.22225 -0.09271) (xy -0.22479 -0.08128) (xy -0.22606 -0.07112)
						(xy -0.2286 -0.05969) (xy -0.2286 -0.01651) (xy -0.22606 -0.00508) (xy -0.22479 0.00508) (xy -0.22225 0.01651)
						(xy -0.21971 0.02667) (xy -0.20828 0.05715) (xy -0.19812 0.07747) (xy -0.19177 0.08636) (xy -0.18669 0.09525)
						(xy -0.17907 0.10414) (xy -0.17272 0.11303) (xy -0.1651 0.12065) (xy -0.1651 0.7366) (xy -0.16256 0.76835)
						(xy -0.1524 0.8001) (xy -0.13716 0.82804) (xy -0.11684 0.85344) (xy -0.09144 0.87376) (xy -0.0635 0.889)
						(xy -0.03175 0.89916) (xy 0 0.9017) (xy 0.03175 0.89916) (xy 0.0635 0.889) (xy 0.09144 0.87376)
						(xy 0.11684 0.85344) (xy 0.13716 0.82804) (xy 0.1524 0.8001) (xy 0.16256 0.76835) (xy 0.1651 0.7366)
						(xy 0.1651 0.11938) (xy 0.17272 0.11176) (xy 0.19812 0.0762) (xy 0.2032 0.06604) (xy 0.20701 0.05715)
						(xy 0.21209 0.04699) (xy 0.2159 0.03683) (xy 0.21844 0.02667) (xy 0.22225 0.01524) (xy 0.22352 0.00508)
						(xy 0.22606 -0.00508) (xy 0.22733 -0.01651) (xy 0.22733 -0.02667) (xy 0.2286 -0.0381) (xy 0.22733 -0.04953)
						(xy 0.22733 -0.05969) (xy 0.22606 -0.07112) (xy 0.22352 -0.08128) (xy 0.22225 -0.09144) (xy 0.21844 -0.10287)
						(xy 0.2159 -0.11303) (xy 0.21209 -0.12319) (xy 0.20701 -0.13335) (xy 0.2032 -0.14224) (xy 0.19812 -0.1524)
						(xy 0.17272 -0.18796) (xy 0.1651 -0.19558) (xy 0.1651 -0.7366) (xy 0.16256 -0.76835) (xy 0.1524 -0.8001)
						(xy 0.13716 -0.82804) (xy 0.11684 -0.85344) (xy 0.09144 -0.87376) (xy 0.0635 -0.889) (xy 0.03175 -0.89916)
					)
					(width 0)
					(fill yes)
				)
			)
		)
		(pad "128" smd custom
			(at 8.850122 4.100068 180)
			(size 0.1143 0.1143)
			(layers "B.Cu" "B.Mask" "B.Paste")
			(net "M_B_ODT1")
			(options
				(clearance outline)
				(anchor circle)
			)
			(primitives
				(gr_poly
					(pts
						(xy 0 -0.9017) (xy -0.03175 -0.89916) (xy -0.0635 -0.889) (xy -0.09144 -0.87376) (xy -0.11684 -0.85344)
						(xy -0.13716 -0.82804) (xy -0.1524 -0.8001) (xy -0.16256 -0.76835) (xy -0.1651 -0.7366) (xy -0.1651 -0.11938)
						(xy -0.17272 -0.11176) (xy -0.19812 -0.0762) (xy -0.2032 -0.06604) (xy -0.20701 -0.05715) (xy -0.21209 -0.04699)
						(xy -0.2159 -0.03683) (xy -0.21844 -0.02667) (xy -0.22225 -0.01524) (xy -0.22352 -0.00508) (xy -0.22606 0.00508)
						(xy -0.22733 0.01651) (xy -0.22733 0.02667) (xy -0.2286 0.0381) (xy -0.22733 0.04953) (xy -0.22733 0.05969)
						(xy -0.22606 0.07112) (xy -0.22352 0.08128) (xy -0.22225 0.09144) (xy -0.21844 0.10287) (xy -0.2159 0.11303)
						(xy -0.21209 0.12319) (xy -0.20701 0.13335) (xy -0.2032 0.14224) (xy -0.19812 0.1524) (xy -0.17272 0.18796)
						(xy -0.1651 0.19558) (xy -0.1651 0.7366) (xy -0.16256 0.76835) (xy -0.1524 0.8001) (xy -0.13716 0.82804)
						(xy -0.11684 0.85344) (xy -0.09144 0.87376) (xy -0.0635 0.889) (xy -0.03175 0.89916) (xy 0 0.9017)
						(xy 0.03175 0.89916) (xy 0.0635 0.889) (xy 0.09144 0.87376) (xy 0.11684 0.85344) (xy 0.13716 0.82804)
						(xy 0.1524 0.8001) (xy 0.16256 0.76835) (xy 0.1651 0.7366) (xy 0.1651 0.19685) (xy 0.17272 0.18923)
						(xy 0.17907 0.18034) (xy 0.18669 0.17145) (xy 0.19177 0.16256) (xy 0.19812 0.15367) (xy 0.20828 0.13335)
						(xy 0.21971 0.10287) (xy 0.22225 0.09271) (xy 0.22479 0.08128) (xy 0.22606 0.07112) (xy 0.2286 0.05969)
						(xy 0.2286 0.01651) (xy 0.22606 0.00508) (xy 0.22479 -0.00508) (xy 0.22225 -0.01651) (xy 0.21971 -0.02667)
						(xy 0.20828 -0.05715) (xy 0.19812 -0.07747) (xy 0.19177 -0.08636) (xy 0.18669 -0.09525) (xy 0.17907 -0.10414)
						(xy 0.17272 -0.11303) (xy 0.1651 -0.12065) (xy 0.1651 -0.7366) (xy 0.16256 -0.76835) (xy 0.1524 -0.8001)
						(xy 0.13716 -0.82804) (xy 0.11684 -0.85344) (xy 0.09144 -0.87376) (xy 0.0635 -0.889) (xy 0.03175 -0.89916)
					)
					(width 0)
					(fill yes)
				)
			)
		)
		(pad "129" smd custom
			(at 9.150096 -4.100068 180)
			(size 0.1143 0.1143)
			(layers "B.Cu" "B.Mask" "B.Paste")
			(net "M_B_CS_N1")
			(options
				(clearance outline)
				(anchor circle)
			)
			(primitives
				(gr_poly
					(pts
						(xy 0 -0.9017) (xy -0.03175 -0.89916) (xy -0.0635 -0.889) (xy -0.09144 -0.87376) (xy -0.11684 -0.85344)
						(xy -0.13716 -0.82804) (xy -0.1524 -0.8001) (xy -0.16256 -0.76835) (xy -0.1651 -0.7366) (xy -0.1651 -0.44958)
						(xy -0.17272 -0.44196) (xy -0.19812 -0.4064) (xy -0.2032 -0.39624) (xy -0.20701 -0.38735) (xy -0.21209 -0.37719)
						(xy -0.2159 -0.36703) (xy -0.21844 -0.35687) (xy -0.22225 -0.34544) (xy -0.22352 -0.33528) (xy -0.22606 -0.32512)
						(xy -0.22733 -0.31369) (xy -0.22733 -0.30353) (xy -0.2286 -0.2921) (xy -0.22733 -0.28067) (xy -0.22733 -0.27051)
						(xy -0.22606 -0.25908) (xy -0.22352 -0.24892) (xy -0.22225 -0.23876) (xy -0.21844 -0.22733) (xy -0.2159 -0.21717)
						(xy -0.21209 -0.20701) (xy -0.20701 -0.19685) (xy -0.2032 -0.18796) (xy -0.19812 -0.1778) (xy -0.17272 -0.14224)
						(xy -0.1651 -0.13462) (xy -0.1651 0.7366) (xy -0.16256 0.76835) (xy -0.1524 0.8001) (xy -0.13716 0.82804)
						(xy -0.11684 0.85344) (xy -0.09144 0.87376) (xy -0.0635 0.889) (xy -0.03175 0.89916) (xy 0 0.9017)
						(xy 0.03175 0.89916) (xy 0.0635 0.889) (xy 0.09144 0.87376) (xy 0.11684 0.85344) (xy 0.13716 0.82804)
						(xy 0.1524 0.8001) (xy 0.16256 0.76835) (xy 0.1651 0.7366) (xy 0.1651 -0.13462) (xy 0.17272 -0.14224)
						(xy 0.19812 -0.1778) (xy 0.2032 -0.18796) (xy 0.20701 -0.19685) (xy 0.21209 -0.20701) (xy 0.2159 -0.21717)
						(xy 0.21844 -0.22733) (xy 0.22225 -0.23876) (xy 0.22352 -0.24892) (xy 0.22606 -0.25908) (xy 0.22733 -0.27051)
						(xy 0.22733 -0.28067) (xy 0.2286 -0.2921) (xy 0.22733 -0.30353) (xy 0.22733 -0.31369) (xy 0.22606 -0.32512)
						(xy 0.22352 -0.33528) (xy 0.22225 -0.34544) (xy 0.21844 -0.35687) (xy 0.2159 -0.36703) (xy 0.21209 -0.37719)
						(xy 0.20701 -0.38735) (xy 0.2032 -0.39624) (xy 0.19812 -0.4064) (xy 0.17272 -0.44196) (xy 0.1651 -0.44958)
						(xy 0.1651 -0.7366) (xy 0.16256 -0.76835) (xy 0.1524 -0.8001) (xy 0.13716 -0.82804) (xy 0.11684 -0.85344)
						(xy 0.09144 -0.87376) (xy 0.0635 -0.889) (xy 0.03175 -0.89916)
					)
					(width 0)
					(fill yes)
				)
			)
		)
		(pad "130" smd custom
			(at 9.45007 4.100068 180)
			(size 0.1143 0.1143)
			(layers "B.Cu" "B.Mask" "B.Paste")
			(net "M_B_MA13")
			(options
				(clearance outline)
				(anchor circle)
			)
			(primitives
				(gr_poly
					(pts
						(xy 0 -0.9017) (xy -0.03175 -0.89916) (xy -0.0635 -0.889) (xy -0.09144 -0.87376) (xy -0.11684 -0.85344)
						(xy -0.13716 -0.82804) (xy -0.1524 -0.8001) (xy -0.16256 -0.76835) (xy -0.1651 -0.7366) (xy -0.1651 0.13462)
						(xy -0.17272 0.14224) (xy -0.19812 0.1778) (xy -0.2032 0.18796) (xy -0.20701 0.19685) (xy -0.21209 0.20701)
						(xy -0.2159 0.21717) (xy -0.21844 0.22733) (xy -0.22225 0.23876) (xy -0.22352 0.24892) (xy -0.22606 0.25908)
						(xy -0.22733 0.27051) (xy -0.22733 0.28067) (xy -0.2286 0.2921) (xy -0.22733 0.30353) (xy -0.22733 0.31369)
						(xy -0.22606 0.32512) (xy -0.22352 0.33528) (xy -0.22225 0.34544) (xy -0.21844 0.35687) (xy -0.2159 0.36703)
						(xy -0.21209 0.37719) (xy -0.20701 0.38735) (xy -0.2032 0.39624) (xy -0.19812 0.4064) (xy -0.17272 0.44196)
						(xy -0.1651 0.44958) (xy -0.1651 0.7366) (xy -0.16256 0.76835) (xy -0.1524 0.8001) (xy -0.13716 0.82804)
						(xy -0.11684 0.85344) (xy -0.09144 0.87376) (xy -0.0635 0.889) (xy -0.03175 0.89916) (xy 0 0.9017)
						(xy 0.03175 0.89916) (xy 0.0635 0.889) (xy 0.09144 0.87376) (xy 0.11684 0.85344) (xy 0.13716 0.82804)
						(xy 0.1524 0.8001) (xy 0.16256 0.76835) (xy 0.1651 0.7366) (xy 0.1651 0.44958) (xy 0.17272 0.44196)
						(xy 0.19812 0.4064) (xy 0.2032 0.39624) (xy 0.20701 0.38735) (xy 0.21209 0.37719) (xy 0.2159 0.36703)
						(xy 0.21844 0.35687) (xy 0.22225 0.34544) (xy 0.22352 0.33528) (xy 0.22606 0.32512) (xy 0.22733 0.31369)
						(xy 0.22733 0.30353) (xy 0.2286 0.2921) (xy 0.22733 0.28067) (xy 0.22733 0.27051) (xy 0.22606 0.25908)
						(xy 0.22352 0.24892) (xy 0.22225 0.23876) (xy 0.21844 0.22733) (xy 0.2159 0.21717) (xy 0.21209 0.20701)
						(xy 0.20701 0.19685) (xy 0.2032 0.18796) (xy 0.19812 0.1778) (xy 0.17272 0.14224) (xy 0.1651 0.13462)
						(xy 0.1651 -0.7366) (xy 0.16256 -0.76835) (xy 0.1524 -0.8001) (xy 0.13716 -0.82804) (xy 0.11684 -0.85344)
						(xy 0.09144 -0.87376) (xy 0.0635 -0.889) (xy 0.03175 -0.89916)
					)
					(width 0)
					(fill yes)
				)
			)
		)
		(pad "131" smd custom
			(at 9.750044 -4.100068 180)
			(size 0.1143 0.1143)
			(layers "B.Cu" "B.Mask" "B.Paste")
			(net "PV_VDDR")
			(options
				(clearance outline)
				(anchor circle)
			)
			(primitives
				(gr_poly
					(pts
						(xy 0 -0.9017) (xy -0.03175 -0.89916) (xy -0.0635 -0.889) (xy -0.09144 -0.87376) (xy -0.11684 -0.85344)
						(xy -0.13716 -0.82804) (xy -0.1524 -0.8001) (xy -0.16256 -0.76835) (xy -0.1651 -0.7366) (xy -0.1651 -0.19685)
						(xy -0.17272 -0.18923) (xy -0.17907 -0.18034) (xy -0.18669 -0.17145) (xy -0.19177 -0.16256) (xy -0.19812 -0.15367)
						(xy -0.20828 -0.13335) (xy -0.21971 -0.10287) (xy -0.22225 -0.09271) (xy -0.22479 -0.08128) (xy -0.22606 -0.07112)
						(xy -0.2286 -0.05969) (xy -0.2286 -0.01651) (xy -0.22606 -0.00508) (xy -0.22479 0.00508) (xy -0.22225 0.01651)
						(xy -0.21971 0.02667) (xy -0.20828 0.05715) (xy -0.19812 0.07747) (xy -0.19177 0.08636) (xy -0.18669 0.09525)
						(xy -0.17907 0.10414) (xy -0.17272 0.11303) (xy -0.1651 0.12065) (xy -0.1651 0.7366) (xy -0.16256 0.76835)
						(xy -0.1524 0.8001) (xy -0.13716 0.82804) (xy -0.11684 0.85344) (xy -0.09144 0.87376) (xy -0.0635 0.889)
						(xy -0.03175 0.89916) (xy 0 0.9017) (xy 0.03175 0.89916) (xy 0.0635 0.889) (xy 0.09144 0.87376)
						(xy 0.11684 0.85344) (xy 0.13716 0.82804) (xy 0.1524 0.8001) (xy 0.16256 0.76835) (xy 0.1651 0.7366)
						(xy 0.1651 0.11938) (xy 0.17272 0.11176) (xy 0.19812 0.0762) (xy 0.2032 0.06604) (xy 0.20701 0.05715)
						(xy 0.21209 0.04699) (xy 0.2159 0.03683) (xy 0.21844 0.02667) (xy 0.22225 0.01524) (xy 0.22352 0.00508)
						(xy 0.22606 -0.00508) (xy 0.22733 -0.01651) (xy 0.22733 -0.02667) (xy 0.2286 -0.0381) (xy 0.22733 -0.04953)
						(xy 0.22733 -0.05969) (xy 0.22606 -0.07112) (xy 0.22352 -0.08128) (xy 0.22225 -0.09144) (xy 0.21844 -0.10287)
						(xy 0.2159 -0.11303) (xy 0.21209 -0.12319) (xy 0.20701 -0.13335) (xy 0.2032 -0.14224) (xy 0.19812 -0.1524)
						(xy 0.17272 -0.18796) (xy 0.1651 -0.19558) (xy 0.1651 -0.7366) (xy 0.16256 -0.76835) (xy 0.1524 -0.8001)
						(xy 0.13716 -0.82804) (xy 0.11684 -0.85344) (xy 0.09144 -0.87376) (xy 0.0635 -0.889) (xy 0.03175 -0.89916)
					)
					(width 0)
					(fill yes)
				)
			)
		)
		(pad "132" smd custom
			(at 10.050018 4.100068 180)
			(size 0.1143 0.1143)
			(layers "B.Cu" "B.Mask" "B.Paste")
			(net "PV_VDDR")
			(options
				(clearance outline)
				(anchor circle)
			)
			(primitives
				(gr_poly
					(pts
						(xy 0 -0.9017) (xy -0.03175 -0.89916) (xy -0.0635 -0.889) (xy -0.09144 -0.87376) (xy -0.11684 -0.85344)
						(xy -0.13716 -0.82804) (xy -0.1524 -0.8001) (xy -0.16256 -0.76835) (xy -0.1651 -0.7366) (xy -0.1651 -0.11938)
						(xy -0.17272 -0.11176) (xy -0.19812 -0.0762) (xy -0.2032 -0.06604) (xy -0.20701 -0.05715) (xy -0.21209 -0.04699)
						(xy -0.2159 -0.03683) (xy -0.21844 -0.02667) (xy -0.22225 -0.01524) (xy -0.22352 -0.00508) (xy -0.22606 0.00508)
						(xy -0.22733 0.01651) (xy -0.22733 0.02667) (xy -0.2286 0.0381) (xy -0.22733 0.04953) (xy -0.22733 0.05969)
						(xy -0.22606 0.07112) (xy -0.22352 0.08128) (xy -0.22225 0.09144) (xy -0.21844 0.10287) (xy -0.2159 0.11303)
						(xy -0.21209 0.12319) (xy -0.20701 0.13335) (xy -0.2032 0.14224) (xy -0.19812 0.1524) (xy -0.17272 0.18796)
						(xy -0.1651 0.19558) (xy -0.1651 0.7366) (xy -0.16256 0.76835) (xy -0.1524 0.8001) (xy -0.13716 0.82804)
						(xy -0.11684 0.85344) (xy -0.09144 0.87376) (xy -0.0635 0.889) (xy -0.03175 0.89916) (xy 0 0.9017)
						(xy 0.03175 0.89916) (xy 0.0635 0.889) (xy 0.09144 0.87376) (xy 0.11684 0.85344) (xy 0.13716 0.82804)
						(xy 0.1524 0.8001) (xy 0.16256 0.76835) (xy 0.1651 0.7366) (xy 0.1651 0.19685) (xy 0.17272 0.18923)
						(xy 0.17907 0.18034) (xy 0.18669 0.17145) (xy 0.19177 0.16256) (xy 0.19812 0.15367) (xy 0.20828 0.13335)
						(xy 0.21971 0.10287) (xy 0.22225 0.09271) (xy 0.22479 0.08128) (xy 0.22606 0.07112) (xy 0.2286 0.05969)
						(xy 0.2286 0.01651) (xy 0.22606 0.00508) (xy 0.22479 -0.00508) (xy 0.22225 -0.01651) (xy 0.21971 -0.02667)
						(xy 0.20828 -0.05715) (xy 0.19812 -0.07747) (xy 0.19177 -0.08636) (xy 0.18669 -0.09525) (xy 0.17907 -0.10414)
						(xy 0.17272 -0.11303) (xy 0.1651 -0.12065) (xy 0.1651 -0.7366) (xy 0.16256 -0.76835) (xy 0.1524 -0.8001)
						(xy 0.13716 -0.82804) (xy 0.11684 -0.85344) (xy 0.09144 -0.87376) (xy 0.0635 -0.889) (xy 0.03175 -0.89916)
					)
					(width 0)
					(fill yes)
				)
			)
		)
		(pad "133" smd custom
			(at 10.349992 -4.100068 180)
			(size 0.1143 0.1143)
			(layers "B.Cu" "B.Mask" "B.Paste")
			(net "M_B_DQ32")
			(options
				(clearance outline)
				(anchor circle)
			)
			(primitives
				(gr_poly
					(pts
						(xy 0 -0.9017) (xy -0.03175 -0.89916) (xy -0.0635 -0.889) (xy -0.09144 -0.87376) (xy -0.11684 -0.85344)
						(xy -0.13716 -0.82804) (xy -0.1524 -0.8001) (xy -0.16256 -0.76835) (xy -0.1651 -0.7366) (xy -0.1651 -0.44958)
						(xy -0.17272 -0.44196) (xy -0.19812 -0.4064) (xy -0.2032 -0.39624) (xy -0.20701 -0.38735) (xy -0.21209 -0.37719)
						(xy -0.2159 -0.36703) (xy -0.21844 -0.35687) (xy -0.22225 -0.34544) (xy -0.22352 -0.33528) (xy -0.22606 -0.32512)
						(xy -0.22733 -0.31369) (xy -0.22733 -0.30353) (xy -0.2286 -0.2921) (xy -0.22733 -0.28067) (xy -0.22733 -0.27051)
						(xy -0.22606 -0.25908) (xy -0.22352 -0.24892) (xy -0.22225 -0.23876) (xy -0.21844 -0.22733) (xy -0.2159 -0.21717)
						(xy -0.21209 -0.20701) (xy -0.20701 -0.19685) (xy -0.2032 -0.18796) (xy -0.19812 -0.1778) (xy -0.17272 -0.14224)
						(xy -0.1651 -0.13462) (xy -0.1651 0.7366) (xy -0.16256 0.76835) (xy -0.1524 0.8001) (xy -0.13716 0.82804)
						(xy -0.11684 0.85344) (xy -0.09144 0.87376) (xy -0.0635 0.889) (xy -0.03175 0.89916) (xy 0 0.9017)
						(xy 0.03175 0.89916) (xy 0.0635 0.889) (xy 0.09144 0.87376) (xy 0.11684 0.85344) (xy 0.13716 0.82804)
						(xy 0.1524 0.8001) (xy 0.16256 0.76835) (xy 0.1651 0.7366) (xy 0.1651 -0.13462) (xy 0.17272 -0.14224)
						(xy 0.19812 -0.1778) (xy 0.2032 -0.18796) (xy 0.20701 -0.19685) (xy 0.21209 -0.20701) (xy 0.2159 -0.21717)
						(xy 0.21844 -0.22733) (xy 0.22225 -0.23876) (xy 0.22352 -0.24892) (xy 0.22606 -0.25908) (xy 0.22733 -0.27051)
						(xy 0.22733 -0.28067) (xy 0.2286 -0.2921) (xy 0.22733 -0.30353) (xy 0.22733 -0.31369) (xy 0.22606 -0.32512)
						(xy 0.22352 -0.33528) (xy 0.22225 -0.34544) (xy 0.21844 -0.35687) (xy 0.2159 -0.36703) (xy 0.21209 -0.37719)
						(xy 0.20701 -0.38735) (xy 0.2032 -0.39624) (xy 0.19812 -0.4064) (xy 0.17272 -0.44196) (xy 0.1651 -0.44958)
						(xy 0.1651 -0.7366) (xy 0.16256 -0.76835) (xy 0.1524 -0.8001) (xy 0.13716 -0.82804) (xy 0.11684 -0.85344)
						(xy 0.09144 -0.87376) (xy 0.0635 -0.889) (xy 0.03175 -0.89916)
					)
					(width 0)
					(fill yes)
				)
			)
		)
		(pad "134" smd custom
			(at 10.649966 4.100068 180)
			(size 0.1143 0.1143)
			(layers "B.Cu" "B.Mask" "B.Paste")
			(net "M_B_DQ36")
			(options
				(clearance outline)
				(anchor circle)
			)
			(primitives
				(gr_poly
					(pts
						(xy 0 -0.9017) (xy -0.03175 -0.89916) (xy -0.0635 -0.889) (xy -0.09144 -0.87376) (xy -0.11684 -0.85344)
						(xy -0.13716 -0.82804) (xy -0.1524 -0.8001) (xy -0.16256 -0.76835) (xy -0.1651 -0.7366) (xy -0.1651 0.13462)
						(xy -0.17272 0.14224) (xy -0.19812 0.1778) (xy -0.2032 0.18796) (xy -0.20701 0.19685) (xy -0.21209 0.20701)
						(xy -0.2159 0.21717) (xy -0.21844 0.22733) (xy -0.22225 0.23876) (xy -0.22352 0.24892) (xy -0.22606 0.25908)
						(xy -0.22733 0.27051) (xy -0.22733 0.28067) (xy -0.2286 0.2921) (xy -0.22733 0.30353) (xy -0.22733 0.31369)
						(xy -0.22606 0.32512) (xy -0.22352 0.33528) (xy -0.22225 0.34544) (xy -0.21844 0.35687) (xy -0.2159 0.36703)
						(xy -0.21209 0.37719) (xy -0.20701 0.38735) (xy -0.2032 0.39624) (xy -0.19812 0.4064) (xy -0.17272 0.44196)
						(xy -0.1651 0.44958) (xy -0.1651 0.7366) (xy -0.16256 0.76835) (xy -0.1524 0.8001) (xy -0.13716 0.82804)
						(xy -0.11684 0.85344) (xy -0.09144 0.87376) (xy -0.0635 0.889) (xy -0.03175 0.89916) (xy 0 0.9017)
						(xy 0.03175 0.89916) (xy 0.0635 0.889) (xy 0.09144 0.87376) (xy 0.11684 0.85344) (xy 0.13716 0.82804)
						(xy 0.1524 0.8001) (xy 0.16256 0.76835) (xy 0.1651 0.7366) (xy 0.1651 0.44958) (xy 0.17272 0.44196)
						(xy 0.19812 0.4064) (xy 0.2032 0.39624) (xy 0.20701 0.38735) (xy 0.21209 0.37719) (xy 0.2159 0.36703)
						(xy 0.21844 0.35687) (xy 0.22225 0.34544) (xy 0.22352 0.33528) (xy 0.22606 0.32512) (xy 0.22733 0.31369)
						(xy 0.22733 0.30353) (xy 0.2286 0.2921) (xy 0.22733 0.28067) (xy 0.22733 0.27051) (xy 0.22606 0.25908)
						(xy 0.22352 0.24892) (xy 0.22225 0.23876) (xy 0.21844 0.22733) (xy 0.2159 0.21717) (xy 0.21209 0.20701)
						(xy 0.20701 0.19685) (xy 0.2032 0.18796) (xy 0.19812 0.1778) (xy 0.17272 0.14224) (xy 0.1651 0.13462)
						(xy 0.1651 -0.7366) (xy 0.16256 -0.76835) (xy 0.1524 -0.8001) (xy 0.13716 -0.82804) (xy 0.11684 -0.85344)
						(xy 0.09144 -0.87376) (xy 0.0635 -0.889) (xy 0.03175 -0.89916)
					)
					(width 0)
					(fill yes)
				)
			)
		)
		(pad "135" smd custom
			(at 10.94994 -4.100068 180)
			(size 0.1143 0.1143)
			(layers "B.Cu" "B.Mask" "B.Paste")
			(net "M_B_DQ33")
			(options
				(clearance outline)
				(anchor circle)
			)
			(primitives
				(gr_poly
					(pts
						(xy 0 -0.9017) (xy -0.03175 -0.89916) (xy -0.0635 -0.889) (xy -0.09144 -0.87376) (xy -0.11684 -0.85344)
						(xy -0.13716 -0.82804) (xy -0.1524 -0.8001) (xy -0.16256 -0.76835) (xy -0.1651 -0.7366) (xy -0.1651 -0.19685)
						(xy -0.17272 -0.18923) (xy -0.17907 -0.18034) (xy -0.18669 -0.17145) (xy -0.19177 -0.16256) (xy -0.19812 -0.15367)
						(xy -0.20828 -0.13335) (xy -0.21971 -0.10287) (xy -0.22225 -0.09271) (xy -0.22479 -0.08128) (xy -0.22606 -0.07112)
						(xy -0.2286 -0.05969) (xy -0.2286 -0.01651) (xy -0.22606 -0.00508) (xy -0.22479 0.00508) (xy -0.22225 0.01651)
						(xy -0.21971 0.02667) (xy -0.20828 0.05715) (xy -0.19812 0.07747) (xy -0.19177 0.08636) (xy -0.18669 0.09525)
						(xy -0.17907 0.10414) (xy -0.17272 0.11303) (xy -0.1651 0.12065) (xy -0.1651 0.7366) (xy -0.16256 0.76835)
						(xy -0.1524 0.8001) (xy -0.13716 0.82804) (xy -0.11684 0.85344) (xy -0.09144 0.87376) (xy -0.0635 0.889)
						(xy -0.03175 0.89916) (xy 0 0.9017) (xy 0.03175 0.89916) (xy 0.0635 0.889) (xy 0.09144 0.87376)
						(xy 0.11684 0.85344) (xy 0.13716 0.82804) (xy 0.1524 0.8001) (xy 0.16256 0.76835) (xy 0.1651 0.7366)
						(xy 0.1651 0.11938) (xy 0.17272 0.11176) (xy 0.19812 0.0762) (xy 0.2032 0.06604) (xy 0.20701 0.05715)
						(xy 0.21209 0.04699) (xy 0.2159 0.03683) (xy 0.21844 0.02667) (xy 0.22225 0.01524) (xy 0.22352 0.00508)
						(xy 0.22606 -0.00508) (xy 0.22733 -0.01651) (xy 0.22733 -0.02667) (xy 0.2286 -0.0381) (xy 0.22733 -0.04953)
						(xy 0.22733 -0.05969) (xy 0.22606 -0.07112) (xy 0.22352 -0.08128) (xy 0.22225 -0.09144) (xy 0.21844 -0.10287)
						(xy 0.2159 -0.11303) (xy 0.21209 -0.12319) (xy 0.20701 -0.13335) (xy 0.2032 -0.14224) (xy 0.19812 -0.1524)
						(xy 0.17272 -0.18796) (xy 0.1651 -0.19558) (xy 0.1651 -0.7366) (xy 0.16256 -0.76835) (xy 0.1524 -0.8001)
						(xy 0.13716 -0.82804) (xy 0.11684 -0.85344) (xy 0.09144 -0.87376) (xy 0.0635 -0.889) (xy 0.03175 -0.89916)
					)
					(width 0)
					(fill yes)
				)
			)
		)
		(pad "136" smd custom
			(at 11.249914 4.100068 180)
			(size 0.1143 0.1143)
			(layers "B.Cu" "B.Mask" "B.Paste")
			(net "M_B_DQ37")
			(options
				(clearance outline)
				(anchor circle)
			)
			(primitives
				(gr_poly
					(pts
						(xy 0 -0.9017) (xy -0.03175 -0.89916) (xy -0.0635 -0.889) (xy -0.09144 -0.87376) (xy -0.11684 -0.85344)
						(xy -0.13716 -0.82804) (xy -0.1524 -0.8001) (xy -0.16256 -0.76835) (xy -0.1651 -0.7366) (xy -0.1651 -0.11938)
						(xy -0.17272 -0.11176) (xy -0.19812 -0.0762) (xy -0.2032 -0.06604) (xy -0.20701 -0.05715) (xy -0.21209 -0.04699)
						(xy -0.2159 -0.03683) (xy -0.21844 -0.02667) (xy -0.22225 -0.01524) (xy -0.22352 -0.00508) (xy -0.22606 0.00508)
						(xy -0.22733 0.01651) (xy -0.22733 0.02667) (xy -0.2286 0.0381) (xy -0.22733 0.04953) (xy -0.22733 0.05969)
						(xy -0.22606 0.07112) (xy -0.22352 0.08128) (xy -0.22225 0.09144) (xy -0.21844 0.10287) (xy -0.2159 0.11303)
						(xy -0.21209 0.12319) (xy -0.20701 0.13335) (xy -0.2032 0.14224) (xy -0.19812 0.1524) (xy -0.17272 0.18796)
						(xy -0.1651 0.19558) (xy -0.1651 0.7366) (xy -0.16256 0.76835) (xy -0.1524 0.8001) (xy -0.13716 0.82804)
						(xy -0.11684 0.85344) (xy -0.09144 0.87376) (xy -0.0635 0.889) (xy -0.03175 0.89916) (xy 0 0.9017)
						(xy 0.03175 0.89916) (xy 0.0635 0.889) (xy 0.09144 0.87376) (xy 0.11684 0.85344) (xy 0.13716 0.82804)
						(xy 0.1524 0.8001) (xy 0.16256 0.76835) (xy 0.1651 0.7366) (xy 0.1651 0.19685) (xy 0.17272 0.18923)
						(xy 0.17907 0.18034) (xy 0.18669 0.17145) (xy 0.19177 0.16256) (xy 0.19812 0.15367) (xy 0.20828 0.13335)
						(xy 0.21971 0.10287) (xy 0.22225 0.09271) (xy 0.22479 0.08128) (xy 0.22606 0.07112) (xy 0.2286 0.05969)
						(xy 0.2286 0.01651) (xy 0.22606 0.00508) (xy 0.22479 -0.00508) (xy 0.22225 -0.01651) (xy 0.21971 -0.02667)
						(xy 0.20828 -0.05715) (xy 0.19812 -0.07747) (xy 0.19177 -0.08636) (xy 0.18669 -0.09525) (xy 0.17907 -0.10414)
						(xy 0.17272 -0.11303) (xy 0.1651 -0.12065) (xy 0.1651 -0.7366) (xy 0.16256 -0.76835) (xy 0.1524 -0.8001)
						(xy 0.13716 -0.82804) (xy 0.11684 -0.85344) (xy 0.09144 -0.87376) (xy 0.0635 -0.889) (xy 0.03175 -0.89916)
					)
					(width 0)
					(fill yes)
				)
			)
		)
		(pad "137" smd custom
			(at 11.549888 -4.100068 180)
			(size 0.1143 0.1143)
			(layers "B.Cu" "B.Mask" "B.Paste")
			(net "GND")
			(options
				(clearance outline)
				(anchor circle)
			)
			(primitives
				(gr_poly
					(pts
						(xy 0 -0.9017) (xy -0.03175 -0.89916) (xy -0.0635 -0.889) (xy -0.09144 -0.87376) (xy -0.11684 -0.85344)
						(xy -0.13716 -0.82804) (xy -0.1524 -0.8001) (xy -0.16256 -0.76835) (xy -0.1651 -0.7366) (xy -0.1651 -0.44958)
						(xy -0.17272 -0.44196) (xy -0.19812 -0.4064) (xy -0.2032 -0.39624) (xy -0.20701 -0.38735) (xy -0.21209 -0.37719)
						(xy -0.2159 -0.36703) (xy -0.21844 -0.35687) (xy -0.22225 -0.34544) (xy -0.22352 -0.33528) (xy -0.22606 -0.32512)
						(xy -0.22733 -0.31369) (xy -0.22733 -0.30353) (xy -0.2286 -0.2921) (xy -0.22733 -0.28067) (xy -0.22733 -0.27051)
						(xy -0.22606 -0.25908) (xy -0.22352 -0.24892) (xy -0.22225 -0.23876) (xy -0.21844 -0.22733) (xy -0.2159 -0.21717)
						(xy -0.21209 -0.20701) (xy -0.20701 -0.19685) (xy -0.2032 -0.18796) (xy -0.19812 -0.1778) (xy -0.17272 -0.14224)
						(xy -0.1651 -0.13462) (xy -0.1651 0.7366) (xy -0.16256 0.76835) (xy -0.1524 0.8001) (xy -0.13716 0.82804)
						(xy -0.11684 0.85344) (xy -0.09144 0.87376) (xy -0.0635 0.889) (xy -0.03175 0.89916) (xy 0 0.9017)
						(xy 0.03175 0.89916) (xy 0.0635 0.889) (xy 0.09144 0.87376) (xy 0.11684 0.85344) (xy 0.13716 0.82804)
						(xy 0.1524 0.8001) (xy 0.16256 0.76835) (xy 0.1651 0.7366) (xy 0.1651 -0.13462) (xy 0.17272 -0.14224)
						(xy 0.19812 -0.1778) (xy 0.2032 -0.18796) (xy 0.20701 -0.19685) (xy 0.21209 -0.20701) (xy 0.2159 -0.21717)
						(xy 0.21844 -0.22733) (xy 0.22225 -0.23876) (xy 0.22352 -0.24892) (xy 0.22606 -0.25908) (xy 0.22733 -0.27051)
						(xy 0.22733 -0.28067) (xy 0.2286 -0.2921) (xy 0.22733 -0.30353) (xy 0.22733 -0.31369) (xy 0.22606 -0.32512)
						(xy 0.22352 -0.33528) (xy 0.22225 -0.34544) (xy 0.21844 -0.35687) (xy 0.2159 -0.36703) (xy 0.21209 -0.37719)
						(xy 0.20701 -0.38735) (xy 0.2032 -0.39624) (xy 0.19812 -0.4064) (xy 0.17272 -0.44196) (xy 0.1651 -0.44958)
						(xy 0.1651 -0.7366) (xy 0.16256 -0.76835) (xy 0.1524 -0.8001) (xy 0.13716 -0.82804) (xy 0.11684 -0.85344)
						(xy 0.09144 -0.87376) (xy 0.0635 -0.889) (xy 0.03175 -0.89916)
					)
					(width 0)
					(fill yes)
				)
			)
		)
		(pad "138" smd custom
			(at 11.850116 4.100068 180)
			(size 0.1143 0.1143)
			(layers "B.Cu" "B.Mask" "B.Paste")
			(net "GND")
			(options
				(clearance outline)
				(anchor circle)
			)
			(primitives
				(gr_poly
					(pts
						(xy 0 -0.9017) (xy -0.03175 -0.89916) (xy -0.0635 -0.889) (xy -0.09144 -0.87376) (xy -0.11684 -0.85344)
						(xy -0.13716 -0.82804) (xy -0.1524 -0.8001) (xy -0.16256 -0.76835) (xy -0.1651 -0.7366) (xy -0.1651 0.13462)
						(xy -0.17272 0.14224) (xy -0.19812 0.1778) (xy -0.2032 0.18796) (xy -0.20701 0.19685) (xy -0.21209 0.20701)
						(xy -0.2159 0.21717) (xy -0.21844 0.22733) (xy -0.22225 0.23876) (xy -0.22352 0.24892) (xy -0.22606 0.25908)
						(xy -0.22733 0.27051) (xy -0.22733 0.28067) (xy -0.2286 0.2921) (xy -0.22733 0.30353) (xy -0.22733 0.31369)
						(xy -0.22606 0.32512) (xy -0.22352 0.33528) (xy -0.22225 0.34544) (xy -0.21844 0.35687) (xy -0.2159 0.36703)
						(xy -0.21209 0.37719) (xy -0.20701 0.38735) (xy -0.2032 0.39624) (xy -0.19812 0.4064) (xy -0.17272 0.44196)
						(xy -0.1651 0.44958) (xy -0.1651 0.7366) (xy -0.16256 0.76835) (xy -0.1524 0.8001) (xy -0.13716 0.82804)
						(xy -0.11684 0.85344) (xy -0.09144 0.87376) (xy -0.0635 0.889) (xy -0.03175 0.89916) (xy 0 0.9017)
						(xy 0.03175 0.89916) (xy 0.0635 0.889) (xy 0.09144 0.87376) (xy 0.11684 0.85344) (xy 0.13716 0.82804)
						(xy 0.1524 0.8001) (xy 0.16256 0.76835) (xy 0.1651 0.7366) (xy 0.1651 0.44958) (xy 0.17272 0.44196)
						(xy 0.19812 0.4064) (xy 0.2032 0.39624) (xy 0.20701 0.38735) (xy 0.21209 0.37719) (xy 0.2159 0.36703)
						(xy 0.21844 0.35687) (xy 0.22225 0.34544) (xy 0.22352 0.33528) (xy 0.22606 0.32512) (xy 0.22733 0.31369)
						(xy 0.22733 0.30353) (xy 0.2286 0.2921) (xy 0.22733 0.28067) (xy 0.22733 0.27051) (xy 0.22606 0.25908)
						(xy 0.22352 0.24892) (xy 0.22225 0.23876) (xy 0.21844 0.22733) (xy 0.2159 0.21717) (xy 0.21209 0.20701)
						(xy 0.20701 0.19685) (xy 0.2032 0.18796) (xy 0.19812 0.1778) (xy 0.17272 0.14224) (xy 0.1651 0.13462)
						(xy 0.1651 -0.7366) (xy 0.16256 -0.76835) (xy 0.1524 -0.8001) (xy 0.13716 -0.82804) (xy 0.11684 -0.85344)
						(xy 0.09144 -0.87376) (xy 0.0635 -0.889) (xy 0.03175 -0.89916)
					)
					(width 0)
					(fill yes)
				)
			)
		)
		(pad "139" smd custom
			(at 12.15009 -4.100068 180)
			(size 0.1143 0.1143)
			(layers "B.Cu" "B.Mask" "B.Paste")
			(net "M_B_DQS_DN4")
			(options
				(clearance outline)
				(anchor circle)
			)
			(primitives
				(gr_poly
					(pts
						(xy 0 -0.9017) (xy -0.03175 -0.89916) (xy -0.0635 -0.889) (xy -0.09144 -0.87376) (xy -0.11684 -0.85344)
						(xy -0.13716 -0.82804) (xy -0.1524 -0.8001) (xy -0.16256 -0.76835) (xy -0.1651 -0.7366) (xy -0.1651 -0.19685)
						(xy -0.17272 -0.18923) (xy -0.17907 -0.18034) (xy -0.18669 -0.17145) (xy -0.19177 -0.16256) (xy -0.19812 -0.15367)
						(xy -0.20828 -0.13335) (xy -0.21971 -0.10287) (xy -0.22225 -0.09271) (xy -0.22479 -0.08128) (xy -0.22606 -0.07112)
						(xy -0.2286 -0.05969) (xy -0.2286 -0.01651) (xy -0.22606 -0.00508) (xy -0.22479 0.00508) (xy -0.22225 0.01651)
						(xy -0.21971 0.02667) (xy -0.20828 0.05715) (xy -0.19812 0.07747) (xy -0.19177 0.08636) (xy -0.18669 0.09525)
						(xy -0.17907 0.10414) (xy -0.17272 0.11303) (xy -0.1651 0.12065) (xy -0.1651 0.7366) (xy -0.16256 0.76835)
						(xy -0.1524 0.8001) (xy -0.13716 0.82804) (xy -0.11684 0.85344) (xy -0.09144 0.87376) (xy -0.0635 0.889)
						(xy -0.03175 0.89916) (xy 0 0.9017) (xy 0.03175 0.89916) (xy 0.0635 0.889) (xy 0.09144 0.87376)
						(xy 0.11684 0.85344) (xy 0.13716 0.82804) (xy 0.1524 0.8001) (xy 0.16256 0.76835) (xy 0.1651 0.7366)
						(xy 0.1651 0.11938) (xy 0.17272 0.11176) (xy 0.19812 0.0762) (xy 0.2032 0.06604) (xy 0.20701 0.05715)
						(xy 0.21209 0.04699) (xy 0.2159 0.03683) (xy 0.21844 0.02667) (xy 0.22225 0.01524) (xy 0.22352 0.00508)
						(xy 0.22606 -0.00508) (xy 0.22733 -0.01651) (xy 0.22733 -0.02667) (xy 0.2286 -0.0381) (xy 0.22733 -0.04953)
						(xy 0.22733 -0.05969) (xy 0.22606 -0.07112) (xy 0.22352 -0.08128) (xy 0.22225 -0.09144) (xy 0.21844 -0.10287)
						(xy 0.2159 -0.11303) (xy 0.21209 -0.12319) (xy 0.20701 -0.13335) (xy 0.2032 -0.14224) (xy 0.19812 -0.1524)
						(xy 0.17272 -0.18796) (xy 0.1651 -0.19558) (xy 0.1651 -0.7366) (xy 0.16256 -0.76835) (xy 0.1524 -0.8001)
						(xy 0.13716 -0.82804) (xy 0.11684 -0.85344) (xy 0.09144 -0.87376) (xy 0.0635 -0.889) (xy 0.03175 -0.89916)
					)
					(width 0)
					(fill yes)
				)
			)
		)
		(pad "140" smd custom
			(at 12.450064 4.100068 180)
			(size 0.1143 0.1143)
			(layers "B.Cu" "B.Mask" "B.Paste")
			(net "GND")
			(options
				(clearance outline)
				(anchor circle)
			)
			(primitives
				(gr_poly
					(pts
						(xy 0 -0.9017) (xy -0.03175 -0.89916) (xy -0.0635 -0.889) (xy -0.09144 -0.87376) (xy -0.11684 -0.85344)
						(xy -0.13716 -0.82804) (xy -0.1524 -0.8001) (xy -0.16256 -0.76835) (xy -0.1651 -0.7366) (xy -0.1651 -0.11938)
						(xy -0.17272 -0.11176) (xy -0.19812 -0.0762) (xy -0.2032 -0.06604) (xy -0.20701 -0.05715) (xy -0.21209 -0.04699)
						(xy -0.2159 -0.03683) (xy -0.21844 -0.02667) (xy -0.22225 -0.01524) (xy -0.22352 -0.00508) (xy -0.22606 0.00508)
						(xy -0.22733 0.01651) (xy -0.22733 0.02667) (xy -0.2286 0.0381) (xy -0.22733 0.04953) (xy -0.22733 0.05969)
						(xy -0.22606 0.07112) (xy -0.22352 0.08128) (xy -0.22225 0.09144) (xy -0.21844 0.10287) (xy -0.2159 0.11303)
						(xy -0.21209 0.12319) (xy -0.20701 0.13335) (xy -0.2032 0.14224) (xy -0.19812 0.1524) (xy -0.17272 0.18796)
						(xy -0.1651 0.19558) (xy -0.1651 0.7366) (xy -0.16256 0.76835) (xy -0.1524 0.8001) (xy -0.13716 0.82804)
						(xy -0.11684 0.85344) (xy -0.09144 0.87376) (xy -0.0635 0.889) (xy -0.03175 0.89916) (xy 0 0.9017)
						(xy 0.03175 0.89916) (xy 0.0635 0.889) (xy 0.09144 0.87376) (xy 0.11684 0.85344) (xy 0.13716 0.82804)
						(xy 0.1524 0.8001) (xy 0.16256 0.76835) (xy 0.1651 0.7366) (xy 0.1651 0.19685) (xy 0.17272 0.18923)
						(xy 0.17907 0.18034) (xy 0.18669 0.17145) (xy 0.19177 0.16256) (xy 0.19812 0.15367) (xy 0.20828 0.13335)
						(xy 0.21971 0.10287) (xy 0.22225 0.09271) (xy 0.22479 0.08128) (xy 0.22606 0.07112) (xy 0.2286 0.05969)
						(xy 0.2286 0.01651) (xy 0.22606 0.00508) (xy 0.22479 -0.00508) (xy 0.22225 -0.01651) (xy 0.21971 -0.02667)
						(xy 0.20828 -0.05715) (xy 0.19812 -0.07747) (xy 0.19177 -0.08636) (xy 0.18669 -0.09525) (xy 0.17907 -0.10414)
						(xy 0.17272 -0.11303) (xy 0.1651 -0.12065) (xy 0.1651 -0.7366) (xy 0.16256 -0.76835) (xy 0.1524 -0.8001)
						(xy 0.13716 -0.82804) (xy 0.11684 -0.85344) (xy 0.09144 -0.87376) (xy 0.0635 -0.889) (xy 0.03175 -0.89916)
					)
					(width 0)
					(fill yes)
				)
			)
		)
		(pad "141" smd custom
			(at 12.750038 -4.100068 180)
			(size 0.1143 0.1143)
			(layers "B.Cu" "B.Mask" "B.Paste")
			(net "M_B_DQS_DP4")
			(options
				(clearance outline)
				(anchor circle)
			)
			(primitives
				(gr_poly
					(pts
						(xy 0 -0.9017) (xy -0.03175 -0.89916) (xy -0.0635 -0.889) (xy -0.09144 -0.87376) (xy -0.11684 -0.85344)
						(xy -0.13716 -0.82804) (xy -0.1524 -0.8001) (xy -0.16256 -0.76835) (xy -0.1651 -0.7366) (xy -0.1651 -0.44958)
						(xy -0.17272 -0.44196) (xy -0.19812 -0.4064) (xy -0.2032 -0.39624) (xy -0.20701 -0.38735) (xy -0.21209 -0.37719)
						(xy -0.2159 -0.36703) (xy -0.21844 -0.35687) (xy -0.22225 -0.34544) (xy -0.22352 -0.33528) (xy -0.22606 -0.32512)
						(xy -0.22733 -0.31369) (xy -0.22733 -0.30353) (xy -0.2286 -0.2921) (xy -0.22733 -0.28067) (xy -0.22733 -0.27051)
						(xy -0.22606 -0.25908) (xy -0.22352 -0.24892) (xy -0.22225 -0.23876) (xy -0.21844 -0.22733) (xy -0.2159 -0.21717)
						(xy -0.21209 -0.20701) (xy -0.20701 -0.19685) (xy -0.2032 -0.18796) (xy -0.19812 -0.1778) (xy -0.17272 -0.14224)
						(xy -0.1651 -0.13462) (xy -0.1651 0.7366) (xy -0.16256 0.76835) (xy -0.1524 0.8001) (xy -0.13716 0.82804)
						(xy -0.11684 0.85344) (xy -0.09144 0.87376) (xy -0.0635 0.889) (xy -0.03175 0.89916) (xy 0 0.9017)
						(xy 0.03175 0.89916) (xy 0.0635 0.889) (xy 0.09144 0.87376) (xy 0.11684 0.85344) (xy 0.13716 0.82804)
						(xy 0.1524 0.8001) (xy 0.16256 0.76835) (xy 0.1651 0.7366) (xy 0.1651 -0.13462) (xy 0.17272 -0.14224)
						(xy 0.19812 -0.1778) (xy 0.2032 -0.18796) (xy 0.20701 -0.19685) (xy 0.21209 -0.20701) (xy 0.2159 -0.21717)
						(xy 0.21844 -0.22733) (xy 0.22225 -0.23876) (xy 0.22352 -0.24892) (xy 0.22606 -0.25908) (xy 0.22733 -0.27051)
						(xy 0.22733 -0.28067) (xy 0.2286 -0.2921) (xy 0.22733 -0.30353) (xy 0.22733 -0.31369) (xy 0.22606 -0.32512)
						(xy 0.22352 -0.33528) (xy 0.22225 -0.34544) (xy 0.21844 -0.35687) (xy 0.2159 -0.36703) (xy 0.21209 -0.37719)
						(xy 0.20701 -0.38735) (xy 0.2032 -0.39624) (xy 0.19812 -0.4064) (xy 0.17272 -0.44196) (xy 0.1651 -0.44958)
						(xy 0.1651 -0.7366) (xy 0.16256 -0.76835) (xy 0.1524 -0.8001) (xy 0.13716 -0.82804) (xy 0.11684 -0.85344)
						(xy 0.09144 -0.87376) (xy 0.0635 -0.889) (xy 0.03175 -0.89916)
					)
					(width 0)
					(fill yes)
				)
			)
		)
		(pad "142" smd custom
			(at 13.050012 4.100068 180)
			(size 0.1143 0.1143)
			(layers "B.Cu" "B.Mask" "B.Paste")
			(net "M_B_DQ38")
			(options
				(clearance outline)
				(anchor circle)
			)
			(primitives
				(gr_poly
					(pts
						(xy 0 -0.9017) (xy -0.03175 -0.89916) (xy -0.0635 -0.889) (xy -0.09144 -0.87376) (xy -0.11684 -0.85344)
						(xy -0.13716 -0.82804) (xy -0.1524 -0.8001) (xy -0.16256 -0.76835) (xy -0.1651 -0.7366) (xy -0.1651 0.13462)
						(xy -0.17272 0.14224) (xy -0.19812 0.1778) (xy -0.2032 0.18796) (xy -0.20701 0.19685) (xy -0.21209 0.20701)
						(xy -0.2159 0.21717) (xy -0.21844 0.22733) (xy -0.22225 0.23876) (xy -0.22352 0.24892) (xy -0.22606 0.25908)
						(xy -0.22733 0.27051) (xy -0.22733 0.28067) (xy -0.2286 0.2921) (xy -0.22733 0.30353) (xy -0.22733 0.31369)
						(xy -0.22606 0.32512) (xy -0.22352 0.33528) (xy -0.22225 0.34544) (xy -0.21844 0.35687) (xy -0.2159 0.36703)
						(xy -0.21209 0.37719) (xy -0.20701 0.38735) (xy -0.2032 0.39624) (xy -0.19812 0.4064) (xy -0.17272 0.44196)
						(xy -0.1651 0.44958) (xy -0.1651 0.7366) (xy -0.16256 0.76835) (xy -0.1524 0.8001) (xy -0.13716 0.82804)
						(xy -0.11684 0.85344) (xy -0.09144 0.87376) (xy -0.0635 0.889) (xy -0.03175 0.89916) (xy 0 0.9017)
						(xy 0.03175 0.89916) (xy 0.0635 0.889) (xy 0.09144 0.87376) (xy 0.11684 0.85344) (xy 0.13716 0.82804)
						(xy 0.1524 0.8001) (xy 0.16256 0.76835) (xy 0.1651 0.7366) (xy 0.1651 0.44958) (xy 0.17272 0.44196)
						(xy 0.19812 0.4064) (xy 0.2032 0.39624) (xy 0.20701 0.38735) (xy 0.21209 0.37719) (xy 0.2159 0.36703)
						(xy 0.21844 0.35687) (xy 0.22225 0.34544) (xy 0.22352 0.33528) (xy 0.22606 0.32512) (xy 0.22733 0.31369)
						(xy 0.22733 0.30353) (xy 0.2286 0.2921) (xy 0.22733 0.28067) (xy 0.22733 0.27051) (xy 0.22606 0.25908)
						(xy 0.22352 0.24892) (xy 0.22225 0.23876) (xy 0.21844 0.22733) (xy 0.2159 0.21717) (xy 0.21209 0.20701)
						(xy 0.20701 0.19685) (xy 0.2032 0.18796) (xy 0.19812 0.1778) (xy 0.17272 0.14224) (xy 0.1651 0.13462)
						(xy 0.1651 -0.7366) (xy 0.16256 -0.76835) (xy 0.1524 -0.8001) (xy 0.13716 -0.82804) (xy 0.11684 -0.85344)
						(xy 0.09144 -0.87376) (xy 0.0635 -0.889) (xy 0.03175 -0.89916)
					)
					(width 0)
					(fill yes)
				)
			)
		)
		(pad "143" smd custom
			(at 13.349986 -4.100068 180)
			(size 0.1143 0.1143)
			(layers "B.Cu" "B.Mask" "B.Paste")
			(net "GND")
			(options
				(clearance outline)
				(anchor circle)
			)
			(primitives
				(gr_poly
					(pts
						(xy 0 -0.9017) (xy -0.03175 -0.89916) (xy -0.0635 -0.889) (xy -0.09144 -0.87376) (xy -0.11684 -0.85344)
						(xy -0.13716 -0.82804) (xy -0.1524 -0.8001) (xy -0.16256 -0.76835) (xy -0.1651 -0.7366) (xy -0.1651 -0.19685)
						(xy -0.17272 -0.18923) (xy -0.17907 -0.18034) (xy -0.18669 -0.17145) (xy -0.19177 -0.16256) (xy -0.19812 -0.15367)
						(xy -0.20828 -0.13335) (xy -0.21971 -0.10287) (xy -0.22225 -0.09271) (xy -0.22479 -0.08128) (xy -0.22606 -0.07112)
						(xy -0.2286 -0.05969) (xy -0.2286 -0.01651) (xy -0.22606 -0.00508) (xy -0.22479 0.00508) (xy -0.22225 0.01651)
						(xy -0.21971 0.02667) (xy -0.20828 0.05715) (xy -0.19812 0.07747) (xy -0.19177 0.08636) (xy -0.18669 0.09525)
						(xy -0.17907 0.10414) (xy -0.17272 0.11303) (xy -0.1651 0.12065) (xy -0.1651 0.7366) (xy -0.16256 0.76835)
						(xy -0.1524 0.8001) (xy -0.13716 0.82804) (xy -0.11684 0.85344) (xy -0.09144 0.87376) (xy -0.0635 0.889)
						(xy -0.03175 0.89916) (xy 0 0.9017) (xy 0.03175 0.89916) (xy 0.0635 0.889) (xy 0.09144 0.87376)
						(xy 0.11684 0.85344) (xy 0.13716 0.82804) (xy 0.1524 0.8001) (xy 0.16256 0.76835) (xy 0.1651 0.7366)
						(xy 0.1651 0.11938) (xy 0.17272 0.11176) (xy 0.19812 0.0762) (xy 0.2032 0.06604) (xy 0.20701 0.05715)
						(xy 0.21209 0.04699) (xy 0.2159 0.03683) (xy 0.21844 0.02667) (xy 0.22225 0.01524) (xy 0.22352 0.00508)
						(xy 0.22606 -0.00508) (xy 0.22733 -0.01651) (xy 0.22733 -0.02667) (xy 0.2286 -0.0381) (xy 0.22733 -0.04953)
						(xy 0.22733 -0.05969) (xy 0.22606 -0.07112) (xy 0.22352 -0.08128) (xy 0.22225 -0.09144) (xy 0.21844 -0.10287)
						(xy 0.2159 -0.11303) (xy 0.21209 -0.12319) (xy 0.20701 -0.13335) (xy 0.2032 -0.14224) (xy 0.19812 -0.1524)
						(xy 0.17272 -0.18796) (xy 0.1651 -0.19558) (xy 0.1651 -0.7366) (xy 0.16256 -0.76835) (xy 0.1524 -0.8001)
						(xy 0.13716 -0.82804) (xy 0.11684 -0.85344) (xy 0.09144 -0.87376) (xy 0.0635 -0.889) (xy 0.03175 -0.89916)
					)
					(width 0)
					(fill yes)
				)
			)
		)
		(pad "144" smd custom
			(at 13.64996 4.100068 180)
			(size 0.1143 0.1143)
			(layers "B.Cu" "B.Mask" "B.Paste")
			(net "M_B_DQ39")
			(options
				(clearance outline)
				(anchor circle)
			)
			(primitives
				(gr_poly
					(pts
						(xy 0 -0.9017) (xy -0.03175 -0.89916) (xy -0.0635 -0.889) (xy -0.09144 -0.87376) (xy -0.11684 -0.85344)
						(xy -0.13716 -0.82804) (xy -0.1524 -0.8001) (xy -0.16256 -0.76835) (xy -0.1651 -0.7366) (xy -0.1651 -0.11938)
						(xy -0.17272 -0.11176) (xy -0.19812 -0.0762) (xy -0.2032 -0.06604) (xy -0.20701 -0.05715) (xy -0.21209 -0.04699)
						(xy -0.2159 -0.03683) (xy -0.21844 -0.02667) (xy -0.22225 -0.01524) (xy -0.22352 -0.00508) (xy -0.22606 0.00508)
						(xy -0.22733 0.01651) (xy -0.22733 0.02667) (xy -0.2286 0.0381) (xy -0.22733 0.04953) (xy -0.22733 0.05969)
						(xy -0.22606 0.07112) (xy -0.22352 0.08128) (xy -0.22225 0.09144) (xy -0.21844 0.10287) (xy -0.2159 0.11303)
						(xy -0.21209 0.12319) (xy -0.20701 0.13335) (xy -0.2032 0.14224) (xy -0.19812 0.1524) (xy -0.17272 0.18796)
						(xy -0.1651 0.19558) (xy -0.1651 0.7366) (xy -0.16256 0.76835) (xy -0.1524 0.8001) (xy -0.13716 0.82804)
						(xy -0.11684 0.85344) (xy -0.09144 0.87376) (xy -0.0635 0.889) (xy -0.03175 0.89916) (xy 0 0.9017)
						(xy 0.03175 0.89916) (xy 0.0635 0.889) (xy 0.09144 0.87376) (xy 0.11684 0.85344) (xy 0.13716 0.82804)
						(xy 0.1524 0.8001) (xy 0.16256 0.76835) (xy 0.1651 0.7366) (xy 0.1651 0.19685) (xy 0.17272 0.18923)
						(xy 0.17907 0.18034) (xy 0.18669 0.17145) (xy 0.19177 0.16256) (xy 0.19812 0.15367) (xy 0.20828 0.13335)
						(xy 0.21971 0.10287) (xy 0.22225 0.09271) (xy 0.22479 0.08128) (xy 0.22606 0.07112) (xy 0.2286 0.05969)
						(xy 0.2286 0.01651) (xy 0.22606 0.00508) (xy 0.22479 -0.00508) (xy 0.22225 -0.01651) (xy 0.21971 -0.02667)
						(xy 0.20828 -0.05715) (xy 0.19812 -0.07747) (xy 0.19177 -0.08636) (xy 0.18669 -0.09525) (xy 0.17907 -0.10414)
						(xy 0.17272 -0.11303) (xy 0.1651 -0.12065) (xy 0.1651 -0.7366) (xy 0.16256 -0.76835) (xy 0.1524 -0.8001)
						(xy 0.13716 -0.82804) (xy 0.11684 -0.85344) (xy 0.09144 -0.87376) (xy 0.0635 -0.889) (xy 0.03175 -0.89916)
					)
					(width 0)
					(fill yes)
				)
			)
		)
		(pad "145" smd custom
			(at 13.949934 -4.100068 180)
			(size 0.1143 0.1143)
			(layers "B.Cu" "B.Mask" "B.Paste")
			(net "M_B_DQ34")
			(options
				(clearance outline)
				(anchor circle)
			)
			(primitives
				(gr_poly
					(pts
						(xy 0 -0.9017) (xy -0.03175 -0.89916) (xy -0.0635 -0.889) (xy -0.09144 -0.87376) (xy -0.11684 -0.85344)
						(xy -0.13716 -0.82804) (xy -0.1524 -0.8001) (xy -0.16256 -0.76835) (xy -0.1651 -0.7366) (xy -0.1651 -0.44958)
						(xy -0.17272 -0.44196) (xy -0.19812 -0.4064) (xy -0.2032 -0.39624) (xy -0.20701 -0.38735) (xy -0.21209 -0.37719)
						(xy -0.2159 -0.36703) (xy -0.21844 -0.35687) (xy -0.22225 -0.34544) (xy -0.22352 -0.33528) (xy -0.22606 -0.32512)
						(xy -0.22733 -0.31369) (xy -0.22733 -0.30353) (xy -0.2286 -0.2921) (xy -0.22733 -0.28067) (xy -0.22733 -0.27051)
						(xy -0.22606 -0.25908) (xy -0.22352 -0.24892) (xy -0.22225 -0.23876) (xy -0.21844 -0.22733) (xy -0.2159 -0.21717)
						(xy -0.21209 -0.20701) (xy -0.20701 -0.19685) (xy -0.2032 -0.18796) (xy -0.19812 -0.1778) (xy -0.17272 -0.14224)
						(xy -0.1651 -0.13462) (xy -0.1651 0.7366) (xy -0.16256 0.76835) (xy -0.1524 0.8001) (xy -0.13716 0.82804)
						(xy -0.11684 0.85344) (xy -0.09144 0.87376) (xy -0.0635 0.889) (xy -0.03175 0.89916) (xy 0 0.9017)
						(xy 0.03175 0.89916) (xy 0.0635 0.889) (xy 0.09144 0.87376) (xy 0.11684 0.85344) (xy 0.13716 0.82804)
						(xy 0.1524 0.8001) (xy 0.16256 0.76835) (xy 0.1651 0.7366) (xy 0.1651 -0.13462) (xy 0.17272 -0.14224)
						(xy 0.19812 -0.1778) (xy 0.2032 -0.18796) (xy 0.20701 -0.19685) (xy 0.21209 -0.20701) (xy 0.2159 -0.21717)
						(xy 0.21844 -0.22733) (xy 0.22225 -0.23876) (xy 0.22352 -0.24892) (xy 0.22606 -0.25908) (xy 0.22733 -0.27051)
						(xy 0.22733 -0.28067) (xy 0.2286 -0.2921) (xy 0.22733 -0.30353) (xy 0.22733 -0.31369) (xy 0.22606 -0.32512)
						(xy 0.22352 -0.33528) (xy 0.22225 -0.34544) (xy 0.21844 -0.35687) (xy 0.2159 -0.36703) (xy 0.21209 -0.37719)
						(xy 0.20701 -0.38735) (xy 0.2032 -0.39624) (xy 0.19812 -0.4064) (xy 0.17272 -0.44196) (xy 0.1651 -0.44958)
						(xy 0.1651 -0.7366) (xy 0.16256 -0.76835) (xy 0.1524 -0.8001) (xy 0.13716 -0.82804) (xy 0.11684 -0.85344)
						(xy 0.09144 -0.87376) (xy 0.0635 -0.889) (xy 0.03175 -0.89916)
					)
					(width 0)
					(fill yes)
				)
			)
		)
		(pad "146" smd custom
			(at 14.249908 4.100068 180)
			(size 0.1143 0.1143)
			(layers "B.Cu" "B.Mask" "B.Paste")
			(net "GND")
			(options
				(clearance outline)
				(anchor circle)
			)
			(primitives
				(gr_poly
					(pts
						(xy 0 -0.9017) (xy -0.03175 -0.89916) (xy -0.0635 -0.889) (xy -0.09144 -0.87376) (xy -0.11684 -0.85344)
						(xy -0.13716 -0.82804) (xy -0.1524 -0.8001) (xy -0.16256 -0.76835) (xy -0.1651 -0.7366) (xy -0.1651 0.13462)
						(xy -0.17272 0.14224) (xy -0.19812 0.1778) (xy -0.2032 0.18796) (xy -0.20701 0.19685) (xy -0.21209 0.20701)
						(xy -0.2159 0.21717) (xy -0.21844 0.22733) (xy -0.22225 0.23876) (xy -0.22352 0.24892) (xy -0.22606 0.25908)
						(xy -0.22733 0.27051) (xy -0.22733 0.28067) (xy -0.2286 0.2921) (xy -0.22733 0.30353) (xy -0.22733 0.31369)
						(xy -0.22606 0.32512) (xy -0.22352 0.33528) (xy -0.22225 0.34544) (xy -0.21844 0.35687) (xy -0.2159 0.36703)
						(xy -0.21209 0.37719) (xy -0.20701 0.38735) (xy -0.2032 0.39624) (xy -0.19812 0.4064) (xy -0.17272 0.44196)
						(xy -0.1651 0.44958) (xy -0.1651 0.7366) (xy -0.16256 0.76835) (xy -0.1524 0.8001) (xy -0.13716 0.82804)
						(xy -0.11684 0.85344) (xy -0.09144 0.87376) (xy -0.0635 0.889) (xy -0.03175 0.89916) (xy 0 0.9017)
						(xy 0.03175 0.89916) (xy 0.0635 0.889) (xy 0.09144 0.87376) (xy 0.11684 0.85344) (xy 0.13716 0.82804)
						(xy 0.1524 0.8001) (xy 0.16256 0.76835) (xy 0.1651 0.7366) (xy 0.1651 0.44958) (xy 0.17272 0.44196)
						(xy 0.19812 0.4064) (xy 0.2032 0.39624) (xy 0.20701 0.38735) (xy 0.21209 0.37719) (xy 0.2159 0.36703)
						(xy 0.21844 0.35687) (xy 0.22225 0.34544) (xy 0.22352 0.33528) (xy 0.22606 0.32512) (xy 0.22733 0.31369)
						(xy 0.22733 0.30353) (xy 0.2286 0.2921) (xy 0.22733 0.28067) (xy 0.22733 0.27051) (xy 0.22606 0.25908)
						(xy 0.22352 0.24892) (xy 0.22225 0.23876) (xy 0.21844 0.22733) (xy 0.2159 0.21717) (xy 0.21209 0.20701)
						(xy 0.20701 0.19685) (xy 0.2032 0.18796) (xy 0.19812 0.1778) (xy 0.17272 0.14224) (xy 0.1651 0.13462)
						(xy 0.1651 -0.7366) (xy 0.16256 -0.76835) (xy 0.1524 -0.8001) (xy 0.13716 -0.82804) (xy 0.11684 -0.85344)
						(xy 0.09144 -0.87376) (xy 0.0635 -0.889) (xy 0.03175 -0.89916)
					)
					(width 0)
					(fill yes)
				)
			)
		)
		(pad "147" smd custom
			(at 14.549882 -4.100068 180)
			(size 0.1143 0.1143)
			(layers "B.Cu" "B.Mask" "B.Paste")
			(net "M_B_DQ35")
			(options
				(clearance outline)
				(anchor circle)
			)
			(primitives
				(gr_poly
					(pts
						(xy 0 -0.9017) (xy -0.03175 -0.89916) (xy -0.0635 -0.889) (xy -0.09144 -0.87376) (xy -0.11684 -0.85344)
						(xy -0.13716 -0.82804) (xy -0.1524 -0.8001) (xy -0.16256 -0.76835) (xy -0.1651 -0.7366) (xy -0.1651 -0.19685)
						(xy -0.17272 -0.18923) (xy -0.17907 -0.18034) (xy -0.18669 -0.17145) (xy -0.19177 -0.16256) (xy -0.19812 -0.15367)
						(xy -0.20828 -0.13335) (xy -0.21971 -0.10287) (xy -0.22225 -0.09271) (xy -0.22479 -0.08128) (xy -0.22606 -0.07112)
						(xy -0.2286 -0.05969) (xy -0.2286 -0.01651) (xy -0.22606 -0.00508) (xy -0.22479 0.00508) (xy -0.22225 0.01651)
						(xy -0.21971 0.02667) (xy -0.20828 0.05715) (xy -0.19812 0.07747) (xy -0.19177 0.08636) (xy -0.18669 0.09525)
						(xy -0.17907 0.10414) (xy -0.17272 0.11303) (xy -0.1651 0.12065) (xy -0.1651 0.7366) (xy -0.16256 0.76835)
						(xy -0.1524 0.8001) (xy -0.13716 0.82804) (xy -0.11684 0.85344) (xy -0.09144 0.87376) (xy -0.0635 0.889)
						(xy -0.03175 0.89916) (xy 0 0.9017) (xy 0.03175 0.89916) (xy 0.0635 0.889) (xy 0.09144 0.87376)
						(xy 0.11684 0.85344) (xy 0.13716 0.82804) (xy 0.1524 0.8001) (xy 0.16256 0.76835) (xy 0.1651 0.7366)
						(xy 0.1651 0.11938) (xy 0.17272 0.11176) (xy 0.19812 0.0762) (xy 0.2032 0.06604) (xy 0.20701 0.05715)
						(xy 0.21209 0.04699) (xy 0.2159 0.03683) (xy 0.21844 0.02667) (xy 0.22225 0.01524) (xy 0.22352 0.00508)
						(xy 0.22606 -0.00508) (xy 0.22733 -0.01651) (xy 0.22733 -0.02667) (xy 0.2286 -0.0381) (xy 0.22733 -0.04953)
						(xy 0.22733 -0.05969) (xy 0.22606 -0.07112) (xy 0.22352 -0.08128) (xy 0.22225 -0.09144) (xy 0.21844 -0.10287)
						(xy 0.2159 -0.11303) (xy 0.21209 -0.12319) (xy 0.20701 -0.13335) (xy 0.2032 -0.14224) (xy 0.19812 -0.1524)
						(xy 0.17272 -0.18796) (xy 0.1651 -0.19558) (xy 0.1651 -0.7366) (xy 0.16256 -0.76835) (xy 0.1524 -0.8001)
						(xy 0.13716 -0.82804) (xy 0.11684 -0.85344) (xy 0.09144 -0.87376) (xy 0.0635 -0.889) (xy 0.03175 -0.89916)
					)
					(width 0)
					(fill yes)
				)
			)
		)
		(pad "148" smd custom
			(at 14.85011 4.100068 180)
			(size 0.1143 0.1143)
			(layers "B.Cu" "B.Mask" "B.Paste")
			(net "M_B_DQ44")
			(options
				(clearance outline)
				(anchor circle)
			)
			(primitives
				(gr_poly
					(pts
						(xy 0 -0.9017) (xy -0.03175 -0.89916) (xy -0.0635 -0.889) (xy -0.09144 -0.87376) (xy -0.11684 -0.85344)
						(xy -0.13716 -0.82804) (xy -0.1524 -0.8001) (xy -0.16256 -0.76835) (xy -0.1651 -0.7366) (xy -0.1651 -0.11938)
						(xy -0.17272 -0.11176) (xy -0.19812 -0.0762) (xy -0.2032 -0.06604) (xy -0.20701 -0.05715) (xy -0.21209 -0.04699)
						(xy -0.2159 -0.03683) (xy -0.21844 -0.02667) (xy -0.22225 -0.01524) (xy -0.22352 -0.00508) (xy -0.22606 0.00508)
						(xy -0.22733 0.01651) (xy -0.22733 0.02667) (xy -0.2286 0.0381) (xy -0.22733 0.04953) (xy -0.22733 0.05969)
						(xy -0.22606 0.07112) (xy -0.22352 0.08128) (xy -0.22225 0.09144) (xy -0.21844 0.10287) (xy -0.2159 0.11303)
						(xy -0.21209 0.12319) (xy -0.20701 0.13335) (xy -0.2032 0.14224) (xy -0.19812 0.1524) (xy -0.17272 0.18796)
						(xy -0.1651 0.19558) (xy -0.1651 0.7366) (xy -0.16256 0.76835) (xy -0.1524 0.8001) (xy -0.13716 0.82804)
						(xy -0.11684 0.85344) (xy -0.09144 0.87376) (xy -0.0635 0.889) (xy -0.03175 0.89916) (xy 0 0.9017)
						(xy 0.03175 0.89916) (xy 0.0635 0.889) (xy 0.09144 0.87376) (xy 0.11684 0.85344) (xy 0.13716 0.82804)
						(xy 0.1524 0.8001) (xy 0.16256 0.76835) (xy 0.1651 0.7366) (xy 0.1651 0.19685) (xy 0.17272 0.18923)
						(xy 0.17907 0.18034) (xy 0.18669 0.17145) (xy 0.19177 0.16256) (xy 0.19812 0.15367) (xy 0.20828 0.13335)
						(xy 0.21971 0.10287) (xy 0.22225 0.09271) (xy 0.22479 0.08128) (xy 0.22606 0.07112) (xy 0.2286 0.05969)
						(xy 0.2286 0.01651) (xy 0.22606 0.00508) (xy 0.22479 -0.00508) (xy 0.22225 -0.01651) (xy 0.21971 -0.02667)
						(xy 0.20828 -0.05715) (xy 0.19812 -0.07747) (xy 0.19177 -0.08636) (xy 0.18669 -0.09525) (xy 0.17907 -0.10414)
						(xy 0.17272 -0.11303) (xy 0.1651 -0.12065) (xy 0.1651 -0.7366) (xy 0.16256 -0.76835) (xy 0.1524 -0.8001)
						(xy 0.13716 -0.82804) (xy 0.11684 -0.85344) (xy 0.09144 -0.87376) (xy 0.0635 -0.889) (xy 0.03175 -0.89916)
					)
					(width 0)
					(fill yes)
				)
			)
		)
		(pad "149" smd custom
			(at 15.150084 -4.100068 180)
			(size 0.1143 0.1143)
			(layers "B.Cu" "B.Mask" "B.Paste")
			(net "GND")
			(options
				(clearance outline)
				(anchor circle)
			)
			(primitives
				(gr_poly
					(pts
						(xy 0 -0.9017) (xy -0.03175 -0.89916) (xy -0.0635 -0.889) (xy -0.09144 -0.87376) (xy -0.11684 -0.85344)
						(xy -0.13716 -0.82804) (xy -0.1524 -0.8001) (xy -0.16256 -0.76835) (xy -0.1651 -0.7366) (xy -0.1651 -0.44958)
						(xy -0.17272 -0.44196) (xy -0.19812 -0.4064) (xy -0.2032 -0.39624) (xy -0.20701 -0.38735) (xy -0.21209 -0.37719)
						(xy -0.2159 -0.36703) (xy -0.21844 -0.35687) (xy -0.22225 -0.34544) (xy -0.22352 -0.33528) (xy -0.22606 -0.32512)
						(xy -0.22733 -0.31369) (xy -0.22733 -0.30353) (xy -0.2286 -0.2921) (xy -0.22733 -0.28067) (xy -0.22733 -0.27051)
						(xy -0.22606 -0.25908) (xy -0.22352 -0.24892) (xy -0.22225 -0.23876) (xy -0.21844 -0.22733) (xy -0.2159 -0.21717)
						(xy -0.21209 -0.20701) (xy -0.20701 -0.19685) (xy -0.2032 -0.18796) (xy -0.19812 -0.1778) (xy -0.17272 -0.14224)
						(xy -0.1651 -0.13462) (xy -0.1651 0.7366) (xy -0.16256 0.76835) (xy -0.1524 0.8001) (xy -0.13716 0.82804)
						(xy -0.11684 0.85344) (xy -0.09144 0.87376) (xy -0.0635 0.889) (xy -0.03175 0.89916) (xy 0 0.9017)
						(xy 0.03175 0.89916) (xy 0.0635 0.889) (xy 0.09144 0.87376) (xy 0.11684 0.85344) (xy 0.13716 0.82804)
						(xy 0.1524 0.8001) (xy 0.16256 0.76835) (xy 0.1651 0.7366) (xy 0.1651 -0.13462) (xy 0.17272 -0.14224)
						(xy 0.19812 -0.1778) (xy 0.2032 -0.18796) (xy 0.20701 -0.19685) (xy 0.21209 -0.20701) (xy 0.2159 -0.21717)
						(xy 0.21844 -0.22733) (xy 0.22225 -0.23876) (xy 0.22352 -0.24892) (xy 0.22606 -0.25908) (xy 0.22733 -0.27051)
						(xy 0.22733 -0.28067) (xy 0.2286 -0.2921) (xy 0.22733 -0.30353) (xy 0.22733 -0.31369) (xy 0.22606 -0.32512)
						(xy 0.22352 -0.33528) (xy 0.22225 -0.34544) (xy 0.21844 -0.35687) (xy 0.2159 -0.36703) (xy 0.21209 -0.37719)
						(xy 0.20701 -0.38735) (xy 0.2032 -0.39624) (xy 0.19812 -0.4064) (xy 0.17272 -0.44196) (xy 0.1651 -0.44958)
						(xy 0.1651 -0.7366) (xy 0.16256 -0.76835) (xy 0.1524 -0.8001) (xy 0.13716 -0.82804) (xy 0.11684 -0.85344)
						(xy 0.09144 -0.87376) (xy 0.0635 -0.889) (xy 0.03175 -0.89916)
					)
					(width 0)
					(fill yes)
				)
			)
		)
		(pad "150" smd custom
			(at 15.450058 4.100068 180)
			(size 0.1143 0.1143)
			(layers "B.Cu" "B.Mask" "B.Paste")
			(net "M_B_DQ45")
			(options
				(clearance outline)
				(anchor circle)
			)
			(primitives
				(gr_poly
					(pts
						(xy 0 -0.9017) (xy -0.03175 -0.89916) (xy -0.0635 -0.889) (xy -0.09144 -0.87376) (xy -0.11684 -0.85344)
						(xy -0.13716 -0.82804) (xy -0.1524 -0.8001) (xy -0.16256 -0.76835) (xy -0.1651 -0.7366) (xy -0.1651 0.13462)
						(xy -0.17272 0.14224) (xy -0.19812 0.1778) (xy -0.2032 0.18796) (xy -0.20701 0.19685) (xy -0.21209 0.20701)
						(xy -0.2159 0.21717) (xy -0.21844 0.22733) (xy -0.22225 0.23876) (xy -0.22352 0.24892) (xy -0.22606 0.25908)
						(xy -0.22733 0.27051) (xy -0.22733 0.28067) (xy -0.2286 0.2921) (xy -0.22733 0.30353) (xy -0.22733 0.31369)
						(xy -0.22606 0.32512) (xy -0.22352 0.33528) (xy -0.22225 0.34544) (xy -0.21844 0.35687) (xy -0.2159 0.36703)
						(xy -0.21209 0.37719) (xy -0.20701 0.38735) (xy -0.2032 0.39624) (xy -0.19812 0.4064) (xy -0.17272 0.44196)
						(xy -0.1651 0.44958) (xy -0.1651 0.7366) (xy -0.16256 0.76835) (xy -0.1524 0.8001) (xy -0.13716 0.82804)
						(xy -0.11684 0.85344) (xy -0.09144 0.87376) (xy -0.0635 0.889) (xy -0.03175 0.89916) (xy 0 0.9017)
						(xy 0.03175 0.89916) (xy 0.0635 0.889) (xy 0.09144 0.87376) (xy 0.11684 0.85344) (xy 0.13716 0.82804)
						(xy 0.1524 0.8001) (xy 0.16256 0.76835) (xy 0.1651 0.7366) (xy 0.1651 0.44958) (xy 0.17272 0.44196)
						(xy 0.19812 0.4064) (xy 0.2032 0.39624) (xy 0.20701 0.38735) (xy 0.21209 0.37719) (xy 0.2159 0.36703)
						(xy 0.21844 0.35687) (xy 0.22225 0.34544) (xy 0.22352 0.33528) (xy 0.22606 0.32512) (xy 0.22733 0.31369)
						(xy 0.22733 0.30353) (xy 0.2286 0.2921) (xy 0.22733 0.28067) (xy 0.22733 0.27051) (xy 0.22606 0.25908)
						(xy 0.22352 0.24892) (xy 0.22225 0.23876) (xy 0.21844 0.22733) (xy 0.2159 0.21717) (xy 0.21209 0.20701)
						(xy 0.20701 0.19685) (xy 0.2032 0.18796) (xy 0.19812 0.1778) (xy 0.17272 0.14224) (xy 0.1651 0.13462)
						(xy 0.1651 -0.7366) (xy 0.16256 -0.76835) (xy 0.1524 -0.8001) (xy 0.13716 -0.82804) (xy 0.11684 -0.85344)
						(xy 0.09144 -0.87376) (xy 0.0635 -0.889) (xy 0.03175 -0.89916)
					)
					(width 0)
					(fill yes)
				)
			)
		)
		(pad "151" smd custom
			(at 15.750032 -4.100068 180)
			(size 0.1143 0.1143)
			(layers "B.Cu" "B.Mask" "B.Paste")
			(net "M_B_DQ40")
			(options
				(clearance outline)
				(anchor circle)
			)
			(primitives
				(gr_poly
					(pts
						(xy 0 -0.9017) (xy -0.03175 -0.89916) (xy -0.0635 -0.889) (xy -0.09144 -0.87376) (xy -0.11684 -0.85344)
						(xy -0.13716 -0.82804) (xy -0.1524 -0.8001) (xy -0.16256 -0.76835) (xy -0.1651 -0.7366) (xy -0.1651 -0.19685)
						(xy -0.17272 -0.18923) (xy -0.17907 -0.18034) (xy -0.18669 -0.17145) (xy -0.19177 -0.16256) (xy -0.19812 -0.15367)
						(xy -0.20828 -0.13335) (xy -0.21971 -0.10287) (xy -0.22225 -0.09271) (xy -0.22479 -0.08128) (xy -0.22606 -0.07112)
						(xy -0.2286 -0.05969) (xy -0.2286 -0.01651) (xy -0.22606 -0.00508) (xy -0.22479 0.00508) (xy -0.22225 0.01651)
						(xy -0.21971 0.02667) (xy -0.20828 0.05715) (xy -0.19812 0.07747) (xy -0.19177 0.08636) (xy -0.18669 0.09525)
						(xy -0.17907 0.10414) (xy -0.17272 0.11303) (xy -0.1651 0.12065) (xy -0.1651 0.7366) (xy -0.16256 0.76835)
						(xy -0.1524 0.8001) (xy -0.13716 0.82804) (xy -0.11684 0.85344) (xy -0.09144 0.87376) (xy -0.0635 0.889)
						(xy -0.03175 0.89916) (xy 0 0.9017) (xy 0.03175 0.89916) (xy 0.0635 0.889) (xy 0.09144 0.87376)
						(xy 0.11684 0.85344) (xy 0.13716 0.82804) (xy 0.1524 0.8001) (xy 0.16256 0.76835) (xy 0.1651 0.7366)
						(xy 0.1651 0.11938) (xy 0.17272 0.11176) (xy 0.19812 0.0762) (xy 0.2032 0.06604) (xy 0.20701 0.05715)
						(xy 0.21209 0.04699) (xy 0.2159 0.03683) (xy 0.21844 0.02667) (xy 0.22225 0.01524) (xy 0.22352 0.00508)
						(xy 0.22606 -0.00508) (xy 0.22733 -0.01651) (xy 0.22733 -0.02667) (xy 0.2286 -0.0381) (xy 0.22733 -0.04953)
						(xy 0.22733 -0.05969) (xy 0.22606 -0.07112) (xy 0.22352 -0.08128) (xy 0.22225 -0.09144) (xy 0.21844 -0.10287)
						(xy 0.2159 -0.11303) (xy 0.21209 -0.12319) (xy 0.20701 -0.13335) (xy 0.2032 -0.14224) (xy 0.19812 -0.1524)
						(xy 0.17272 -0.18796) (xy 0.1651 -0.19558) (xy 0.1651 -0.7366) (xy 0.16256 -0.76835) (xy 0.1524 -0.8001)
						(xy 0.13716 -0.82804) (xy 0.11684 -0.85344) (xy 0.09144 -0.87376) (xy 0.0635 -0.889) (xy 0.03175 -0.89916)
					)
					(width 0)
					(fill yes)
				)
			)
		)
		(pad "152" smd custom
			(at 16.050006 4.100068 180)
			(size 0.1143 0.1143)
			(layers "B.Cu" "B.Mask" "B.Paste")
			(net "GND")
			(options
				(clearance outline)
				(anchor circle)
			)
			(primitives
				(gr_poly
					(pts
						(xy 0 -0.9017) (xy -0.03175 -0.89916) (xy -0.0635 -0.889) (xy -0.09144 -0.87376) (xy -0.11684 -0.85344)
						(xy -0.13716 -0.82804) (xy -0.1524 -0.8001) (xy -0.16256 -0.76835) (xy -0.1651 -0.7366) (xy -0.1651 -0.11938)
						(xy -0.17272 -0.11176) (xy -0.19812 -0.0762) (xy -0.2032 -0.06604) (xy -0.20701 -0.05715) (xy -0.21209 -0.04699)
						(xy -0.2159 -0.03683) (xy -0.21844 -0.02667) (xy -0.22225 -0.01524) (xy -0.22352 -0.00508) (xy -0.22606 0.00508)
						(xy -0.22733 0.01651) (xy -0.22733 0.02667) (xy -0.2286 0.0381) (xy -0.22733 0.04953) (xy -0.22733 0.05969)
						(xy -0.22606 0.07112) (xy -0.22352 0.08128) (xy -0.22225 0.09144) (xy -0.21844 0.10287) (xy -0.2159 0.11303)
						(xy -0.21209 0.12319) (xy -0.20701 0.13335) (xy -0.2032 0.14224) (xy -0.19812 0.1524) (xy -0.17272 0.18796)
						(xy -0.1651 0.19558) (xy -0.1651 0.7366) (xy -0.16256 0.76835) (xy -0.1524 0.8001) (xy -0.13716 0.82804)
						(xy -0.11684 0.85344) (xy -0.09144 0.87376) (xy -0.0635 0.889) (xy -0.03175 0.89916) (xy 0 0.9017)
						(xy 0.03175 0.89916) (xy 0.0635 0.889) (xy 0.09144 0.87376) (xy 0.11684 0.85344) (xy 0.13716 0.82804)
						(xy 0.1524 0.8001) (xy 0.16256 0.76835) (xy 0.1651 0.7366) (xy 0.1651 0.19685) (xy 0.17272 0.18923)
						(xy 0.17907 0.18034) (xy 0.18669 0.17145) (xy 0.19177 0.16256) (xy 0.19812 0.15367) (xy 0.20828 0.13335)
						(xy 0.21971 0.10287) (xy 0.22225 0.09271) (xy 0.22479 0.08128) (xy 0.22606 0.07112) (xy 0.2286 0.05969)
						(xy 0.2286 0.01651) (xy 0.22606 0.00508) (xy 0.22479 -0.00508) (xy 0.22225 -0.01651) (xy 0.21971 -0.02667)
						(xy 0.20828 -0.05715) (xy 0.19812 -0.07747) (xy 0.19177 -0.08636) (xy 0.18669 -0.09525) (xy 0.17907 -0.10414)
						(xy 0.17272 -0.11303) (xy 0.1651 -0.12065) (xy 0.1651 -0.7366) (xy 0.16256 -0.76835) (xy 0.1524 -0.8001)
						(xy 0.13716 -0.82804) (xy 0.11684 -0.85344) (xy 0.09144 -0.87376) (xy 0.0635 -0.889) (xy 0.03175 -0.89916)
					)
					(width 0)
					(fill yes)
				)
			)
		)
		(pad "153" smd custom
			(at 16.34998 -4.100068 180)
			(size 0.1143 0.1143)
			(layers "B.Cu" "B.Mask" "B.Paste")
			(net "M_B_DQ41")
			(options
				(clearance outline)
				(anchor circle)
			)
			(primitives
				(gr_poly
					(pts
						(xy 0 -0.9017) (xy -0.03175 -0.89916) (xy -0.0635 -0.889) (xy -0.09144 -0.87376) (xy -0.11684 -0.85344)
						(xy -0.13716 -0.82804) (xy -0.1524 -0.8001) (xy -0.16256 -0.76835) (xy -0.1651 -0.7366) (xy -0.1651 -0.44958)
						(xy -0.17272 -0.44196) (xy -0.19812 -0.4064) (xy -0.2032 -0.39624) (xy -0.20701 -0.38735) (xy -0.21209 -0.37719)
						(xy -0.2159 -0.36703) (xy -0.21844 -0.35687) (xy -0.22225 -0.34544) (xy -0.22352 -0.33528) (xy -0.22606 -0.32512)
						(xy -0.22733 -0.31369) (xy -0.22733 -0.30353) (xy -0.2286 -0.2921) (xy -0.22733 -0.28067) (xy -0.22733 -0.27051)
						(xy -0.22606 -0.25908) (xy -0.22352 -0.24892) (xy -0.22225 -0.23876) (xy -0.21844 -0.22733) (xy -0.2159 -0.21717)
						(xy -0.21209 -0.20701) (xy -0.20701 -0.19685) (xy -0.2032 -0.18796) (xy -0.19812 -0.1778) (xy -0.17272 -0.14224)
						(xy -0.1651 -0.13462) (xy -0.1651 0.7366) (xy -0.16256 0.76835) (xy -0.1524 0.8001) (xy -0.13716 0.82804)
						(xy -0.11684 0.85344) (xy -0.09144 0.87376) (xy -0.0635 0.889) (xy -0.03175 0.89916) (xy 0 0.9017)
						(xy 0.03175 0.89916) (xy 0.0635 0.889) (xy 0.09144 0.87376) (xy 0.11684 0.85344) (xy 0.13716 0.82804)
						(xy 0.1524 0.8001) (xy 0.16256 0.76835) (xy 0.1651 0.7366) (xy 0.1651 -0.13462) (xy 0.17272 -0.14224)
						(xy 0.19812 -0.1778) (xy 0.2032 -0.18796) (xy 0.20701 -0.19685) (xy 0.21209 -0.20701) (xy 0.2159 -0.21717)
						(xy 0.21844 -0.22733) (xy 0.22225 -0.23876) (xy 0.22352 -0.24892) (xy 0.22606 -0.25908) (xy 0.22733 -0.27051)
						(xy 0.22733 -0.28067) (xy 0.2286 -0.2921) (xy 0.22733 -0.30353) (xy 0.22733 -0.31369) (xy 0.22606 -0.32512)
						(xy 0.22352 -0.33528) (xy 0.22225 -0.34544) (xy 0.21844 -0.35687) (xy 0.2159 -0.36703) (xy 0.21209 -0.37719)
						(xy 0.20701 -0.38735) (xy 0.2032 -0.39624) (xy 0.19812 -0.4064) (xy 0.17272 -0.44196) (xy 0.1651 -0.44958)
						(xy 0.1651 -0.7366) (xy 0.16256 -0.76835) (xy 0.1524 -0.8001) (xy 0.13716 -0.82804) (xy 0.11684 -0.85344)
						(xy 0.09144 -0.87376) (xy 0.0635 -0.889) (xy 0.03175 -0.89916)
					)
					(width 0)
					(fill yes)
				)
			)
		)
		(pad "154" smd custom
			(at 16.649954 4.100068 180)
			(size 0.1143 0.1143)
			(layers "B.Cu" "B.Mask" "B.Paste")
			(net "M_B_DQS_DN5")
			(options
				(clearance outline)
				(anchor circle)
			)
			(primitives
				(gr_poly
					(pts
						(xy 0 -0.9017) (xy -0.03175 -0.89916) (xy -0.0635 -0.889) (xy -0.09144 -0.87376) (xy -0.11684 -0.85344)
						(xy -0.13716 -0.82804) (xy -0.1524 -0.8001) (xy -0.16256 -0.76835) (xy -0.1651 -0.7366) (xy -0.1651 0.13462)
						(xy -0.17272 0.14224) (xy -0.19812 0.1778) (xy -0.2032 0.18796) (xy -0.20701 0.19685) (xy -0.21209 0.20701)
						(xy -0.2159 0.21717) (xy -0.21844 0.22733) (xy -0.22225 0.23876) (xy -0.22352 0.24892) (xy -0.22606 0.25908)
						(xy -0.22733 0.27051) (xy -0.22733 0.28067) (xy -0.2286 0.2921) (xy -0.22733 0.30353) (xy -0.22733 0.31369)
						(xy -0.22606 0.32512) (xy -0.22352 0.33528) (xy -0.22225 0.34544) (xy -0.21844 0.35687) (xy -0.2159 0.36703)
						(xy -0.21209 0.37719) (xy -0.20701 0.38735) (xy -0.2032 0.39624) (xy -0.19812 0.4064) (xy -0.17272 0.44196)
						(xy -0.1651 0.44958) (xy -0.1651 0.7366) (xy -0.16256 0.76835) (xy -0.1524 0.8001) (xy -0.13716 0.82804)
						(xy -0.11684 0.85344) (xy -0.09144 0.87376) (xy -0.0635 0.889) (xy -0.03175 0.89916) (xy 0 0.9017)
						(xy 0.03175 0.89916) (xy 0.0635 0.889) (xy 0.09144 0.87376) (xy 0.11684 0.85344) (xy 0.13716 0.82804)
						(xy 0.1524 0.8001) (xy 0.16256 0.76835) (xy 0.1651 0.7366) (xy 0.1651 0.44958) (xy 0.17272 0.44196)
						(xy 0.19812 0.4064) (xy 0.2032 0.39624) (xy 0.20701 0.38735) (xy 0.21209 0.37719) (xy 0.2159 0.36703)
						(xy 0.21844 0.35687) (xy 0.22225 0.34544) (xy 0.22352 0.33528) (xy 0.22606 0.32512) (xy 0.22733 0.31369)
						(xy 0.22733 0.30353) (xy 0.2286 0.2921) (xy 0.22733 0.28067) (xy 0.22733 0.27051) (xy 0.22606 0.25908)
						(xy 0.22352 0.24892) (xy 0.22225 0.23876) (xy 0.21844 0.22733) (xy 0.2159 0.21717) (xy 0.21209 0.20701)
						(xy 0.20701 0.19685) (xy 0.2032 0.18796) (xy 0.19812 0.1778) (xy 0.17272 0.14224) (xy 0.1651 0.13462)
						(xy 0.1651 -0.7366) (xy 0.16256 -0.76835) (xy 0.1524 -0.8001) (xy 0.13716 -0.82804) (xy 0.11684 -0.85344)
						(xy 0.09144 -0.87376) (xy 0.0635 -0.889) (xy 0.03175 -0.89916)
					)
					(width 0)
					(fill yes)
				)
			)
		)
		(pad "155" smd custom
			(at 16.949928 -4.100068 180)
			(size 0.1143 0.1143)
			(layers "B.Cu" "B.Mask" "B.Paste")
			(net "GND")
			(options
				(clearance outline)
				(anchor circle)
			)
			(primitives
				(gr_poly
					(pts
						(xy 0 -0.9017) (xy -0.03175 -0.89916) (xy -0.0635 -0.889) (xy -0.09144 -0.87376) (xy -0.11684 -0.85344)
						(xy -0.13716 -0.82804) (xy -0.1524 -0.8001) (xy -0.16256 -0.76835) (xy -0.1651 -0.7366) (xy -0.1651 -0.19685)
						(xy -0.17272 -0.18923) (xy -0.17907 -0.18034) (xy -0.18669 -0.17145) (xy -0.19177 -0.16256) (xy -0.19812 -0.15367)
						(xy -0.20828 -0.13335) (xy -0.21971 -0.10287) (xy -0.22225 -0.09271) (xy -0.22479 -0.08128) (xy -0.22606 -0.07112)
						(xy -0.2286 -0.05969) (xy -0.2286 -0.01651) (xy -0.22606 -0.00508) (xy -0.22479 0.00508) (xy -0.22225 0.01651)
						(xy -0.21971 0.02667) (xy -0.20828 0.05715) (xy -0.19812 0.07747) (xy -0.19177 0.08636) (xy -0.18669 0.09525)
						(xy -0.17907 0.10414) (xy -0.17272 0.11303) (xy -0.1651 0.12065) (xy -0.1651 0.7366) (xy -0.16256 0.76835)
						(xy -0.1524 0.8001) (xy -0.13716 0.82804) (xy -0.11684 0.85344) (xy -0.09144 0.87376) (xy -0.0635 0.889)
						(xy -0.03175 0.89916) (xy 0 0.9017) (xy 0.03175 0.89916) (xy 0.0635 0.889) (xy 0.09144 0.87376)
						(xy 0.11684 0.85344) (xy 0.13716 0.82804) (xy 0.1524 0.8001) (xy 0.16256 0.76835) (xy 0.1651 0.7366)
						(xy 0.1651 0.11938) (xy 0.17272 0.11176) (xy 0.19812 0.0762) (xy 0.2032 0.06604) (xy 0.20701 0.05715)
						(xy 0.21209 0.04699) (xy 0.2159 0.03683) (xy 0.21844 0.02667) (xy 0.22225 0.01524) (xy 0.22352 0.00508)
						(xy 0.22606 -0.00508) (xy 0.22733 -0.01651) (xy 0.22733 -0.02667) (xy 0.2286 -0.0381) (xy 0.22733 -0.04953)
						(xy 0.22733 -0.05969) (xy 0.22606 -0.07112) (xy 0.22352 -0.08128) (xy 0.22225 -0.09144) (xy 0.21844 -0.10287)
						(xy 0.2159 -0.11303) (xy 0.21209 -0.12319) (xy 0.20701 -0.13335) (xy 0.2032 -0.14224) (xy 0.19812 -0.1524)
						(xy 0.17272 -0.18796) (xy 0.1651 -0.19558) (xy 0.1651 -0.7366) (xy 0.16256 -0.76835) (xy 0.1524 -0.8001)
						(xy 0.13716 -0.82804) (xy 0.11684 -0.85344) (xy 0.09144 -0.87376) (xy 0.0635 -0.889) (xy 0.03175 -0.89916)
					)
					(width 0)
					(fill yes)
				)
			)
		)
		(pad "156" smd custom
			(at 17.249902 4.100068 180)
			(size 0.1143 0.1143)
			(layers "B.Cu" "B.Mask" "B.Paste")
			(net "M_B_DQS_DP5")
			(options
				(clearance outline)
				(anchor circle)
			)
			(primitives
				(gr_poly
					(pts
						(xy 0 -0.9017) (xy -0.03175 -0.89916) (xy -0.0635 -0.889) (xy -0.09144 -0.87376) (xy -0.11684 -0.85344)
						(xy -0.13716 -0.82804) (xy -0.1524 -0.8001) (xy -0.16256 -0.76835) (xy -0.1651 -0.7366) (xy -0.1651 -0.11938)
						(xy -0.17272 -0.11176) (xy -0.19812 -0.0762) (xy -0.2032 -0.06604) (xy -0.20701 -0.05715) (xy -0.21209 -0.04699)
						(xy -0.2159 -0.03683) (xy -0.21844 -0.02667) (xy -0.22225 -0.01524) (xy -0.22352 -0.00508) (xy -0.22606 0.00508)
						(xy -0.22733 0.01651) (xy -0.22733 0.02667) (xy -0.2286 0.0381) (xy -0.22733 0.04953) (xy -0.22733 0.05969)
						(xy -0.22606 0.07112) (xy -0.22352 0.08128) (xy -0.22225 0.09144) (xy -0.21844 0.10287) (xy -0.2159 0.11303)
						(xy -0.21209 0.12319) (xy -0.20701 0.13335) (xy -0.2032 0.14224) (xy -0.19812 0.1524) (xy -0.17272 0.18796)
						(xy -0.1651 0.19558) (xy -0.1651 0.7366) (xy -0.16256 0.76835) (xy -0.1524 0.8001) (xy -0.13716 0.82804)
						(xy -0.11684 0.85344) (xy -0.09144 0.87376) (xy -0.0635 0.889) (xy -0.03175 0.89916) (xy 0 0.9017)
						(xy 0.03175 0.89916) (xy 0.0635 0.889) (xy 0.09144 0.87376) (xy 0.11684 0.85344) (xy 0.13716 0.82804)
						(xy 0.1524 0.8001) (xy 0.16256 0.76835) (xy 0.1651 0.7366) (xy 0.1651 0.19685) (xy 0.17272 0.18923)
						(xy 0.17907 0.18034) (xy 0.18669 0.17145) (xy 0.19177 0.16256) (xy 0.19812 0.15367) (xy 0.20828 0.13335)
						(xy 0.21971 0.10287) (xy 0.22225 0.09271) (xy 0.22479 0.08128) (xy 0.22606 0.07112) (xy 0.2286 0.05969)
						(xy 0.2286 0.01651) (xy 0.22606 0.00508) (xy 0.22479 -0.00508) (xy 0.22225 -0.01651) (xy 0.21971 -0.02667)
						(xy 0.20828 -0.05715) (xy 0.19812 -0.07747) (xy 0.19177 -0.08636) (xy 0.18669 -0.09525) (xy 0.17907 -0.10414)
						(xy 0.17272 -0.11303) (xy 0.1651 -0.12065) (xy 0.1651 -0.7366) (xy 0.16256 -0.76835) (xy 0.1524 -0.8001)
						(xy 0.13716 -0.82804) (xy 0.11684 -0.85344) (xy 0.09144 -0.87376) (xy 0.0635 -0.889) (xy 0.03175 -0.89916)
					)
					(width 0)
					(fill yes)
				)
			)
		)
		(pad "157" smd custom
			(at 17.549876 -4.100068 180)
			(size 0.1143 0.1143)
			(layers "B.Cu" "B.Mask" "B.Paste")
			(net "GND")
			(options
				(clearance outline)
				(anchor circle)
			)
			(primitives
				(gr_poly
					(pts
						(xy 0 -0.9017) (xy -0.03175 -0.89916) (xy -0.0635 -0.889) (xy -0.09144 -0.87376) (xy -0.11684 -0.85344)
						(xy -0.13716 -0.82804) (xy -0.1524 -0.8001) (xy -0.16256 -0.76835) (xy -0.1651 -0.7366) (xy -0.1651 -0.44958)
						(xy -0.17272 -0.44196) (xy -0.19812 -0.4064) (xy -0.2032 -0.39624) (xy -0.20701 -0.38735) (xy -0.21209 -0.37719)
						(xy -0.2159 -0.36703) (xy -0.21844 -0.35687) (xy -0.22225 -0.34544) (xy -0.22352 -0.33528) (xy -0.22606 -0.32512)
						(xy -0.22733 -0.31369) (xy -0.22733 -0.30353) (xy -0.2286 -0.2921) (xy -0.22733 -0.28067) (xy -0.22733 -0.27051)
						(xy -0.22606 -0.25908) (xy -0.22352 -0.24892) (xy -0.22225 -0.23876) (xy -0.21844 -0.22733) (xy -0.2159 -0.21717)
						(xy -0.21209 -0.20701) (xy -0.20701 -0.19685) (xy -0.2032 -0.18796) (xy -0.19812 -0.1778) (xy -0.17272 -0.14224)
						(xy -0.1651 -0.13462) (xy -0.1651 0.7366) (xy -0.16256 0.76835) (xy -0.1524 0.8001) (xy -0.13716 0.82804)
						(xy -0.11684 0.85344) (xy -0.09144 0.87376) (xy -0.0635 0.889) (xy -0.03175 0.89916) (xy 0 0.9017)
						(xy 0.03175 0.89916) (xy 0.0635 0.889) (xy 0.09144 0.87376) (xy 0.11684 0.85344) (xy 0.13716 0.82804)
						(xy 0.1524 0.8001) (xy 0.16256 0.76835) (xy 0.1651 0.7366) (xy 0.1651 -0.13462) (xy 0.17272 -0.14224)
						(xy 0.19812 -0.1778) (xy 0.2032 -0.18796) (xy 0.20701 -0.19685) (xy 0.21209 -0.20701) (xy 0.2159 -0.21717)
						(xy 0.21844 -0.22733) (xy 0.22225 -0.23876) (xy 0.22352 -0.24892) (xy 0.22606 -0.25908) (xy 0.22733 -0.27051)
						(xy 0.22733 -0.28067) (xy 0.2286 -0.2921) (xy 0.22733 -0.30353) (xy 0.22733 -0.31369) (xy 0.22606 -0.32512)
						(xy 0.22352 -0.33528) (xy 0.22225 -0.34544) (xy 0.21844 -0.35687) (xy 0.2159 -0.36703) (xy 0.21209 -0.37719)
						(xy 0.20701 -0.38735) (xy 0.2032 -0.39624) (xy 0.19812 -0.4064) (xy 0.17272 -0.44196) (xy 0.1651 -0.44958)
						(xy 0.1651 -0.7366) (xy 0.16256 -0.76835) (xy 0.1524 -0.8001) (xy 0.13716 -0.82804) (xy 0.11684 -0.85344)
						(xy 0.09144 -0.87376) (xy 0.0635 -0.889) (xy 0.03175 -0.89916)
					)
					(width 0)
					(fill yes)
				)
			)
		)
		(pad "158" smd custom
			(at 17.850104 4.100068 180)
			(size 0.1143 0.1143)
			(layers "B.Cu" "B.Mask" "B.Paste")
			(net "GND")
			(options
				(clearance outline)
				(anchor circle)
			)
			(primitives
				(gr_poly
					(pts
						(xy 0 -0.9017) (xy -0.03175 -0.89916) (xy -0.0635 -0.889) (xy -0.09144 -0.87376) (xy -0.11684 -0.85344)
						(xy -0.13716 -0.82804) (xy -0.1524 -0.8001) (xy -0.16256 -0.76835) (xy -0.1651 -0.7366) (xy -0.1651 0.13462)
						(xy -0.17272 0.14224) (xy -0.19812 0.1778) (xy -0.2032 0.18796) (xy -0.20701 0.19685) (xy -0.21209 0.20701)
						(xy -0.2159 0.21717) (xy -0.21844 0.22733) (xy -0.22225 0.23876) (xy -0.22352 0.24892) (xy -0.22606 0.25908)
						(xy -0.22733 0.27051) (xy -0.22733 0.28067) (xy -0.2286 0.2921) (xy -0.22733 0.30353) (xy -0.22733 0.31369)
						(xy -0.22606 0.32512) (xy -0.22352 0.33528) (xy -0.22225 0.34544) (xy -0.21844 0.35687) (xy -0.2159 0.36703)
						(xy -0.21209 0.37719) (xy -0.20701 0.38735) (xy -0.2032 0.39624) (xy -0.19812 0.4064) (xy -0.17272 0.44196)
						(xy -0.1651 0.44958) (xy -0.1651 0.7366) (xy -0.16256 0.76835) (xy -0.1524 0.8001) (xy -0.13716 0.82804)
						(xy -0.11684 0.85344) (xy -0.09144 0.87376) (xy -0.0635 0.889) (xy -0.03175 0.89916) (xy 0 0.9017)
						(xy 0.03175 0.89916) (xy 0.0635 0.889) (xy 0.09144 0.87376) (xy 0.11684 0.85344) (xy 0.13716 0.82804)
						(xy 0.1524 0.8001) (xy 0.16256 0.76835) (xy 0.1651 0.7366) (xy 0.1651 0.44958) (xy 0.17272 0.44196)
						(xy 0.19812 0.4064) (xy 0.2032 0.39624) (xy 0.20701 0.38735) (xy 0.21209 0.37719) (xy 0.2159 0.36703)
						(xy 0.21844 0.35687) (xy 0.22225 0.34544) (xy 0.22352 0.33528) (xy 0.22606 0.32512) (xy 0.22733 0.31369)
						(xy 0.22733 0.30353) (xy 0.2286 0.2921) (xy 0.22733 0.28067) (xy 0.22733 0.27051) (xy 0.22606 0.25908)
						(xy 0.22352 0.24892) (xy 0.22225 0.23876) (xy 0.21844 0.22733) (xy 0.2159 0.21717) (xy 0.21209 0.20701)
						(xy 0.20701 0.19685) (xy 0.2032 0.18796) (xy 0.19812 0.1778) (xy 0.17272 0.14224) (xy 0.1651 0.13462)
						(xy 0.1651 -0.7366) (xy 0.16256 -0.76835) (xy 0.1524 -0.8001) (xy 0.13716 -0.82804) (xy 0.11684 -0.85344)
						(xy 0.09144 -0.87376) (xy 0.0635 -0.889) (xy 0.03175 -0.89916)
					)
					(width 0)
					(fill yes)
				)
			)
		)
		(pad "159" smd custom
			(at 18.150078 -4.100068 180)
			(size 0.1143 0.1143)
			(layers "B.Cu" "B.Mask" "B.Paste")
			(net "M_B_DQ42")
			(options
				(clearance outline)
				(anchor circle)
			)
			(primitives
				(gr_poly
					(pts
						(xy 0 -0.9017) (xy -0.03175 -0.89916) (xy -0.0635 -0.889) (xy -0.09144 -0.87376) (xy -0.11684 -0.85344)
						(xy -0.13716 -0.82804) (xy -0.1524 -0.8001) (xy -0.16256 -0.76835) (xy -0.1651 -0.7366) (xy -0.1651 -0.19685)
						(xy -0.17272 -0.18923) (xy -0.17907 -0.18034) (xy -0.18669 -0.17145) (xy -0.19177 -0.16256) (xy -0.19812 -0.15367)
						(xy -0.20828 -0.13335) (xy -0.21971 -0.10287) (xy -0.22225 -0.09271) (xy -0.22479 -0.08128) (xy -0.22606 -0.07112)
						(xy -0.2286 -0.05969) (xy -0.2286 -0.01651) (xy -0.22606 -0.00508) (xy -0.22479 0.00508) (xy -0.22225 0.01651)
						(xy -0.21971 0.02667) (xy -0.20828 0.05715) (xy -0.19812 0.07747) (xy -0.19177 0.08636) (xy -0.18669 0.09525)
						(xy -0.17907 0.10414) (xy -0.17272 0.11303) (xy -0.1651 0.12065) (xy -0.1651 0.7366) (xy -0.16256 0.76835)
						(xy -0.1524 0.8001) (xy -0.13716 0.82804) (xy -0.11684 0.85344) (xy -0.09144 0.87376) (xy -0.0635 0.889)
						(xy -0.03175 0.89916) (xy 0 0.9017) (xy 0.03175 0.89916) (xy 0.0635 0.889) (xy 0.09144 0.87376)
						(xy 0.11684 0.85344) (xy 0.13716 0.82804) (xy 0.1524 0.8001) (xy 0.16256 0.76835) (xy 0.1651 0.7366)
						(xy 0.1651 0.11938) (xy 0.17272 0.11176) (xy 0.19812 0.0762) (xy 0.2032 0.06604) (xy 0.20701 0.05715)
						(xy 0.21209 0.04699) (xy 0.2159 0.03683) (xy 0.21844 0.02667) (xy 0.22225 0.01524) (xy 0.22352 0.00508)
						(xy 0.22606 -0.00508) (xy 0.22733 -0.01651) (xy 0.22733 -0.02667) (xy 0.2286 -0.0381) (xy 0.22733 -0.04953)
						(xy 0.22733 -0.05969) (xy 0.22606 -0.07112) (xy 0.22352 -0.08128) (xy 0.22225 -0.09144) (xy 0.21844 -0.10287)
						(xy 0.2159 -0.11303) (xy 0.21209 -0.12319) (xy 0.20701 -0.13335) (xy 0.2032 -0.14224) (xy 0.19812 -0.1524)
						(xy 0.17272 -0.18796) (xy 0.1651 -0.19558) (xy 0.1651 -0.7366) (xy 0.16256 -0.76835) (xy 0.1524 -0.8001)
						(xy 0.13716 -0.82804) (xy 0.11684 -0.85344) (xy 0.09144 -0.87376) (xy 0.0635 -0.889) (xy 0.03175 -0.89916)
					)
					(width 0)
					(fill yes)
				)
			)
		)
		(pad "160" smd custom
			(at 18.450052 4.100068 180)
			(size 0.1143 0.1143)
			(layers "B.Cu" "B.Mask" "B.Paste")
			(net "M_B_DQ46")
			(options
				(clearance outline)
				(anchor circle)
			)
			(primitives
				(gr_poly
					(pts
						(xy 0 -0.9017) (xy -0.03175 -0.89916) (xy -0.0635 -0.889) (xy -0.09144 -0.87376) (xy -0.11684 -0.85344)
						(xy -0.13716 -0.82804) (xy -0.1524 -0.8001) (xy -0.16256 -0.76835) (xy -0.1651 -0.7366) (xy -0.1651 -0.11938)
						(xy -0.17272 -0.11176) (xy -0.19812 -0.0762) (xy -0.2032 -0.06604) (xy -0.20701 -0.05715) (xy -0.21209 -0.04699)
						(xy -0.2159 -0.03683) (xy -0.21844 -0.02667) (xy -0.22225 -0.01524) (xy -0.22352 -0.00508) (xy -0.22606 0.00508)
						(xy -0.22733 0.01651) (xy -0.22733 0.02667) (xy -0.2286 0.0381) (xy -0.22733 0.04953) (xy -0.22733 0.05969)
						(xy -0.22606 0.07112) (xy -0.22352 0.08128) (xy -0.22225 0.09144) (xy -0.21844 0.10287) (xy -0.2159 0.11303)
						(xy -0.21209 0.12319) (xy -0.20701 0.13335) (xy -0.2032 0.14224) (xy -0.19812 0.1524) (xy -0.17272 0.18796)
						(xy -0.1651 0.19558) (xy -0.1651 0.7366) (xy -0.16256 0.76835) (xy -0.1524 0.8001) (xy -0.13716 0.82804)
						(xy -0.11684 0.85344) (xy -0.09144 0.87376) (xy -0.0635 0.889) (xy -0.03175 0.89916) (xy 0 0.9017)
						(xy 0.03175 0.89916) (xy 0.0635 0.889) (xy 0.09144 0.87376) (xy 0.11684 0.85344) (xy 0.13716 0.82804)
						(xy 0.1524 0.8001) (xy 0.16256 0.76835) (xy 0.1651 0.7366) (xy 0.1651 0.19685) (xy 0.17272 0.18923)
						(xy 0.17907 0.18034) (xy 0.18669 0.17145) (xy 0.19177 0.16256) (xy 0.19812 0.15367) (xy 0.20828 0.13335)
						(xy 0.21971 0.10287) (xy 0.22225 0.09271) (xy 0.22479 0.08128) (xy 0.22606 0.07112) (xy 0.2286 0.05969)
						(xy 0.2286 0.01651) (xy 0.22606 0.00508) (xy 0.22479 -0.00508) (xy 0.22225 -0.01651) (xy 0.21971 -0.02667)
						(xy 0.20828 -0.05715) (xy 0.19812 -0.07747) (xy 0.19177 -0.08636) (xy 0.18669 -0.09525) (xy 0.17907 -0.10414)
						(xy 0.17272 -0.11303) (xy 0.1651 -0.12065) (xy 0.1651 -0.7366) (xy 0.16256 -0.76835) (xy 0.1524 -0.8001)
						(xy 0.13716 -0.82804) (xy 0.11684 -0.85344) (xy 0.09144 -0.87376) (xy 0.0635 -0.889) (xy 0.03175 -0.89916)
					)
					(width 0)
					(fill yes)
				)
			)
		)
		(pad "161" smd custom
			(at 18.750026 -4.100068 180)
			(size 0.1143 0.1143)
			(layers "B.Cu" "B.Mask" "B.Paste")
			(net "M_B_DQ43")
			(options
				(clearance outline)
				(anchor circle)
			)
			(primitives
				(gr_poly
					(pts
						(xy 0 -0.9017) (xy -0.03175 -0.89916) (xy -0.0635 -0.889) (xy -0.09144 -0.87376) (xy -0.11684 -0.85344)
						(xy -0.13716 -0.82804) (xy -0.1524 -0.8001) (xy -0.16256 -0.76835) (xy -0.1651 -0.7366) (xy -0.1651 -0.44958)
						(xy -0.17272 -0.44196) (xy -0.19812 -0.4064) (xy -0.2032 -0.39624) (xy -0.20701 -0.38735) (xy -0.21209 -0.37719)
						(xy -0.2159 -0.36703) (xy -0.21844 -0.35687) (xy -0.22225 -0.34544) (xy -0.22352 -0.33528) (xy -0.22606 -0.32512)
						(xy -0.22733 -0.31369) (xy -0.22733 -0.30353) (xy -0.2286 -0.2921) (xy -0.22733 -0.28067) (xy -0.22733 -0.27051)
						(xy -0.22606 -0.25908) (xy -0.22352 -0.24892) (xy -0.22225 -0.23876) (xy -0.21844 -0.22733) (xy -0.2159 -0.21717)
						(xy -0.21209 -0.20701) (xy -0.20701 -0.19685) (xy -0.2032 -0.18796) (xy -0.19812 -0.1778) (xy -0.17272 -0.14224)
						(xy -0.1651 -0.13462) (xy -0.1651 0.7366) (xy -0.16256 0.76835) (xy -0.1524 0.8001) (xy -0.13716 0.82804)
						(xy -0.11684 0.85344) (xy -0.09144 0.87376) (xy -0.0635 0.889) (xy -0.03175 0.89916) (xy 0 0.9017)
						(xy 0.03175 0.89916) (xy 0.0635 0.889) (xy 0.09144 0.87376) (xy 0.11684 0.85344) (xy 0.13716 0.82804)
						(xy 0.1524 0.8001) (xy 0.16256 0.76835) (xy 0.1651 0.7366) (xy 0.1651 -0.13462) (xy 0.17272 -0.14224)
						(xy 0.19812 -0.1778) (xy 0.2032 -0.18796) (xy 0.20701 -0.19685) (xy 0.21209 -0.20701) (xy 0.2159 -0.21717)
						(xy 0.21844 -0.22733) (xy 0.22225 -0.23876) (xy 0.22352 -0.24892) (xy 0.22606 -0.25908) (xy 0.22733 -0.27051)
						(xy 0.22733 -0.28067) (xy 0.2286 -0.2921) (xy 0.22733 -0.30353) (xy 0.22733 -0.31369) (xy 0.22606 -0.32512)
						(xy 0.22352 -0.33528) (xy 0.22225 -0.34544) (xy 0.21844 -0.35687) (xy 0.2159 -0.36703) (xy 0.21209 -0.37719)
						(xy 0.20701 -0.38735) (xy 0.2032 -0.39624) (xy 0.19812 -0.4064) (xy 0.17272 -0.44196) (xy 0.1651 -0.44958)
						(xy 0.1651 -0.7366) (xy 0.16256 -0.76835) (xy 0.1524 -0.8001) (xy 0.13716 -0.82804) (xy 0.11684 -0.85344)
						(xy 0.09144 -0.87376) (xy 0.0635 -0.889) (xy 0.03175 -0.89916)
					)
					(width 0)
					(fill yes)
				)
			)
		)
		(pad "162" smd custom
			(at 19.05 4.100068 180)
			(size 0.1143 0.1143)
			(layers "B.Cu" "B.Mask" "B.Paste")
			(net "M_B_DQ47")
			(options
				(clearance outline)
				(anchor circle)
			)
			(primitives
				(gr_poly
					(pts
						(xy 0 -0.9017) (xy -0.03175 -0.89916) (xy -0.0635 -0.889) (xy -0.09144 -0.87376) (xy -0.11684 -0.85344)
						(xy -0.13716 -0.82804) (xy -0.1524 -0.8001) (xy -0.16256 -0.76835) (xy -0.1651 -0.7366) (xy -0.1651 0.13462)
						(xy -0.17272 0.14224) (xy -0.19812 0.1778) (xy -0.2032 0.18796) (xy -0.20701 0.19685) (xy -0.21209 0.20701)
						(xy -0.2159 0.21717) (xy -0.21844 0.22733) (xy -0.22225 0.23876) (xy -0.22352 0.24892) (xy -0.22606 0.25908)
						(xy -0.22733 0.27051) (xy -0.22733 0.28067) (xy -0.2286 0.2921) (xy -0.22733 0.30353) (xy -0.22733 0.31369)
						(xy -0.22606 0.32512) (xy -0.22352 0.33528) (xy -0.22225 0.34544) (xy -0.21844 0.35687) (xy -0.2159 0.36703)
						(xy -0.21209 0.37719) (xy -0.20701 0.38735) (xy -0.2032 0.39624) (xy -0.19812 0.4064) (xy -0.17272 0.44196)
						(xy -0.1651 0.44958) (xy -0.1651 0.7366) (xy -0.16256 0.76835) (xy -0.1524 0.8001) (xy -0.13716 0.82804)
						(xy -0.11684 0.85344) (xy -0.09144 0.87376) (xy -0.0635 0.889) (xy -0.03175 0.89916) (xy 0 0.9017)
						(xy 0.03175 0.89916) (xy 0.0635 0.889) (xy 0.09144 0.87376) (xy 0.11684 0.85344) (xy 0.13716 0.82804)
						(xy 0.1524 0.8001) (xy 0.16256 0.76835) (xy 0.1651 0.7366) (xy 0.1651 0.44958) (xy 0.17272 0.44196)
						(xy 0.19812 0.4064) (xy 0.2032 0.39624) (xy 0.20701 0.38735) (xy 0.21209 0.37719) (xy 0.2159 0.36703)
						(xy 0.21844 0.35687) (xy 0.22225 0.34544) (xy 0.22352 0.33528) (xy 0.22606 0.32512) (xy 0.22733 0.31369)
						(xy 0.22733 0.30353) (xy 0.2286 0.2921) (xy 0.22733 0.28067) (xy 0.22733 0.27051) (xy 0.22606 0.25908)
						(xy 0.22352 0.24892) (xy 0.22225 0.23876) (xy 0.21844 0.22733) (xy 0.2159 0.21717) (xy 0.21209 0.20701)
						(xy 0.20701 0.19685) (xy 0.2032 0.18796) (xy 0.19812 0.1778) (xy 0.17272 0.14224) (xy 0.1651 0.13462)
						(xy 0.1651 -0.7366) (xy 0.16256 -0.76835) (xy 0.1524 -0.8001) (xy 0.13716 -0.82804) (xy 0.11684 -0.85344)
						(xy 0.09144 -0.87376) (xy 0.0635 -0.889) (xy 0.03175 -0.89916)
					)
					(width 0)
					(fill yes)
				)
			)
		)
		(pad "163" smd custom
			(at 19.349974 -4.100068 180)
			(size 0.1143 0.1143)
			(layers "B.Cu" "B.Mask" "B.Paste")
			(net "GND")
			(options
				(clearance outline)
				(anchor circle)
			)
			(primitives
				(gr_poly
					(pts
						(xy 0 -0.9017) (xy -0.03175 -0.89916) (xy -0.0635 -0.889) (xy -0.09144 -0.87376) (xy -0.11684 -0.85344)
						(xy -0.13716 -0.82804) (xy -0.1524 -0.8001) (xy -0.16256 -0.76835) (xy -0.1651 -0.7366) (xy -0.1651 -0.19685)
						(xy -0.17272 -0.18923) (xy -0.17907 -0.18034) (xy -0.18669 -0.17145) (xy -0.19177 -0.16256) (xy -0.19812 -0.15367)
						(xy -0.20828 -0.13335) (xy -0.21971 -0.10287) (xy -0.22225 -0.09271) (xy -0.22479 -0.08128) (xy -0.22606 -0.07112)
						(xy -0.2286 -0.05969) (xy -0.2286 -0.01651) (xy -0.22606 -0.00508) (xy -0.22479 0.00508) (xy -0.22225 0.01651)
						(xy -0.21971 0.02667) (xy -0.20828 0.05715) (xy -0.19812 0.07747) (xy -0.19177 0.08636) (xy -0.18669 0.09525)
						(xy -0.17907 0.10414) (xy -0.17272 0.11303) (xy -0.1651 0.12065) (xy -0.1651 0.7366) (xy -0.16256 0.76835)
						(xy -0.1524 0.8001) (xy -0.13716 0.82804) (xy -0.11684 0.85344) (xy -0.09144 0.87376) (xy -0.0635 0.889)
						(xy -0.03175 0.89916) (xy 0 0.9017) (xy 0.03175 0.89916) (xy 0.0635 0.889) (xy 0.09144 0.87376)
						(xy 0.11684 0.85344) (xy 0.13716 0.82804) (xy 0.1524 0.8001) (xy 0.16256 0.76835) (xy 0.1651 0.7366)
						(xy 0.1651 0.11938) (xy 0.17272 0.11176) (xy 0.19812 0.0762) (xy 0.2032 0.06604) (xy 0.20701 0.05715)
						(xy 0.21209 0.04699) (xy 0.2159 0.03683) (xy 0.21844 0.02667) (xy 0.22225 0.01524) (xy 0.22352 0.00508)
						(xy 0.22606 -0.00508) (xy 0.22733 -0.01651) (xy 0.22733 -0.02667) (xy 0.2286 -0.0381) (xy 0.22733 -0.04953)
						(xy 0.22733 -0.05969) (xy 0.22606 -0.07112) (xy 0.22352 -0.08128) (xy 0.22225 -0.09144) (xy 0.21844 -0.10287)
						(xy 0.2159 -0.11303) (xy 0.21209 -0.12319) (xy 0.20701 -0.13335) (xy 0.2032 -0.14224) (xy 0.19812 -0.1524)
						(xy 0.17272 -0.18796) (xy 0.1651 -0.19558) (xy 0.1651 -0.7366) (xy 0.16256 -0.76835) (xy 0.1524 -0.8001)
						(xy 0.13716 -0.82804) (xy 0.11684 -0.85344) (xy 0.09144 -0.87376) (xy 0.0635 -0.889) (xy 0.03175 -0.89916)
					)
					(width 0)
					(fill yes)
				)
			)
		)
		(pad "164" smd custom
			(at 19.649948 4.100068 180)
			(size 0.1143 0.1143)
			(layers "B.Cu" "B.Mask" "B.Paste")
			(net "GND")
			(options
				(clearance outline)
				(anchor circle)
			)
			(primitives
				(gr_poly
					(pts
						(xy 0 -0.9017) (xy -0.03175 -0.89916) (xy -0.0635 -0.889) (xy -0.09144 -0.87376) (xy -0.11684 -0.85344)
						(xy -0.13716 -0.82804) (xy -0.1524 -0.8001) (xy -0.16256 -0.76835) (xy -0.1651 -0.7366) (xy -0.1651 -0.11938)
						(xy -0.17272 -0.11176) (xy -0.19812 -0.0762) (xy -0.2032 -0.06604) (xy -0.20701 -0.05715) (xy -0.21209 -0.04699)
						(xy -0.2159 -0.03683) (xy -0.21844 -0.02667) (xy -0.22225 -0.01524) (xy -0.22352 -0.00508) (xy -0.22606 0.00508)
						(xy -0.22733 0.01651) (xy -0.22733 0.02667) (xy -0.2286 0.0381) (xy -0.22733 0.04953) (xy -0.22733 0.05969)
						(xy -0.22606 0.07112) (xy -0.22352 0.08128) (xy -0.22225 0.09144) (xy -0.21844 0.10287) (xy -0.2159 0.11303)
						(xy -0.21209 0.12319) (xy -0.20701 0.13335) (xy -0.2032 0.14224) (xy -0.19812 0.1524) (xy -0.17272 0.18796)
						(xy -0.1651 0.19558) (xy -0.1651 0.7366) (xy -0.16256 0.76835) (xy -0.1524 0.8001) (xy -0.13716 0.82804)
						(xy -0.11684 0.85344) (xy -0.09144 0.87376) (xy -0.0635 0.889) (xy -0.03175 0.89916) (xy 0 0.9017)
						(xy 0.03175 0.89916) (xy 0.0635 0.889) (xy 0.09144 0.87376) (xy 0.11684 0.85344) (xy 0.13716 0.82804)
						(xy 0.1524 0.8001) (xy 0.16256 0.76835) (xy 0.1651 0.7366) (xy 0.1651 0.19685) (xy 0.17272 0.18923)
						(xy 0.17907 0.18034) (xy 0.18669 0.17145) (xy 0.19177 0.16256) (xy 0.19812 0.15367) (xy 0.20828 0.13335)
						(xy 0.21971 0.10287) (xy 0.22225 0.09271) (xy 0.22479 0.08128) (xy 0.22606 0.07112) (xy 0.2286 0.05969)
						(xy 0.2286 0.01651) (xy 0.22606 0.00508) (xy 0.22479 -0.00508) (xy 0.22225 -0.01651) (xy 0.21971 -0.02667)
						(xy 0.20828 -0.05715) (xy 0.19812 -0.07747) (xy 0.19177 -0.08636) (xy 0.18669 -0.09525) (xy 0.17907 -0.10414)
						(xy 0.17272 -0.11303) (xy 0.1651 -0.12065) (xy 0.1651 -0.7366) (xy 0.16256 -0.76835) (xy 0.1524 -0.8001)
						(xy 0.13716 -0.82804) (xy 0.11684 -0.85344) (xy 0.09144 -0.87376) (xy 0.0635 -0.889) (xy 0.03175 -0.89916)
					)
					(width 0)
					(fill yes)
				)
			)
		)
		(pad "165" smd custom
			(at 19.949922 -4.100068 180)
			(size 0.1143 0.1143)
			(layers "B.Cu" "B.Mask" "B.Paste")
			(net "M_B_DQ48")
			(options
				(clearance outline)
				(anchor circle)
			)
			(primitives
				(gr_poly
					(pts
						(xy 0 -0.9017) (xy -0.03175 -0.89916) (xy -0.0635 -0.889) (xy -0.09144 -0.87376) (xy -0.11684 -0.85344)
						(xy -0.13716 -0.82804) (xy -0.1524 -0.8001) (xy -0.16256 -0.76835) (xy -0.1651 -0.7366) (xy -0.1651 -0.44958)
						(xy -0.17272 -0.44196) (xy -0.19812 -0.4064) (xy -0.2032 -0.39624) (xy -0.20701 -0.38735) (xy -0.21209 -0.37719)
						(xy -0.2159 -0.36703) (xy -0.21844 -0.35687) (xy -0.22225 -0.34544) (xy -0.22352 -0.33528) (xy -0.22606 -0.32512)
						(xy -0.22733 -0.31369) (xy -0.22733 -0.30353) (xy -0.2286 -0.2921) (xy -0.22733 -0.28067) (xy -0.22733 -0.27051)
						(xy -0.22606 -0.25908) (xy -0.22352 -0.24892) (xy -0.22225 -0.23876) (xy -0.21844 -0.22733) (xy -0.2159 -0.21717)
						(xy -0.21209 -0.20701) (xy -0.20701 -0.19685) (xy -0.2032 -0.18796) (xy -0.19812 -0.1778) (xy -0.17272 -0.14224)
						(xy -0.1651 -0.13462) (xy -0.1651 0.7366) (xy -0.16256 0.76835) (xy -0.1524 0.8001) (xy -0.13716 0.82804)
						(xy -0.11684 0.85344) (xy -0.09144 0.87376) (xy -0.0635 0.889) (xy -0.03175 0.89916) (xy 0 0.9017)
						(xy 0.03175 0.89916) (xy 0.0635 0.889) (xy 0.09144 0.87376) (xy 0.11684 0.85344) (xy 0.13716 0.82804)
						(xy 0.1524 0.8001) (xy 0.16256 0.76835) (xy 0.1651 0.7366) (xy 0.1651 -0.13462) (xy 0.17272 -0.14224)
						(xy 0.19812 -0.1778) (xy 0.2032 -0.18796) (xy 0.20701 -0.19685) (xy 0.21209 -0.20701) (xy 0.2159 -0.21717)
						(xy 0.21844 -0.22733) (xy 0.22225 -0.23876) (xy 0.22352 -0.24892) (xy 0.22606 -0.25908) (xy 0.22733 -0.27051)
						(xy 0.22733 -0.28067) (xy 0.2286 -0.2921) (xy 0.22733 -0.30353) (xy 0.22733 -0.31369) (xy 0.22606 -0.32512)
						(xy 0.22352 -0.33528) (xy 0.22225 -0.34544) (xy 0.21844 -0.35687) (xy 0.2159 -0.36703) (xy 0.21209 -0.37719)
						(xy 0.20701 -0.38735) (xy 0.2032 -0.39624) (xy 0.19812 -0.4064) (xy 0.17272 -0.44196) (xy 0.1651 -0.44958)
						(xy 0.1651 -0.7366) (xy 0.16256 -0.76835) (xy 0.1524 -0.8001) (xy 0.13716 -0.82804) (xy 0.11684 -0.85344)
						(xy 0.09144 -0.87376) (xy 0.0635 -0.889) (xy 0.03175 -0.89916)
					)
					(width 0)
					(fill yes)
				)
			)
		)
		(pad "166" smd custom
			(at 20.249896 4.100068 180)
			(size 0.1143 0.1143)
			(layers "B.Cu" "B.Mask" "B.Paste")
			(net "M_B_DQ52")
			(options
				(clearance outline)
				(anchor circle)
			)
			(primitives
				(gr_poly
					(pts
						(xy 0 -0.9017) (xy -0.03175 -0.89916) (xy -0.0635 -0.889) (xy -0.09144 -0.87376) (xy -0.11684 -0.85344)
						(xy -0.13716 -0.82804) (xy -0.1524 -0.8001) (xy -0.16256 -0.76835) (xy -0.1651 -0.7366) (xy -0.1651 0.13462)
						(xy -0.17272 0.14224) (xy -0.19812 0.1778) (xy -0.2032 0.18796) (xy -0.20701 0.19685) (xy -0.21209 0.20701)
						(xy -0.2159 0.21717) (xy -0.21844 0.22733) (xy -0.22225 0.23876) (xy -0.22352 0.24892) (xy -0.22606 0.25908)
						(xy -0.22733 0.27051) (xy -0.22733 0.28067) (xy -0.2286 0.2921) (xy -0.22733 0.30353) (xy -0.22733 0.31369)
						(xy -0.22606 0.32512) (xy -0.22352 0.33528) (xy -0.22225 0.34544) (xy -0.21844 0.35687) (xy -0.2159 0.36703)
						(xy -0.21209 0.37719) (xy -0.20701 0.38735) (xy -0.2032 0.39624) (xy -0.19812 0.4064) (xy -0.17272 0.44196)
						(xy -0.1651 0.44958) (xy -0.1651 0.7366) (xy -0.16256 0.76835) (xy -0.1524 0.8001) (xy -0.13716 0.82804)
						(xy -0.11684 0.85344) (xy -0.09144 0.87376) (xy -0.0635 0.889) (xy -0.03175 0.89916) (xy 0 0.9017)
						(xy 0.03175 0.89916) (xy 0.0635 0.889) (xy 0.09144 0.87376) (xy 0.11684 0.85344) (xy 0.13716 0.82804)
						(xy 0.1524 0.8001) (xy 0.16256 0.76835) (xy 0.1651 0.7366) (xy 0.1651 0.44958) (xy 0.17272 0.44196)
						(xy 0.19812 0.4064) (xy 0.2032 0.39624) (xy 0.20701 0.38735) (xy 0.21209 0.37719) (xy 0.2159 0.36703)
						(xy 0.21844 0.35687) (xy 0.22225 0.34544) (xy 0.22352 0.33528) (xy 0.22606 0.32512) (xy 0.22733 0.31369)
						(xy 0.22733 0.30353) (xy 0.2286 0.2921) (xy 0.22733 0.28067) (xy 0.22733 0.27051) (xy 0.22606 0.25908)
						(xy 0.22352 0.24892) (xy 0.22225 0.23876) (xy 0.21844 0.22733) (xy 0.2159 0.21717) (xy 0.21209 0.20701)
						(xy 0.20701 0.19685) (xy 0.2032 0.18796) (xy 0.19812 0.1778) (xy 0.17272 0.14224) (xy 0.1651 0.13462)
						(xy 0.1651 -0.7366) (xy 0.16256 -0.76835) (xy 0.1524 -0.8001) (xy 0.13716 -0.82804) (xy 0.11684 -0.85344)
						(xy 0.09144 -0.87376) (xy 0.0635 -0.889) (xy 0.03175 -0.89916)
					)
					(width 0)
					(fill yes)
				)
			)
		)
		(pad "167" smd custom
			(at 20.550124 -4.100068 180)
			(size 0.1143 0.1143)
			(layers "B.Cu" "B.Mask" "B.Paste")
			(net "M_B_DQ49")
			(options
				(clearance outline)
				(anchor circle)
			)
			(primitives
				(gr_poly
					(pts
						(xy 0 -0.9017) (xy -0.03175 -0.89916) (xy -0.0635 -0.889) (xy -0.09144 -0.87376) (xy -0.11684 -0.85344)
						(xy -0.13716 -0.82804) (xy -0.1524 -0.8001) (xy -0.16256 -0.76835) (xy -0.1651 -0.7366) (xy -0.1651 -0.19685)
						(xy -0.17272 -0.18923) (xy -0.17907 -0.18034) (xy -0.18669 -0.17145) (xy -0.19177 -0.16256) (xy -0.19812 -0.15367)
						(xy -0.20828 -0.13335) (xy -0.21971 -0.10287) (xy -0.22225 -0.09271) (xy -0.22479 -0.08128) (xy -0.22606 -0.07112)
						(xy -0.2286 -0.05969) (xy -0.2286 -0.01651) (xy -0.22606 -0.00508) (xy -0.22479 0.00508) (xy -0.22225 0.01651)
						(xy -0.21971 0.02667) (xy -0.20828 0.05715) (xy -0.19812 0.07747) (xy -0.19177 0.08636) (xy -0.18669 0.09525)
						(xy -0.17907 0.10414) (xy -0.17272 0.11303) (xy -0.1651 0.12065) (xy -0.1651 0.7366) (xy -0.16256 0.76835)
						(xy -0.1524 0.8001) (xy -0.13716 0.82804) (xy -0.11684 0.85344) (xy -0.09144 0.87376) (xy -0.0635 0.889)
						(xy -0.03175 0.89916) (xy 0 0.9017) (xy 0.03175 0.89916) (xy 0.0635 0.889) (xy 0.09144 0.87376)
						(xy 0.11684 0.85344) (xy 0.13716 0.82804) (xy 0.1524 0.8001) (xy 0.16256 0.76835) (xy 0.1651 0.7366)
						(xy 0.1651 0.11938) (xy 0.17272 0.11176) (xy 0.19812 0.0762) (xy 0.2032 0.06604) (xy 0.20701 0.05715)
						(xy 0.21209 0.04699) (xy 0.2159 0.03683) (xy 0.21844 0.02667) (xy 0.22225 0.01524) (xy 0.22352 0.00508)
						(xy 0.22606 -0.00508) (xy 0.22733 -0.01651) (xy 0.22733 -0.02667) (xy 0.2286 -0.0381) (xy 0.22733 -0.04953)
						(xy 0.22733 -0.05969) (xy 0.22606 -0.07112) (xy 0.22352 -0.08128) (xy 0.22225 -0.09144) (xy 0.21844 -0.10287)
						(xy 0.2159 -0.11303) (xy 0.21209 -0.12319) (xy 0.20701 -0.13335) (xy 0.2032 -0.14224) (xy 0.19812 -0.1524)
						(xy 0.17272 -0.18796) (xy 0.1651 -0.19558) (xy 0.1651 -0.7366) (xy 0.16256 -0.76835) (xy 0.1524 -0.8001)
						(xy 0.13716 -0.82804) (xy 0.11684 -0.85344) (xy 0.09144 -0.87376) (xy 0.0635 -0.889) (xy 0.03175 -0.89916)
					)
					(width 0)
					(fill yes)
				)
			)
		)
		(pad "168" smd custom
			(at 20.850098 4.100068 180)
			(size 0.1143 0.1143)
			(layers "B.Cu" "B.Mask" "B.Paste")
			(net "M_B_DQ53")
			(options
				(clearance outline)
				(anchor circle)
			)
			(primitives
				(gr_poly
					(pts
						(xy 0 -0.9017) (xy -0.03175 -0.89916) (xy -0.0635 -0.889) (xy -0.09144 -0.87376) (xy -0.11684 -0.85344)
						(xy -0.13716 -0.82804) (xy -0.1524 -0.8001) (xy -0.16256 -0.76835) (xy -0.1651 -0.7366) (xy -0.1651 -0.11938)
						(xy -0.17272 -0.11176) (xy -0.19812 -0.0762) (xy -0.2032 -0.06604) (xy -0.20701 -0.05715) (xy -0.21209 -0.04699)
						(xy -0.2159 -0.03683) (xy -0.21844 -0.02667) (xy -0.22225 -0.01524) (xy -0.22352 -0.00508) (xy -0.22606 0.00508)
						(xy -0.22733 0.01651) (xy -0.22733 0.02667) (xy -0.2286 0.0381) (xy -0.22733 0.04953) (xy -0.22733 0.05969)
						(xy -0.22606 0.07112) (xy -0.22352 0.08128) (xy -0.22225 0.09144) (xy -0.21844 0.10287) (xy -0.2159 0.11303)
						(xy -0.21209 0.12319) (xy -0.20701 0.13335) (xy -0.2032 0.14224) (xy -0.19812 0.1524) (xy -0.17272 0.18796)
						(xy -0.1651 0.19558) (xy -0.1651 0.7366) (xy -0.16256 0.76835) (xy -0.1524 0.8001) (xy -0.13716 0.82804)
						(xy -0.11684 0.85344) (xy -0.09144 0.87376) (xy -0.0635 0.889) (xy -0.03175 0.89916) (xy 0 0.9017)
						(xy 0.03175 0.89916) (xy 0.0635 0.889) (xy 0.09144 0.87376) (xy 0.11684 0.85344) (xy 0.13716 0.82804)
						(xy 0.1524 0.8001) (xy 0.16256 0.76835) (xy 0.1651 0.7366) (xy 0.1651 0.19685) (xy 0.17272 0.18923)
						(xy 0.17907 0.18034) (xy 0.18669 0.17145) (xy 0.19177 0.16256) (xy 0.19812 0.15367) (xy 0.20828 0.13335)
						(xy 0.21971 0.10287) (xy 0.22225 0.09271) (xy 0.22479 0.08128) (xy 0.22606 0.07112) (xy 0.2286 0.05969)
						(xy 0.2286 0.01651) (xy 0.22606 0.00508) (xy 0.22479 -0.00508) (xy 0.22225 -0.01651) (xy 0.21971 -0.02667)
						(xy 0.20828 -0.05715) (xy 0.19812 -0.07747) (xy 0.19177 -0.08636) (xy 0.18669 -0.09525) (xy 0.17907 -0.10414)
						(xy 0.17272 -0.11303) (xy 0.1651 -0.12065) (xy 0.1651 -0.7366) (xy 0.16256 -0.76835) (xy 0.1524 -0.8001)
						(xy 0.13716 -0.82804) (xy 0.11684 -0.85344) (xy 0.09144 -0.87376) (xy 0.0635 -0.889) (xy 0.03175 -0.89916)
					)
					(width 0)
					(fill yes)
				)
			)
		)
		(pad "169" smd custom
			(at 21.150072 -4.100068 180)
			(size 0.1143 0.1143)
			(layers "B.Cu" "B.Mask" "B.Paste")
			(net "GND")
			(options
				(clearance outline)
				(anchor circle)
			)
			(primitives
				(gr_poly
					(pts
						(xy 0 -0.9017) (xy -0.03175 -0.89916) (xy -0.0635 -0.889) (xy -0.09144 -0.87376) (xy -0.11684 -0.85344)
						(xy -0.13716 -0.82804) (xy -0.1524 -0.8001) (xy -0.16256 -0.76835) (xy -0.1651 -0.7366) (xy -0.1651 -0.44958)
						(xy -0.17272 -0.44196) (xy -0.19812 -0.4064) (xy -0.2032 -0.39624) (xy -0.20701 -0.38735) (xy -0.21209 -0.37719)
						(xy -0.2159 -0.36703) (xy -0.21844 -0.35687) (xy -0.22225 -0.34544) (xy -0.22352 -0.33528) (xy -0.22606 -0.32512)
						(xy -0.22733 -0.31369) (xy -0.22733 -0.30353) (xy -0.2286 -0.2921) (xy -0.22733 -0.28067) (xy -0.22733 -0.27051)
						(xy -0.22606 -0.25908) (xy -0.22352 -0.24892) (xy -0.22225 -0.23876) (xy -0.21844 -0.22733) (xy -0.2159 -0.21717)
						(xy -0.21209 -0.20701) (xy -0.20701 -0.19685) (xy -0.2032 -0.18796) (xy -0.19812 -0.1778) (xy -0.17272 -0.14224)
						(xy -0.1651 -0.13462) (xy -0.1651 0.7366) (xy -0.16256 0.76835) (xy -0.1524 0.8001) (xy -0.13716 0.82804)
						(xy -0.11684 0.85344) (xy -0.09144 0.87376) (xy -0.0635 0.889) (xy -0.03175 0.89916) (xy 0 0.9017)
						(xy 0.03175 0.89916) (xy 0.0635 0.889) (xy 0.09144 0.87376) (xy 0.11684 0.85344) (xy 0.13716 0.82804)
						(xy 0.1524 0.8001) (xy 0.16256 0.76835) (xy 0.1651 0.7366) (xy 0.1651 -0.13462) (xy 0.17272 -0.14224)
						(xy 0.19812 -0.1778) (xy 0.2032 -0.18796) (xy 0.20701 -0.19685) (xy 0.21209 -0.20701) (xy 0.2159 -0.21717)
						(xy 0.21844 -0.22733) (xy 0.22225 -0.23876) (xy 0.22352 -0.24892) (xy 0.22606 -0.25908) (xy 0.22733 -0.27051)
						(xy 0.22733 -0.28067) (xy 0.2286 -0.2921) (xy 0.22733 -0.30353) (xy 0.22733 -0.31369) (xy 0.22606 -0.32512)
						(xy 0.22352 -0.33528) (xy 0.22225 -0.34544) (xy 0.21844 -0.35687) (xy 0.2159 -0.36703) (xy 0.21209 -0.37719)
						(xy 0.20701 -0.38735) (xy 0.2032 -0.39624) (xy 0.19812 -0.4064) (xy 0.17272 -0.44196) (xy 0.1651 -0.44958)
						(xy 0.1651 -0.7366) (xy 0.16256 -0.76835) (xy 0.1524 -0.8001) (xy 0.13716 -0.82804) (xy 0.11684 -0.85344)
						(xy 0.09144 -0.87376) (xy 0.0635 -0.889) (xy 0.03175 -0.89916)
					)
					(width 0)
					(fill yes)
				)
			)
		)
		(pad "170" smd custom
			(at 21.450046 4.100068 180)
			(size 0.1143 0.1143)
			(layers "B.Cu" "B.Mask" "B.Paste")
			(net "GND")
			(options
				(clearance outline)
				(anchor circle)
			)
			(primitives
				(gr_poly
					(pts
						(xy 0 -0.9017) (xy -0.03175 -0.89916) (xy -0.0635 -0.889) (xy -0.09144 -0.87376) (xy -0.11684 -0.85344)
						(xy -0.13716 -0.82804) (xy -0.1524 -0.8001) (xy -0.16256 -0.76835) (xy -0.1651 -0.7366) (xy -0.1651 0.13462)
						(xy -0.17272 0.14224) (xy -0.19812 0.1778) (xy -0.2032 0.18796) (xy -0.20701 0.19685) (xy -0.21209 0.20701)
						(xy -0.2159 0.21717) (xy -0.21844 0.22733) (xy -0.22225 0.23876) (xy -0.22352 0.24892) (xy -0.22606 0.25908)
						(xy -0.22733 0.27051) (xy -0.22733 0.28067) (xy -0.2286 0.2921) (xy -0.22733 0.30353) (xy -0.22733 0.31369)
						(xy -0.22606 0.32512) (xy -0.22352 0.33528) (xy -0.22225 0.34544) (xy -0.21844 0.35687) (xy -0.2159 0.36703)
						(xy -0.21209 0.37719) (xy -0.20701 0.38735) (xy -0.2032 0.39624) (xy -0.19812 0.4064) (xy -0.17272 0.44196)
						(xy -0.1651 0.44958) (xy -0.1651 0.7366) (xy -0.16256 0.76835) (xy -0.1524 0.8001) (xy -0.13716 0.82804)
						(xy -0.11684 0.85344) (xy -0.09144 0.87376) (xy -0.0635 0.889) (xy -0.03175 0.89916) (xy 0 0.9017)
						(xy 0.03175 0.89916) (xy 0.0635 0.889) (xy 0.09144 0.87376) (xy 0.11684 0.85344) (xy 0.13716 0.82804)
						(xy 0.1524 0.8001) (xy 0.16256 0.76835) (xy 0.1651 0.7366) (xy 0.1651 0.44958) (xy 0.17272 0.44196)
						(xy 0.19812 0.4064) (xy 0.2032 0.39624) (xy 0.20701 0.38735) (xy 0.21209 0.37719) (xy 0.2159 0.36703)
						(xy 0.21844 0.35687) (xy 0.22225 0.34544) (xy 0.22352 0.33528) (xy 0.22606 0.32512) (xy 0.22733 0.31369)
						(xy 0.22733 0.30353) (xy 0.2286 0.2921) (xy 0.22733 0.28067) (xy 0.22733 0.27051) (xy 0.22606 0.25908)
						(xy 0.22352 0.24892) (xy 0.22225 0.23876) (xy 0.21844 0.22733) (xy 0.2159 0.21717) (xy 0.21209 0.20701)
						(xy 0.20701 0.19685) (xy 0.2032 0.18796) (xy 0.19812 0.1778) (xy 0.17272 0.14224) (xy 0.1651 0.13462)
						(xy 0.1651 -0.7366) (xy 0.16256 -0.76835) (xy 0.1524 -0.8001) (xy 0.13716 -0.82804) (xy 0.11684 -0.85344)
						(xy 0.09144 -0.87376) (xy 0.0635 -0.889) (xy 0.03175 -0.89916)
					)
					(width 0)
					(fill yes)
				)
			)
		)
		(pad "171" smd custom
			(at 21.75002 -4.100068 180)
			(size 0.1143 0.1143)
			(layers "B.Cu" "B.Mask" "B.Paste")
			(net "M_B_DQS_DN6")
			(options
				(clearance outline)
				(anchor circle)
			)
			(primitives
				(gr_poly
					(pts
						(xy 0 -0.9017) (xy -0.03175 -0.89916) (xy -0.0635 -0.889) (xy -0.09144 -0.87376) (xy -0.11684 -0.85344)
						(xy -0.13716 -0.82804) (xy -0.1524 -0.8001) (xy -0.16256 -0.76835) (xy -0.1651 -0.7366) (xy -0.1651 -0.19685)
						(xy -0.17272 -0.18923) (xy -0.17907 -0.18034) (xy -0.18669 -0.17145) (xy -0.19177 -0.16256) (xy -0.19812 -0.15367)
						(xy -0.20828 -0.13335) (xy -0.21971 -0.10287) (xy -0.22225 -0.09271) (xy -0.22479 -0.08128) (xy -0.22606 -0.07112)
						(xy -0.2286 -0.05969) (xy -0.2286 -0.01651) (xy -0.22606 -0.00508) (xy -0.22479 0.00508) (xy -0.22225 0.01651)
						(xy -0.21971 0.02667) (xy -0.20828 0.05715) (xy -0.19812 0.07747) (xy -0.19177 0.08636) (xy -0.18669 0.09525)
						(xy -0.17907 0.10414) (xy -0.17272 0.11303) (xy -0.1651 0.12065) (xy -0.1651 0.7366) (xy -0.16256 0.76835)
						(xy -0.1524 0.8001) (xy -0.13716 0.82804) (xy -0.11684 0.85344) (xy -0.09144 0.87376) (xy -0.0635 0.889)
						(xy -0.03175 0.89916) (xy 0 0.9017) (xy 0.03175 0.89916) (xy 0.0635 0.889) (xy 0.09144 0.87376)
						(xy 0.11684 0.85344) (xy 0.13716 0.82804) (xy 0.1524 0.8001) (xy 0.16256 0.76835) (xy 0.1651 0.7366)
						(xy 0.1651 0.11938) (xy 0.17272 0.11176) (xy 0.19812 0.0762) (xy 0.2032 0.06604) (xy 0.20701 0.05715)
						(xy 0.21209 0.04699) (xy 0.2159 0.03683) (xy 0.21844 0.02667) (xy 0.22225 0.01524) (xy 0.22352 0.00508)
						(xy 0.22606 -0.00508) (xy 0.22733 -0.01651) (xy 0.22733 -0.02667) (xy 0.2286 -0.0381) (xy 0.22733 -0.04953)
						(xy 0.22733 -0.05969) (xy 0.22606 -0.07112) (xy 0.22352 -0.08128) (xy 0.22225 -0.09144) (xy 0.21844 -0.10287)
						(xy 0.2159 -0.11303) (xy 0.21209 -0.12319) (xy 0.20701 -0.13335) (xy 0.2032 -0.14224) (xy 0.19812 -0.1524)
						(xy 0.17272 -0.18796) (xy 0.1651 -0.19558) (xy 0.1651 -0.7366) (xy 0.16256 -0.76835) (xy 0.1524 -0.8001)
						(xy 0.13716 -0.82804) (xy 0.11684 -0.85344) (xy 0.09144 -0.87376) (xy 0.0635 -0.889) (xy 0.03175 -0.89916)
					)
					(width 0)
					(fill yes)
				)
			)
		)
		(pad "172" smd custom
			(at 22.049994 4.100068 180)
			(size 0.1143 0.1143)
			(layers "B.Cu" "B.Mask" "B.Paste")
			(net "GND")
			(options
				(clearance outline)
				(anchor circle)
			)
			(primitives
				(gr_poly
					(pts
						(xy 0 -0.9017) (xy -0.03175 -0.89916) (xy -0.0635 -0.889) (xy -0.09144 -0.87376) (xy -0.11684 -0.85344)
						(xy -0.13716 -0.82804) (xy -0.1524 -0.8001) (xy -0.16256 -0.76835) (xy -0.1651 -0.7366) (xy -0.1651 -0.11938)
						(xy -0.17272 -0.11176) (xy -0.19812 -0.0762) (xy -0.2032 -0.06604) (xy -0.20701 -0.05715) (xy -0.21209 -0.04699)
						(xy -0.2159 -0.03683) (xy -0.21844 -0.02667) (xy -0.22225 -0.01524) (xy -0.22352 -0.00508) (xy -0.22606 0.00508)
						(xy -0.22733 0.01651) (xy -0.22733 0.02667) (xy -0.2286 0.0381) (xy -0.22733 0.04953) (xy -0.22733 0.05969)
						(xy -0.22606 0.07112) (xy -0.22352 0.08128) (xy -0.22225 0.09144) (xy -0.21844 0.10287) (xy -0.2159 0.11303)
						(xy -0.21209 0.12319) (xy -0.20701 0.13335) (xy -0.2032 0.14224) (xy -0.19812 0.1524) (xy -0.17272 0.18796)
						(xy -0.1651 0.19558) (xy -0.1651 0.7366) (xy -0.16256 0.76835) (xy -0.1524 0.8001) (xy -0.13716 0.82804)
						(xy -0.11684 0.85344) (xy -0.09144 0.87376) (xy -0.0635 0.889) (xy -0.03175 0.89916) (xy 0 0.9017)
						(xy 0.03175 0.89916) (xy 0.0635 0.889) (xy 0.09144 0.87376) (xy 0.11684 0.85344) (xy 0.13716 0.82804)
						(xy 0.1524 0.8001) (xy 0.16256 0.76835) (xy 0.1651 0.7366) (xy 0.1651 0.19685) (xy 0.17272 0.18923)
						(xy 0.17907 0.18034) (xy 0.18669 0.17145) (xy 0.19177 0.16256) (xy 0.19812 0.15367) (xy 0.20828 0.13335)
						(xy 0.21971 0.10287) (xy 0.22225 0.09271) (xy 0.22479 0.08128) (xy 0.22606 0.07112) (xy 0.2286 0.05969)
						(xy 0.2286 0.01651) (xy 0.22606 0.00508) (xy 0.22479 -0.00508) (xy 0.22225 -0.01651) (xy 0.21971 -0.02667)
						(xy 0.20828 -0.05715) (xy 0.19812 -0.07747) (xy 0.19177 -0.08636) (xy 0.18669 -0.09525) (xy 0.17907 -0.10414)
						(xy 0.17272 -0.11303) (xy 0.1651 -0.12065) (xy 0.1651 -0.7366) (xy 0.16256 -0.76835) (xy 0.1524 -0.8001)
						(xy 0.13716 -0.82804) (xy 0.11684 -0.85344) (xy 0.09144 -0.87376) (xy 0.0635 -0.889) (xy 0.03175 -0.89916)
					)
					(width 0)
					(fill yes)
				)
			)
		)
		(pad "173" smd custom
			(at 22.349968 -4.100068 180)
			(size 0.1143 0.1143)
			(layers "B.Cu" "B.Mask" "B.Paste")
			(net "M_B_DQS_DP6")
			(options
				(clearance outline)
				(anchor circle)
			)
			(primitives
				(gr_poly
					(pts
						(xy 0 -0.9017) (xy -0.03175 -0.89916) (xy -0.0635 -0.889) (xy -0.09144 -0.87376) (xy -0.11684 -0.85344)
						(xy -0.13716 -0.82804) (xy -0.1524 -0.8001) (xy -0.16256 -0.76835) (xy -0.1651 -0.7366) (xy -0.1651 -0.44958)
						(xy -0.17272 -0.44196) (xy -0.19812 -0.4064) (xy -0.2032 -0.39624) (xy -0.20701 -0.38735) (xy -0.21209 -0.37719)
						(xy -0.2159 -0.36703) (xy -0.21844 -0.35687) (xy -0.22225 -0.34544) (xy -0.22352 -0.33528) (xy -0.22606 -0.32512)
						(xy -0.22733 -0.31369) (xy -0.22733 -0.30353) (xy -0.2286 -0.2921) (xy -0.22733 -0.28067) (xy -0.22733 -0.27051)
						(xy -0.22606 -0.25908) (xy -0.22352 -0.24892) (xy -0.22225 -0.23876) (xy -0.21844 -0.22733) (xy -0.2159 -0.21717)
						(xy -0.21209 -0.20701) (xy -0.20701 -0.19685) (xy -0.2032 -0.18796) (xy -0.19812 -0.1778) (xy -0.17272 -0.14224)
						(xy -0.1651 -0.13462) (xy -0.1651 0.7366) (xy -0.16256 0.76835) (xy -0.1524 0.8001) (xy -0.13716 0.82804)
						(xy -0.11684 0.85344) (xy -0.09144 0.87376) (xy -0.0635 0.889) (xy -0.03175 0.89916) (xy 0 0.9017)
						(xy 0.03175 0.89916) (xy 0.0635 0.889) (xy 0.09144 0.87376) (xy 0.11684 0.85344) (xy 0.13716 0.82804)
						(xy 0.1524 0.8001) (xy 0.16256 0.76835) (xy 0.1651 0.7366) (xy 0.1651 -0.13462) (xy 0.17272 -0.14224)
						(xy 0.19812 -0.1778) (xy 0.2032 -0.18796) (xy 0.20701 -0.19685) (xy 0.21209 -0.20701) (xy 0.2159 -0.21717)
						(xy 0.21844 -0.22733) (xy 0.22225 -0.23876) (xy 0.22352 -0.24892) (xy 0.22606 -0.25908) (xy 0.22733 -0.27051)
						(xy 0.22733 -0.28067) (xy 0.2286 -0.2921) (xy 0.22733 -0.30353) (xy 0.22733 -0.31369) (xy 0.22606 -0.32512)
						(xy 0.22352 -0.33528) (xy 0.22225 -0.34544) (xy 0.21844 -0.35687) (xy 0.2159 -0.36703) (xy 0.21209 -0.37719)
						(xy 0.20701 -0.38735) (xy 0.2032 -0.39624) (xy 0.19812 -0.4064) (xy 0.17272 -0.44196) (xy 0.1651 -0.44958)
						(xy 0.1651 -0.7366) (xy 0.16256 -0.76835) (xy 0.1524 -0.8001) (xy 0.13716 -0.82804) (xy 0.11684 -0.85344)
						(xy 0.09144 -0.87376) (xy 0.0635 -0.889) (xy 0.03175 -0.89916)
					)
					(width 0)
					(fill yes)
				)
			)
		)
		(pad "174" smd custom
			(at 22.649942 4.100068 180)
			(size 0.1143 0.1143)
			(layers "B.Cu" "B.Mask" "B.Paste")
			(net "M_B_DQ54")
			(options
				(clearance outline)
				(anchor circle)
			)
			(primitives
				(gr_poly
					(pts
						(xy 0 -0.9017) (xy -0.03175 -0.89916) (xy -0.0635 -0.889) (xy -0.09144 -0.87376) (xy -0.11684 -0.85344)
						(xy -0.13716 -0.82804) (xy -0.1524 -0.8001) (xy -0.16256 -0.76835) (xy -0.1651 -0.7366) (xy -0.1651 0.13462)
						(xy -0.17272 0.14224) (xy -0.19812 0.1778) (xy -0.2032 0.18796) (xy -0.20701 0.19685) (xy -0.21209 0.20701)
						(xy -0.2159 0.21717) (xy -0.21844 0.22733) (xy -0.22225 0.23876) (xy -0.22352 0.24892) (xy -0.22606 0.25908)
						(xy -0.22733 0.27051) (xy -0.22733 0.28067) (xy -0.2286 0.2921) (xy -0.22733 0.30353) (xy -0.22733 0.31369)
						(xy -0.22606 0.32512) (xy -0.22352 0.33528) (xy -0.22225 0.34544) (xy -0.21844 0.35687) (xy -0.2159 0.36703)
						(xy -0.21209 0.37719) (xy -0.20701 0.38735) (xy -0.2032 0.39624) (xy -0.19812 0.4064) (xy -0.17272 0.44196)
						(xy -0.1651 0.44958) (xy -0.1651 0.7366) (xy -0.16256 0.76835) (xy -0.1524 0.8001) (xy -0.13716 0.82804)
						(xy -0.11684 0.85344) (xy -0.09144 0.87376) (xy -0.0635 0.889) (xy -0.03175 0.89916) (xy 0 0.9017)
						(xy 0.03175 0.89916) (xy 0.0635 0.889) (xy 0.09144 0.87376) (xy 0.11684 0.85344) (xy 0.13716 0.82804)
						(xy 0.1524 0.8001) (xy 0.16256 0.76835) (xy 0.1651 0.7366) (xy 0.1651 0.44958) (xy 0.17272 0.44196)
						(xy 0.19812 0.4064) (xy 0.2032 0.39624) (xy 0.20701 0.38735) (xy 0.21209 0.37719) (xy 0.2159 0.36703)
						(xy 0.21844 0.35687) (xy 0.22225 0.34544) (xy 0.22352 0.33528) (xy 0.22606 0.32512) (xy 0.22733 0.31369)
						(xy 0.22733 0.30353) (xy 0.2286 0.2921) (xy 0.22733 0.28067) (xy 0.22733 0.27051) (xy 0.22606 0.25908)
						(xy 0.22352 0.24892) (xy 0.22225 0.23876) (xy 0.21844 0.22733) (xy 0.2159 0.21717) (xy 0.21209 0.20701)
						(xy 0.20701 0.19685) (xy 0.2032 0.18796) (xy 0.19812 0.1778) (xy 0.17272 0.14224) (xy 0.1651 0.13462)
						(xy 0.1651 -0.7366) (xy 0.16256 -0.76835) (xy 0.1524 -0.8001) (xy 0.13716 -0.82804) (xy 0.11684 -0.85344)
						(xy 0.09144 -0.87376) (xy 0.0635 -0.889) (xy 0.03175 -0.89916)
					)
					(width 0)
					(fill yes)
				)
			)
		)
		(pad "175" smd custom
			(at 22.949916 -4.100068 180)
			(size 0.1143 0.1143)
			(layers "B.Cu" "B.Mask" "B.Paste")
			(net "GND")
			(options
				(clearance outline)
				(anchor circle)
			)
			(primitives
				(gr_poly
					(pts
						(xy 0 -0.9017) (xy -0.03175 -0.89916) (xy -0.0635 -0.889) (xy -0.09144 -0.87376) (xy -0.11684 -0.85344)
						(xy -0.13716 -0.82804) (xy -0.1524 -0.8001) (xy -0.16256 -0.76835) (xy -0.1651 -0.7366) (xy -0.1651 -0.19685)
						(xy -0.17272 -0.18923) (xy -0.17907 -0.18034) (xy -0.18669 -0.17145) (xy -0.19177 -0.16256) (xy -0.19812 -0.15367)
						(xy -0.20828 -0.13335) (xy -0.21971 -0.10287) (xy -0.22225 -0.09271) (xy -0.22479 -0.08128) (xy -0.22606 -0.07112)
						(xy -0.2286 -0.05969) (xy -0.2286 -0.01651) (xy -0.22606 -0.00508) (xy -0.22479 0.00508) (xy -0.22225 0.01651)
						(xy -0.21971 0.02667) (xy -0.20828 0.05715) (xy -0.19812 0.07747) (xy -0.19177 0.08636) (xy -0.18669 0.09525)
						(xy -0.17907 0.10414) (xy -0.17272 0.11303) (xy -0.1651 0.12065) (xy -0.1651 0.7366) (xy -0.16256 0.76835)
						(xy -0.1524 0.8001) (xy -0.13716 0.82804) (xy -0.11684 0.85344) (xy -0.09144 0.87376) (xy -0.0635 0.889)
						(xy -0.03175 0.89916) (xy 0 0.9017) (xy 0.03175 0.89916) (xy 0.0635 0.889) (xy 0.09144 0.87376)
						(xy 0.11684 0.85344) (xy 0.13716 0.82804) (xy 0.1524 0.8001) (xy 0.16256 0.76835) (xy 0.1651 0.7366)
						(xy 0.1651 0.11938) (xy 0.17272 0.11176) (xy 0.19812 0.0762) (xy 0.2032 0.06604) (xy 0.20701 0.05715)
						(xy 0.21209 0.04699) (xy 0.2159 0.03683) (xy 0.21844 0.02667) (xy 0.22225 0.01524) (xy 0.22352 0.00508)
						(xy 0.22606 -0.00508) (xy 0.22733 -0.01651) (xy 0.22733 -0.02667) (xy 0.2286 -0.0381) (xy 0.22733 -0.04953)
						(xy 0.22733 -0.05969) (xy 0.22606 -0.07112) (xy 0.22352 -0.08128) (xy 0.22225 -0.09144) (xy 0.21844 -0.10287)
						(xy 0.2159 -0.11303) (xy 0.21209 -0.12319) (xy 0.20701 -0.13335) (xy 0.2032 -0.14224) (xy 0.19812 -0.1524)
						(xy 0.17272 -0.18796) (xy 0.1651 -0.19558) (xy 0.1651 -0.7366) (xy 0.16256 -0.76835) (xy 0.1524 -0.8001)
						(xy 0.13716 -0.82804) (xy 0.11684 -0.85344) (xy 0.09144 -0.87376) (xy 0.0635 -0.889) (xy 0.03175 -0.89916)
					)
					(width 0)
					(fill yes)
				)
			)
		)
		(pad "176" smd custom
			(at 23.24989 4.100068 180)
			(size 0.1143 0.1143)
			(layers "B.Cu" "B.Mask" "B.Paste")
			(net "M_B_DQ55")
			(options
				(clearance outline)
				(anchor circle)
			)
			(primitives
				(gr_poly
					(pts
						(xy 0 -0.9017) (xy -0.03175 -0.89916) (xy -0.0635 -0.889) (xy -0.09144 -0.87376) (xy -0.11684 -0.85344)
						(xy -0.13716 -0.82804) (xy -0.1524 -0.8001) (xy -0.16256 -0.76835) (xy -0.1651 -0.7366) (xy -0.1651 -0.11938)
						(xy -0.17272 -0.11176) (xy -0.19812 -0.0762) (xy -0.2032 -0.06604) (xy -0.20701 -0.05715) (xy -0.21209 -0.04699)
						(xy -0.2159 -0.03683) (xy -0.21844 -0.02667) (xy -0.22225 -0.01524) (xy -0.22352 -0.00508) (xy -0.22606 0.00508)
						(xy -0.22733 0.01651) (xy -0.22733 0.02667) (xy -0.2286 0.0381) (xy -0.22733 0.04953) (xy -0.22733 0.05969)
						(xy -0.22606 0.07112) (xy -0.22352 0.08128) (xy -0.22225 0.09144) (xy -0.21844 0.10287) (xy -0.2159 0.11303)
						(xy -0.21209 0.12319) (xy -0.20701 0.13335) (xy -0.2032 0.14224) (xy -0.19812 0.1524) (xy -0.17272 0.18796)
						(xy -0.1651 0.19558) (xy -0.1651 0.7366) (xy -0.16256 0.76835) (xy -0.1524 0.8001) (xy -0.13716 0.82804)
						(xy -0.11684 0.85344) (xy -0.09144 0.87376) (xy -0.0635 0.889) (xy -0.03175 0.89916) (xy 0 0.9017)
						(xy 0.03175 0.89916) (xy 0.0635 0.889) (xy 0.09144 0.87376) (xy 0.11684 0.85344) (xy 0.13716 0.82804)
						(xy 0.1524 0.8001) (xy 0.16256 0.76835) (xy 0.1651 0.7366) (xy 0.1651 0.19685) (xy 0.17272 0.18923)
						(xy 0.17907 0.18034) (xy 0.18669 0.17145) (xy 0.19177 0.16256) (xy 0.19812 0.15367) (xy 0.20828 0.13335)
						(xy 0.21971 0.10287) (xy 0.22225 0.09271) (xy 0.22479 0.08128) (xy 0.22606 0.07112) (xy 0.2286 0.05969)
						(xy 0.2286 0.01651) (xy 0.22606 0.00508) (xy 0.22479 -0.00508) (xy 0.22225 -0.01651) (xy 0.21971 -0.02667)
						(xy 0.20828 -0.05715) (xy 0.19812 -0.07747) (xy 0.19177 -0.08636) (xy 0.18669 -0.09525) (xy 0.17907 -0.10414)
						(xy 0.17272 -0.11303) (xy 0.1651 -0.12065) (xy 0.1651 -0.7366) (xy 0.16256 -0.76835) (xy 0.1524 -0.8001)
						(xy 0.13716 -0.82804) (xy 0.11684 -0.85344) (xy 0.09144 -0.87376) (xy 0.0635 -0.889) (xy 0.03175 -0.89916)
					)
					(width 0)
					(fill yes)
				)
			)
		)
		(pad "177" smd custom
			(at 23.550118 -4.100068 180)
			(size 0.1143 0.1143)
			(layers "B.Cu" "B.Mask" "B.Paste")
			(net "M_B_DQ50")
			(options
				(clearance outline)
				(anchor circle)
			)
			(primitives
				(gr_poly
					(pts
						(xy 0 -0.9017) (xy -0.03175 -0.89916) (xy -0.0635 -0.889) (xy -0.09144 -0.87376) (xy -0.11684 -0.85344)
						(xy -0.13716 -0.82804) (xy -0.1524 -0.8001) (xy -0.16256 -0.76835) (xy -0.1651 -0.7366) (xy -0.1651 -0.44958)
						(xy -0.17272 -0.44196) (xy -0.19812 -0.4064) (xy -0.2032 -0.39624) (xy -0.20701 -0.38735) (xy -0.21209 -0.37719)
						(xy -0.2159 -0.36703) (xy -0.21844 -0.35687) (xy -0.22225 -0.34544) (xy -0.22352 -0.33528) (xy -0.22606 -0.32512)
						(xy -0.22733 -0.31369) (xy -0.22733 -0.30353) (xy -0.2286 -0.2921) (xy -0.22733 -0.28067) (xy -0.22733 -0.27051)
						(xy -0.22606 -0.25908) (xy -0.22352 -0.24892) (xy -0.22225 -0.23876) (xy -0.21844 -0.22733) (xy -0.2159 -0.21717)
						(xy -0.21209 -0.20701) (xy -0.20701 -0.19685) (xy -0.2032 -0.18796) (xy -0.19812 -0.1778) (xy -0.17272 -0.14224)
						(xy -0.1651 -0.13462) (xy -0.1651 0.7366) (xy -0.16256 0.76835) (xy -0.1524 0.8001) (xy -0.13716 0.82804)
						(xy -0.11684 0.85344) (xy -0.09144 0.87376) (xy -0.0635 0.889) (xy -0.03175 0.89916) (xy 0 0.9017)
						(xy 0.03175 0.89916) (xy 0.0635 0.889) (xy 0.09144 0.87376) (xy 0.11684 0.85344) (xy 0.13716 0.82804)
						(xy 0.1524 0.8001) (xy 0.16256 0.76835) (xy 0.1651 0.7366) (xy 0.1651 -0.13462) (xy 0.17272 -0.14224)
						(xy 0.19812 -0.1778) (xy 0.2032 -0.18796) (xy 0.20701 -0.19685) (xy 0.21209 -0.20701) (xy 0.2159 -0.21717)
						(xy 0.21844 -0.22733) (xy 0.22225 -0.23876) (xy 0.22352 -0.24892) (xy 0.22606 -0.25908) (xy 0.22733 -0.27051)
						(xy 0.22733 -0.28067) (xy 0.2286 -0.2921) (xy 0.22733 -0.30353) (xy 0.22733 -0.31369) (xy 0.22606 -0.32512)
						(xy 0.22352 -0.33528) (xy 0.22225 -0.34544) (xy 0.21844 -0.35687) (xy 0.2159 -0.36703) (xy 0.21209 -0.37719)
						(xy 0.20701 -0.38735) (xy 0.2032 -0.39624) (xy 0.19812 -0.4064) (xy 0.17272 -0.44196) (xy 0.1651 -0.44958)
						(xy 0.1651 -0.7366) (xy 0.16256 -0.76835) (xy 0.1524 -0.8001) (xy 0.13716 -0.82804) (xy 0.11684 -0.85344)
						(xy 0.09144 -0.87376) (xy 0.0635 -0.889) (xy 0.03175 -0.89916)
					)
					(width 0)
					(fill yes)
				)
			)
		)
		(pad "178" smd custom
			(at 23.850092 4.100068 180)
			(size 0.1143 0.1143)
			(layers "B.Cu" "B.Mask" "B.Paste")
			(net "GND")
			(options
				(clearance outline)
				(anchor circle)
			)
			(primitives
				(gr_poly
					(pts
						(xy 0 -0.9017) (xy -0.03175 -0.89916) (xy -0.0635 -0.889) (xy -0.09144 -0.87376) (xy -0.11684 -0.85344)
						(xy -0.13716 -0.82804) (xy -0.1524 -0.8001) (xy -0.16256 -0.76835) (xy -0.1651 -0.7366) (xy -0.1651 0.13462)
						(xy -0.17272 0.14224) (xy -0.19812 0.1778) (xy -0.2032 0.18796) (xy -0.20701 0.19685) (xy -0.21209 0.20701)
						(xy -0.2159 0.21717) (xy -0.21844 0.22733) (xy -0.22225 0.23876) (xy -0.22352 0.24892) (xy -0.22606 0.25908)
						(xy -0.22733 0.27051) (xy -0.22733 0.28067) (xy -0.2286 0.2921) (xy -0.22733 0.30353) (xy -0.22733 0.31369)
						(xy -0.22606 0.32512) (xy -0.22352 0.33528) (xy -0.22225 0.34544) (xy -0.21844 0.35687) (xy -0.2159 0.36703)
						(xy -0.21209 0.37719) (xy -0.20701 0.38735) (xy -0.2032 0.39624) (xy -0.19812 0.4064) (xy -0.17272 0.44196)
						(xy -0.1651 0.44958) (xy -0.1651 0.7366) (xy -0.16256 0.76835) (xy -0.1524 0.8001) (xy -0.13716 0.82804)
						(xy -0.11684 0.85344) (xy -0.09144 0.87376) (xy -0.0635 0.889) (xy -0.03175 0.89916) (xy 0 0.9017)
						(xy 0.03175 0.89916) (xy 0.0635 0.889) (xy 0.09144 0.87376) (xy 0.11684 0.85344) (xy 0.13716 0.82804)
						(xy 0.1524 0.8001) (xy 0.16256 0.76835) (xy 0.1651 0.7366) (xy 0.1651 0.44958) (xy 0.17272 0.44196)
						(xy 0.19812 0.4064) (xy 0.2032 0.39624) (xy 0.20701 0.38735) (xy 0.21209 0.37719) (xy 0.2159 0.36703)
						(xy 0.21844 0.35687) (xy 0.22225 0.34544) (xy 0.22352 0.33528) (xy 0.22606 0.32512) (xy 0.22733 0.31369)
						(xy 0.22733 0.30353) (xy 0.2286 0.2921) (xy 0.22733 0.28067) (xy 0.22733 0.27051) (xy 0.22606 0.25908)
						(xy 0.22352 0.24892) (xy 0.22225 0.23876) (xy 0.21844 0.22733) (xy 0.2159 0.21717) (xy 0.21209 0.20701)
						(xy 0.20701 0.19685) (xy 0.2032 0.18796) (xy 0.19812 0.1778) (xy 0.17272 0.14224) (xy 0.1651 0.13462)
						(xy 0.1651 -0.7366) (xy 0.16256 -0.76835) (xy 0.1524 -0.8001) (xy 0.13716 -0.82804) (xy 0.11684 -0.85344)
						(xy 0.09144 -0.87376) (xy 0.0635 -0.889) (xy 0.03175 -0.89916)
					)
					(width 0)
					(fill yes)
				)
			)
		)
		(pad "179" smd custom
			(at 24.150066 -4.100068 180)
			(size 0.1143 0.1143)
			(layers "B.Cu" "B.Mask" "B.Paste")
			(net "M_B_DQ51")
			(options
				(clearance outline)
				(anchor circle)
			)
			(primitives
				(gr_poly
					(pts
						(xy 0 -0.9017) (xy -0.03175 -0.89916) (xy -0.0635 -0.889) (xy -0.09144 -0.87376) (xy -0.11684 -0.85344)
						(xy -0.13716 -0.82804) (xy -0.1524 -0.8001) (xy -0.16256 -0.76835) (xy -0.1651 -0.7366) (xy -0.1651 -0.19685)
						(xy -0.17272 -0.18923) (xy -0.17907 -0.18034) (xy -0.18669 -0.17145) (xy -0.19177 -0.16256) (xy -0.19812 -0.15367)
						(xy -0.20828 -0.13335) (xy -0.21971 -0.10287) (xy -0.22225 -0.09271) (xy -0.22479 -0.08128) (xy -0.22606 -0.07112)
						(xy -0.2286 -0.05969) (xy -0.2286 -0.01651) (xy -0.22606 -0.00508) (xy -0.22479 0.00508) (xy -0.22225 0.01651)
						(xy -0.21971 0.02667) (xy -0.20828 0.05715) (xy -0.19812 0.07747) (xy -0.19177 0.08636) (xy -0.18669 0.09525)
						(xy -0.17907 0.10414) (xy -0.17272 0.11303) (xy -0.1651 0.12065) (xy -0.1651 0.7366) (xy -0.16256 0.76835)
						(xy -0.1524 0.8001) (xy -0.13716 0.82804) (xy -0.11684 0.85344) (xy -0.09144 0.87376) (xy -0.0635 0.889)
						(xy -0.03175 0.89916) (xy 0 0.9017) (xy 0.03175 0.89916) (xy 0.0635 0.889) (xy 0.09144 0.87376)
						(xy 0.11684 0.85344) (xy 0.13716 0.82804) (xy 0.1524 0.8001) (xy 0.16256 0.76835) (xy 0.1651 0.7366)
						(xy 0.1651 0.11938) (xy 0.17272 0.11176) (xy 0.19812 0.0762) (xy 0.2032 0.06604) (xy 0.20701 0.05715)
						(xy 0.21209 0.04699) (xy 0.2159 0.03683) (xy 0.21844 0.02667) (xy 0.22225 0.01524) (xy 0.22352 0.00508)
						(xy 0.22606 -0.00508) (xy 0.22733 -0.01651) (xy 0.22733 -0.02667) (xy 0.2286 -0.0381) (xy 0.22733 -0.04953)
						(xy 0.22733 -0.05969) (xy 0.22606 -0.07112) (xy 0.22352 -0.08128) (xy 0.22225 -0.09144) (xy 0.21844 -0.10287)
						(xy 0.2159 -0.11303) (xy 0.21209 -0.12319) (xy 0.20701 -0.13335) (xy 0.2032 -0.14224) (xy 0.19812 -0.1524)
						(xy 0.17272 -0.18796) (xy 0.1651 -0.19558) (xy 0.1651 -0.7366) (xy 0.16256 -0.76835) (xy 0.1524 -0.8001)
						(xy 0.13716 -0.82804) (xy 0.11684 -0.85344) (xy 0.09144 -0.87376) (xy 0.0635 -0.889) (xy 0.03175 -0.89916)
					)
					(width 0)
					(fill yes)
				)
			)
		)
		(pad "180" smd custom
			(at 24.45004 4.100068 180)
			(size 0.1143 0.1143)
			(layers "B.Cu" "B.Mask" "B.Paste")
			(net "M_B_DQ60")
			(options
				(clearance outline)
				(anchor circle)
			)
			(primitives
				(gr_poly
					(pts
						(xy 0 -0.9017) (xy -0.03175 -0.89916) (xy -0.0635 -0.889) (xy -0.09144 -0.87376) (xy -0.11684 -0.85344)
						(xy -0.13716 -0.82804) (xy -0.1524 -0.8001) (xy -0.16256 -0.76835) (xy -0.1651 -0.7366) (xy -0.1651 -0.11938)
						(xy -0.17272 -0.11176) (xy -0.19812 -0.0762) (xy -0.2032 -0.06604) (xy -0.20701 -0.05715) (xy -0.21209 -0.04699)
						(xy -0.2159 -0.03683) (xy -0.21844 -0.02667) (xy -0.22225 -0.01524) (xy -0.22352 -0.00508) (xy -0.22606 0.00508)
						(xy -0.22733 0.01651) (xy -0.22733 0.02667) (xy -0.2286 0.0381) (xy -0.22733 0.04953) (xy -0.22733 0.05969)
						(xy -0.22606 0.07112) (xy -0.22352 0.08128) (xy -0.22225 0.09144) (xy -0.21844 0.10287) (xy -0.2159 0.11303)
						(xy -0.21209 0.12319) (xy -0.20701 0.13335) (xy -0.2032 0.14224) (xy -0.19812 0.1524) (xy -0.17272 0.18796)
						(xy -0.1651 0.19558) (xy -0.1651 0.7366) (xy -0.16256 0.76835) (xy -0.1524 0.8001) (xy -0.13716 0.82804)
						(xy -0.11684 0.85344) (xy -0.09144 0.87376) (xy -0.0635 0.889) (xy -0.03175 0.89916) (xy 0 0.9017)
						(xy 0.03175 0.89916) (xy 0.0635 0.889) (xy 0.09144 0.87376) (xy 0.11684 0.85344) (xy 0.13716 0.82804)
						(xy 0.1524 0.8001) (xy 0.16256 0.76835) (xy 0.1651 0.7366) (xy 0.1651 0.19685) (xy 0.17272 0.18923)
						(xy 0.17907 0.18034) (xy 0.18669 0.17145) (xy 0.19177 0.16256) (xy 0.19812 0.15367) (xy 0.20828 0.13335)
						(xy 0.21971 0.10287) (xy 0.22225 0.09271) (xy 0.22479 0.08128) (xy 0.22606 0.07112) (xy 0.2286 0.05969)
						(xy 0.2286 0.01651) (xy 0.22606 0.00508) (xy 0.22479 -0.00508) (xy 0.22225 -0.01651) (xy 0.21971 -0.02667)
						(xy 0.20828 -0.05715) (xy 0.19812 -0.07747) (xy 0.19177 -0.08636) (xy 0.18669 -0.09525) (xy 0.17907 -0.10414)
						(xy 0.17272 -0.11303) (xy 0.1651 -0.12065) (xy 0.1651 -0.7366) (xy 0.16256 -0.76835) (xy 0.1524 -0.8001)
						(xy 0.13716 -0.82804) (xy 0.11684 -0.85344) (xy 0.09144 -0.87376) (xy 0.0635 -0.889) (xy 0.03175 -0.89916)
					)
					(width 0)
					(fill yes)
				)
			)
		)
		(pad "181" smd custom
			(at 24.750014 -4.100068 180)
			(size 0.1143 0.1143)
			(layers "B.Cu" "B.Mask" "B.Paste")
			(net "GND")
			(options
				(clearance outline)
				(anchor circle)
			)
			(primitives
				(gr_poly
					(pts
						(xy 0 -0.9017) (xy -0.03175 -0.89916) (xy -0.0635 -0.889) (xy -0.09144 -0.87376) (xy -0.11684 -0.85344)
						(xy -0.13716 -0.82804) (xy -0.1524 -0.8001) (xy -0.16256 -0.76835) (xy -0.1651 -0.7366) (xy -0.1651 -0.44958)
						(xy -0.17272 -0.44196) (xy -0.19812 -0.4064) (xy -0.2032 -0.39624) (xy -0.20701 -0.38735) (xy -0.21209 -0.37719)
						(xy -0.2159 -0.36703) (xy -0.21844 -0.35687) (xy -0.22225 -0.34544) (xy -0.22352 -0.33528) (xy -0.22606 -0.32512)
						(xy -0.22733 -0.31369) (xy -0.22733 -0.30353) (xy -0.2286 -0.2921) (xy -0.22733 -0.28067) (xy -0.22733 -0.27051)
						(xy -0.22606 -0.25908) (xy -0.22352 -0.24892) (xy -0.22225 -0.23876) (xy -0.21844 -0.22733) (xy -0.2159 -0.21717)
						(xy -0.21209 -0.20701) (xy -0.20701 -0.19685) (xy -0.2032 -0.18796) (xy -0.19812 -0.1778) (xy -0.17272 -0.14224)
						(xy -0.1651 -0.13462) (xy -0.1651 0.7366) (xy -0.16256 0.76835) (xy -0.1524 0.8001) (xy -0.13716 0.82804)
						(xy -0.11684 0.85344) (xy -0.09144 0.87376) (xy -0.0635 0.889) (xy -0.03175 0.89916) (xy 0 0.9017)
						(xy 0.03175 0.89916) (xy 0.0635 0.889) (xy 0.09144 0.87376) (xy 0.11684 0.85344) (xy 0.13716 0.82804)
						(xy 0.1524 0.8001) (xy 0.16256 0.76835) (xy 0.1651 0.7366) (xy 0.1651 -0.13462) (xy 0.17272 -0.14224)
						(xy 0.19812 -0.1778) (xy 0.2032 -0.18796) (xy 0.20701 -0.19685) (xy 0.21209 -0.20701) (xy 0.2159 -0.21717)
						(xy 0.21844 -0.22733) (xy 0.22225 -0.23876) (xy 0.22352 -0.24892) (xy 0.22606 -0.25908) (xy 0.22733 -0.27051)
						(xy 0.22733 -0.28067) (xy 0.2286 -0.2921) (xy 0.22733 -0.30353) (xy 0.22733 -0.31369) (xy 0.22606 -0.32512)
						(xy 0.22352 -0.33528) (xy 0.22225 -0.34544) (xy 0.21844 -0.35687) (xy 0.2159 -0.36703) (xy 0.21209 -0.37719)
						(xy 0.20701 -0.38735) (xy 0.2032 -0.39624) (xy 0.19812 -0.4064) (xy 0.17272 -0.44196) (xy 0.1651 -0.44958)
						(xy 0.1651 -0.7366) (xy 0.16256 -0.76835) (xy 0.1524 -0.8001) (xy 0.13716 -0.82804) (xy 0.11684 -0.85344)
						(xy 0.09144 -0.87376) (xy 0.0635 -0.889) (xy 0.03175 -0.89916)
					)
					(width 0)
					(fill yes)
				)
			)
		)
		(pad "182" smd custom
			(at 25.049988 4.100068 180)
			(size 0.1143 0.1143)
			(layers "B.Cu" "B.Mask" "B.Paste")
			(net "M_B_DQ61")
			(options
				(clearance outline)
				(anchor circle)
			)
			(primitives
				(gr_poly
					(pts
						(xy 0 -0.9017) (xy -0.03175 -0.89916) (xy -0.0635 -0.889) (xy -0.09144 -0.87376) (xy -0.11684 -0.85344)
						(xy -0.13716 -0.82804) (xy -0.1524 -0.8001) (xy -0.16256 -0.76835) (xy -0.1651 -0.7366) (xy -0.1651 0.13462)
						(xy -0.17272 0.14224) (xy -0.19812 0.1778) (xy -0.2032 0.18796) (xy -0.20701 0.19685) (xy -0.21209 0.20701)
						(xy -0.2159 0.21717) (xy -0.21844 0.22733) (xy -0.22225 0.23876) (xy -0.22352 0.24892) (xy -0.22606 0.25908)
						(xy -0.22733 0.27051) (xy -0.22733 0.28067) (xy -0.2286 0.2921) (xy -0.22733 0.30353) (xy -0.22733 0.31369)
						(xy -0.22606 0.32512) (xy -0.22352 0.33528) (xy -0.22225 0.34544) (xy -0.21844 0.35687) (xy -0.2159 0.36703)
						(xy -0.21209 0.37719) (xy -0.20701 0.38735) (xy -0.2032 0.39624) (xy -0.19812 0.4064) (xy -0.17272 0.44196)
						(xy -0.1651 0.44958) (xy -0.1651 0.7366) (xy -0.16256 0.76835) (xy -0.1524 0.8001) (xy -0.13716 0.82804)
						(xy -0.11684 0.85344) (xy -0.09144 0.87376) (xy -0.0635 0.889) (xy -0.03175 0.89916) (xy 0 0.9017)
						(xy 0.03175 0.89916) (xy 0.0635 0.889) (xy 0.09144 0.87376) (xy 0.11684 0.85344) (xy 0.13716 0.82804)
						(xy 0.1524 0.8001) (xy 0.16256 0.76835) (xy 0.1651 0.7366) (xy 0.1651 0.44958) (xy 0.17272 0.44196)
						(xy 0.19812 0.4064) (xy 0.2032 0.39624) (xy 0.20701 0.38735) (xy 0.21209 0.37719) (xy 0.2159 0.36703)
						(xy 0.21844 0.35687) (xy 0.22225 0.34544) (xy 0.22352 0.33528) (xy 0.22606 0.32512) (xy 0.22733 0.31369)
						(xy 0.22733 0.30353) (xy 0.2286 0.2921) (xy 0.22733 0.28067) (xy 0.22733 0.27051) (xy 0.22606 0.25908)
						(xy 0.22352 0.24892) (xy 0.22225 0.23876) (xy 0.21844 0.22733) (xy 0.2159 0.21717) (xy 0.21209 0.20701)
						(xy 0.20701 0.19685) (xy 0.2032 0.18796) (xy 0.19812 0.1778) (xy 0.17272 0.14224) (xy 0.1651 0.13462)
						(xy 0.1651 -0.7366) (xy 0.16256 -0.76835) (xy 0.1524 -0.8001) (xy 0.13716 -0.82804) (xy 0.11684 -0.85344)
						(xy 0.09144 -0.87376) (xy 0.0635 -0.889) (xy 0.03175 -0.89916)
					)
					(width 0)
					(fill yes)
				)
			)
		)
		(pad "183" smd custom
			(at 25.349962 -4.100068 180)
			(size 0.1143 0.1143)
			(layers "B.Cu" "B.Mask" "B.Paste")
			(net "M_B_DQ56")
			(options
				(clearance outline)
				(anchor circle)
			)
			(primitives
				(gr_poly
					(pts
						(xy 0 -0.9017) (xy -0.03175 -0.89916) (xy -0.0635 -0.889) (xy -0.09144 -0.87376) (xy -0.11684 -0.85344)
						(xy -0.13716 -0.82804) (xy -0.1524 -0.8001) (xy -0.16256 -0.76835) (xy -0.1651 -0.7366) (xy -0.1651 -0.19685)
						(xy -0.17272 -0.18923) (xy -0.17907 -0.18034) (xy -0.18669 -0.17145) (xy -0.19177 -0.16256) (xy -0.19812 -0.15367)
						(xy -0.20828 -0.13335) (xy -0.21971 -0.10287) (xy -0.22225 -0.09271) (xy -0.22479 -0.08128) (xy -0.22606 -0.07112)
						(xy -0.2286 -0.05969) (xy -0.2286 -0.01651) (xy -0.22606 -0.00508) (xy -0.22479 0.00508) (xy -0.22225 0.01651)
						(xy -0.21971 0.02667) (xy -0.20828 0.05715) (xy -0.19812 0.07747) (xy -0.19177 0.08636) (xy -0.18669 0.09525)
						(xy -0.17907 0.10414) (xy -0.17272 0.11303) (xy -0.1651 0.12065) (xy -0.1651 0.7366) (xy -0.16256 0.76835)
						(xy -0.1524 0.8001) (xy -0.13716 0.82804) (xy -0.11684 0.85344) (xy -0.09144 0.87376) (xy -0.0635 0.889)
						(xy -0.03175 0.89916) (xy 0 0.9017) (xy 0.03175 0.89916) (xy 0.0635 0.889) (xy 0.09144 0.87376)
						(xy 0.11684 0.85344) (xy 0.13716 0.82804) (xy 0.1524 0.8001) (xy 0.16256 0.76835) (xy 0.1651 0.7366)
						(xy 0.1651 0.11938) (xy 0.17272 0.11176) (xy 0.19812 0.0762) (xy 0.2032 0.06604) (xy 0.20701 0.05715)
						(xy 0.21209 0.04699) (xy 0.2159 0.03683) (xy 0.21844 0.02667) (xy 0.22225 0.01524) (xy 0.22352 0.00508)
						(xy 0.22606 -0.00508) (xy 0.22733 -0.01651) (xy 0.22733 -0.02667) (xy 0.2286 -0.0381) (xy 0.22733 -0.04953)
						(xy 0.22733 -0.05969) (xy 0.22606 -0.07112) (xy 0.22352 -0.08128) (xy 0.22225 -0.09144) (xy 0.21844 -0.10287)
						(xy 0.2159 -0.11303) (xy 0.21209 -0.12319) (xy 0.20701 -0.13335) (xy 0.2032 -0.14224) (xy 0.19812 -0.1524)
						(xy 0.17272 -0.18796) (xy 0.1651 -0.19558) (xy 0.1651 -0.7366) (xy 0.16256 -0.76835) (xy 0.1524 -0.8001)
						(xy 0.13716 -0.82804) (xy 0.11684 -0.85344) (xy 0.09144 -0.87376) (xy 0.0635 -0.889) (xy 0.03175 -0.89916)
					)
					(width 0)
					(fill yes)
				)
			)
		)
		(pad "184" smd custom
			(at 25.649936 4.100068 180)
			(size 0.1143 0.1143)
			(layers "B.Cu" "B.Mask" "B.Paste")
			(net "GND")
			(options
				(clearance outline)
				(anchor circle)
			)
			(primitives
				(gr_poly
					(pts
						(xy 0 -0.9017) (xy -0.03175 -0.89916) (xy -0.0635 -0.889) (xy -0.09144 -0.87376) (xy -0.11684 -0.85344)
						(xy -0.13716 -0.82804) (xy -0.1524 -0.8001) (xy -0.16256 -0.76835) (xy -0.1651 -0.7366) (xy -0.1651 -0.11938)
						(xy -0.17272 -0.11176) (xy -0.19812 -0.0762) (xy -0.2032 -0.06604) (xy -0.20701 -0.05715) (xy -0.21209 -0.04699)
						(xy -0.2159 -0.03683) (xy -0.21844 -0.02667) (xy -0.22225 -0.01524) (xy -0.22352 -0.00508) (xy -0.22606 0.00508)
						(xy -0.22733 0.01651) (xy -0.22733 0.02667) (xy -0.2286 0.0381) (xy -0.22733 0.04953) (xy -0.22733 0.05969)
						(xy -0.22606 0.07112) (xy -0.22352 0.08128) (xy -0.22225 0.09144) (xy -0.21844 0.10287) (xy -0.2159 0.11303)
						(xy -0.21209 0.12319) (xy -0.20701 0.13335) (xy -0.2032 0.14224) (xy -0.19812 0.1524) (xy -0.17272 0.18796)
						(xy -0.1651 0.19558) (xy -0.1651 0.7366) (xy -0.16256 0.76835) (xy -0.1524 0.8001) (xy -0.13716 0.82804)
						(xy -0.11684 0.85344) (xy -0.09144 0.87376) (xy -0.0635 0.889) (xy -0.03175 0.89916) (xy 0 0.9017)
						(xy 0.03175 0.89916) (xy 0.0635 0.889) (xy 0.09144 0.87376) (xy 0.11684 0.85344) (xy 0.13716 0.82804)
						(xy 0.1524 0.8001) (xy 0.16256 0.76835) (xy 0.1651 0.7366) (xy 0.1651 0.19685) (xy 0.17272 0.18923)
						(xy 0.17907 0.18034) (xy 0.18669 0.17145) (xy 0.19177 0.16256) (xy 0.19812 0.15367) (xy 0.20828 0.13335)
						(xy 0.21971 0.10287) (xy 0.22225 0.09271) (xy 0.22479 0.08128) (xy 0.22606 0.07112) (xy 0.2286 0.05969)
						(xy 0.2286 0.01651) (xy 0.22606 0.00508) (xy 0.22479 -0.00508) (xy 0.22225 -0.01651) (xy 0.21971 -0.02667)
						(xy 0.20828 -0.05715) (xy 0.19812 -0.07747) (xy 0.19177 -0.08636) (xy 0.18669 -0.09525) (xy 0.17907 -0.10414)
						(xy 0.17272 -0.11303) (xy 0.1651 -0.12065) (xy 0.1651 -0.7366) (xy 0.16256 -0.76835) (xy 0.1524 -0.8001)
						(xy 0.13716 -0.82804) (xy 0.11684 -0.85344) (xy 0.09144 -0.87376) (xy 0.0635 -0.889) (xy 0.03175 -0.89916)
					)
					(width 0)
					(fill yes)
				)
			)
		)
		(pad "185" smd custom
			(at 25.94991 -4.100068 180)
			(size 0.1143 0.1143)
			(layers "B.Cu" "B.Mask" "B.Paste")
			(net "M_B_DQ57")
			(options
				(clearance outline)
				(anchor circle)
			)
			(primitives
				(gr_poly
					(pts
						(xy 0 -0.9017) (xy -0.03175 -0.89916) (xy -0.0635 -0.889) (xy -0.09144 -0.87376) (xy -0.11684 -0.85344)
						(xy -0.13716 -0.82804) (xy -0.1524 -0.8001) (xy -0.16256 -0.76835) (xy -0.1651 -0.7366) (xy -0.1651 -0.44958)
						(xy -0.17272 -0.44196) (xy -0.19812 -0.4064) (xy -0.2032 -0.39624) (xy -0.20701 -0.38735) (xy -0.21209 -0.37719)
						(xy -0.2159 -0.36703) (xy -0.21844 -0.35687) (xy -0.22225 -0.34544) (xy -0.22352 -0.33528) (xy -0.22606 -0.32512)
						(xy -0.22733 -0.31369) (xy -0.22733 -0.30353) (xy -0.2286 -0.2921) (xy -0.22733 -0.28067) (xy -0.22733 -0.27051)
						(xy -0.22606 -0.25908) (xy -0.22352 -0.24892) (xy -0.22225 -0.23876) (xy -0.21844 -0.22733) (xy -0.2159 -0.21717)
						(xy -0.21209 -0.20701) (xy -0.20701 -0.19685) (xy -0.2032 -0.18796) (xy -0.19812 -0.1778) (xy -0.17272 -0.14224)
						(xy -0.1651 -0.13462) (xy -0.1651 0.7366) (xy -0.16256 0.76835) (xy -0.1524 0.8001) (xy -0.13716 0.82804)
						(xy -0.11684 0.85344) (xy -0.09144 0.87376) (xy -0.0635 0.889) (xy -0.03175 0.89916) (xy 0 0.9017)
						(xy 0.03175 0.89916) (xy 0.0635 0.889) (xy 0.09144 0.87376) (xy 0.11684 0.85344) (xy 0.13716 0.82804)
						(xy 0.1524 0.8001) (xy 0.16256 0.76835) (xy 0.1651 0.7366) (xy 0.1651 -0.13462) (xy 0.17272 -0.14224)
						(xy 0.19812 -0.1778) (xy 0.2032 -0.18796) (xy 0.20701 -0.19685) (xy 0.21209 -0.20701) (xy 0.2159 -0.21717)
						(xy 0.21844 -0.22733) (xy 0.22225 -0.23876) (xy 0.22352 -0.24892) (xy 0.22606 -0.25908) (xy 0.22733 -0.27051)
						(xy 0.22733 -0.28067) (xy 0.2286 -0.2921) (xy 0.22733 -0.30353) (xy 0.22733 -0.31369) (xy 0.22606 -0.32512)
						(xy 0.22352 -0.33528) (xy 0.22225 -0.34544) (xy 0.21844 -0.35687) (xy 0.2159 -0.36703) (xy 0.21209 -0.37719)
						(xy 0.20701 -0.38735) (xy 0.2032 -0.39624) (xy 0.19812 -0.4064) (xy 0.17272 -0.44196) (xy 0.1651 -0.44958)
						(xy 0.1651 -0.7366) (xy 0.16256 -0.76835) (xy 0.1524 -0.8001) (xy 0.13716 -0.82804) (xy 0.11684 -0.85344)
						(xy 0.09144 -0.87376) (xy 0.0635 -0.889) (xy 0.03175 -0.89916)
					)
					(width 0)
					(fill yes)
				)
			)
		)
		(pad "186" smd custom
			(at 26.249884 4.100068 180)
			(size 0.1143 0.1143)
			(layers "B.Cu" "B.Mask" "B.Paste")
			(net "M_B_DQS_DN7")
			(options
				(clearance outline)
				(anchor circle)
			)
			(primitives
				(gr_poly
					(pts
						(xy 0 -0.9017) (xy -0.03175 -0.89916) (xy -0.0635 -0.889) (xy -0.09144 -0.87376) (xy -0.11684 -0.85344)
						(xy -0.13716 -0.82804) (xy -0.1524 -0.8001) (xy -0.16256 -0.76835) (xy -0.1651 -0.7366) (xy -0.1651 0.13462)
						(xy -0.17272 0.14224) (xy -0.19812 0.1778) (xy -0.2032 0.18796) (xy -0.20701 0.19685) (xy -0.21209 0.20701)
						(xy -0.2159 0.21717) (xy -0.21844 0.22733) (xy -0.22225 0.23876) (xy -0.22352 0.24892) (xy -0.22606 0.25908)
						(xy -0.22733 0.27051) (xy -0.22733 0.28067) (xy -0.2286 0.2921) (xy -0.22733 0.30353) (xy -0.22733 0.31369)
						(xy -0.22606 0.32512) (xy -0.22352 0.33528) (xy -0.22225 0.34544) (xy -0.21844 0.35687) (xy -0.2159 0.36703)
						(xy -0.21209 0.37719) (xy -0.20701 0.38735) (xy -0.2032 0.39624) (xy -0.19812 0.4064) (xy -0.17272 0.44196)
						(xy -0.1651 0.44958) (xy -0.1651 0.7366) (xy -0.16256 0.76835) (xy -0.1524 0.8001) (xy -0.13716 0.82804)
						(xy -0.11684 0.85344) (xy -0.09144 0.87376) (xy -0.0635 0.889) (xy -0.03175 0.89916) (xy 0 0.9017)
						(xy 0.03175 0.89916) (xy 0.0635 0.889) (xy 0.09144 0.87376) (xy 0.11684 0.85344) (xy 0.13716 0.82804)
						(xy 0.1524 0.8001) (xy 0.16256 0.76835) (xy 0.1651 0.7366) (xy 0.1651 0.44958) (xy 0.17272 0.44196)
						(xy 0.19812 0.4064) (xy 0.2032 0.39624) (xy 0.20701 0.38735) (xy 0.21209 0.37719) (xy 0.2159 0.36703)
						(xy 0.21844 0.35687) (xy 0.22225 0.34544) (xy 0.22352 0.33528) (xy 0.22606 0.32512) (xy 0.22733 0.31369)
						(xy 0.22733 0.30353) (xy 0.2286 0.2921) (xy 0.22733 0.28067) (xy 0.22733 0.27051) (xy 0.22606 0.25908)
						(xy 0.22352 0.24892) (xy 0.22225 0.23876) (xy 0.21844 0.22733) (xy 0.2159 0.21717) (xy 0.21209 0.20701)
						(xy 0.20701 0.19685) (xy 0.2032 0.18796) (xy 0.19812 0.1778) (xy 0.17272 0.14224) (xy 0.1651 0.13462)
						(xy 0.1651 -0.7366) (xy 0.16256 -0.76835) (xy 0.1524 -0.8001) (xy 0.13716 -0.82804) (xy 0.11684 -0.85344)
						(xy 0.09144 -0.87376) (xy 0.0635 -0.889) (xy 0.03175 -0.89916)
					)
					(width 0)
					(fill yes)
				)
			)
		)
		(pad "187" smd custom
			(at 26.550112 -4.100068 180)
			(size 0.1143 0.1143)
			(layers "B.Cu" "B.Mask" "B.Paste")
			(net "GND")
			(options
				(clearance outline)
				(anchor circle)
			)
			(primitives
				(gr_poly
					(pts
						(xy 0 -0.9017) (xy -0.03175 -0.89916) (xy -0.0635 -0.889) (xy -0.09144 -0.87376) (xy -0.11684 -0.85344)
						(xy -0.13716 -0.82804) (xy -0.1524 -0.8001) (xy -0.16256 -0.76835) (xy -0.1651 -0.7366) (xy -0.1651 -0.19685)
						(xy -0.17272 -0.18923) (xy -0.17907 -0.18034) (xy -0.18669 -0.17145) (xy -0.19177 -0.16256) (xy -0.19812 -0.15367)
						(xy -0.20828 -0.13335) (xy -0.21971 -0.10287) (xy -0.22225 -0.09271) (xy -0.22479 -0.08128) (xy -0.22606 -0.07112)
						(xy -0.2286 -0.05969) (xy -0.2286 -0.01651) (xy -0.22606 -0.00508) (xy -0.22479 0.00508) (xy -0.22225 0.01651)
						(xy -0.21971 0.02667) (xy -0.20828 0.05715) (xy -0.19812 0.07747) (xy -0.19177 0.08636) (xy -0.18669 0.09525)
						(xy -0.17907 0.10414) (xy -0.17272 0.11303) (xy -0.1651 0.12065) (xy -0.1651 0.7366) (xy -0.16256 0.76835)
						(xy -0.1524 0.8001) (xy -0.13716 0.82804) (xy -0.11684 0.85344) (xy -0.09144 0.87376) (xy -0.0635 0.889)
						(xy -0.03175 0.89916) (xy 0 0.9017) (xy 0.03175 0.89916) (xy 0.0635 0.889) (xy 0.09144 0.87376)
						(xy 0.11684 0.85344) (xy 0.13716 0.82804) (xy 0.1524 0.8001) (xy 0.16256 0.76835) (xy 0.1651 0.7366)
						(xy 0.1651 0.11938) (xy 0.17272 0.11176) (xy 0.19812 0.0762) (xy 0.2032 0.06604) (xy 0.20701 0.05715)
						(xy 0.21209 0.04699) (xy 0.2159 0.03683) (xy 0.21844 0.02667) (xy 0.22225 0.01524) (xy 0.22352 0.00508)
						(xy 0.22606 -0.00508) (xy 0.22733 -0.01651) (xy 0.22733 -0.02667) (xy 0.2286 -0.0381) (xy 0.22733 -0.04953)
						(xy 0.22733 -0.05969) (xy 0.22606 -0.07112) (xy 0.22352 -0.08128) (xy 0.22225 -0.09144) (xy 0.21844 -0.10287)
						(xy 0.2159 -0.11303) (xy 0.21209 -0.12319) (xy 0.20701 -0.13335) (xy 0.2032 -0.14224) (xy 0.19812 -0.1524)
						(xy 0.17272 -0.18796) (xy 0.1651 -0.19558) (xy 0.1651 -0.7366) (xy 0.16256 -0.76835) (xy 0.1524 -0.8001)
						(xy 0.13716 -0.82804) (xy 0.11684 -0.85344) (xy 0.09144 -0.87376) (xy 0.0635 -0.889) (xy 0.03175 -0.89916)
					)
					(width 0)
					(fill yes)
				)
			)
		)
		(pad "188" smd custom
			(at 26.850086 4.100068 180)
			(size 0.1143 0.1143)
			(layers "B.Cu" "B.Mask" "B.Paste")
			(net "M_B_DQS_DP7")
			(options
				(clearance outline)
				(anchor circle)
			)
			(primitives
				(gr_poly
					(pts
						(xy 0 -0.9017) (xy -0.03175 -0.89916) (xy -0.0635 -0.889) (xy -0.09144 -0.87376) (xy -0.11684 -0.85344)
						(xy -0.13716 -0.82804) (xy -0.1524 -0.8001) (xy -0.16256 -0.76835) (xy -0.1651 -0.7366) (xy -0.1651 -0.11938)
						(xy -0.17272 -0.11176) (xy -0.19812 -0.0762) (xy -0.2032 -0.06604) (xy -0.20701 -0.05715) (xy -0.21209 -0.04699)
						(xy -0.2159 -0.03683) (xy -0.21844 -0.02667) (xy -0.22225 -0.01524) (xy -0.22352 -0.00508) (xy -0.22606 0.00508)
						(xy -0.22733 0.01651) (xy -0.22733 0.02667) (xy -0.2286 0.0381) (xy -0.22733 0.04953) (xy -0.22733 0.05969)
						(xy -0.22606 0.07112) (xy -0.22352 0.08128) (xy -0.22225 0.09144) (xy -0.21844 0.10287) (xy -0.2159 0.11303)
						(xy -0.21209 0.12319) (xy -0.20701 0.13335) (xy -0.2032 0.14224) (xy -0.19812 0.1524) (xy -0.17272 0.18796)
						(xy -0.1651 0.19558) (xy -0.1651 0.7366) (xy -0.16256 0.76835) (xy -0.1524 0.8001) (xy -0.13716 0.82804)
						(xy -0.11684 0.85344) (xy -0.09144 0.87376) (xy -0.0635 0.889) (xy -0.03175 0.89916) (xy 0 0.9017)
						(xy 0.03175 0.89916) (xy 0.0635 0.889) (xy 0.09144 0.87376) (xy 0.11684 0.85344) (xy 0.13716 0.82804)
						(xy 0.1524 0.8001) (xy 0.16256 0.76835) (xy 0.1651 0.7366) (xy 0.1651 0.19685) (xy 0.17272 0.18923)
						(xy 0.17907 0.18034) (xy 0.18669 0.17145) (xy 0.19177 0.16256) (xy 0.19812 0.15367) (xy 0.20828 0.13335)
						(xy 0.21971 0.10287) (xy 0.22225 0.09271) (xy 0.22479 0.08128) (xy 0.22606 0.07112) (xy 0.2286 0.05969)
						(xy 0.2286 0.01651) (xy 0.22606 0.00508) (xy 0.22479 -0.00508) (xy 0.22225 -0.01651) (xy 0.21971 -0.02667)
						(xy 0.20828 -0.05715) (xy 0.19812 -0.07747) (xy 0.19177 -0.08636) (xy 0.18669 -0.09525) (xy 0.17907 -0.10414)
						(xy 0.17272 -0.11303) (xy 0.1651 -0.12065) (xy 0.1651 -0.7366) (xy 0.16256 -0.76835) (xy 0.1524 -0.8001)
						(xy 0.13716 -0.82804) (xy 0.11684 -0.85344) (xy 0.09144 -0.87376) (xy 0.0635 -0.889) (xy 0.03175 -0.89916)
					)
					(width 0)
					(fill yes)
				)
			)
		)
		(pad "189" smd custom
			(at 27.15006 -4.100068 180)
			(size 0.1143 0.1143)
			(layers "B.Cu" "B.Mask" "B.Paste")
			(net "GND")
			(options
				(clearance outline)
				(anchor circle)
			)
			(primitives
				(gr_poly
					(pts
						(xy 0 -0.9017) (xy -0.03175 -0.89916) (xy -0.0635 -0.889) (xy -0.09144 -0.87376) (xy -0.11684 -0.85344)
						(xy -0.13716 -0.82804) (xy -0.1524 -0.8001) (xy -0.16256 -0.76835) (xy -0.1651 -0.7366) (xy -0.1651 -0.44958)
						(xy -0.17272 -0.44196) (xy -0.19812 -0.4064) (xy -0.2032 -0.39624) (xy -0.20701 -0.38735) (xy -0.21209 -0.37719)
						(xy -0.2159 -0.36703) (xy -0.21844 -0.35687) (xy -0.22225 -0.34544) (xy -0.22352 -0.33528) (xy -0.22606 -0.32512)
						(xy -0.22733 -0.31369) (xy -0.22733 -0.30353) (xy -0.2286 -0.2921) (xy -0.22733 -0.28067) (xy -0.22733 -0.27051)
						(xy -0.22606 -0.25908) (xy -0.22352 -0.24892) (xy -0.22225 -0.23876) (xy -0.21844 -0.22733) (xy -0.2159 -0.21717)
						(xy -0.21209 -0.20701) (xy -0.20701 -0.19685) (xy -0.2032 -0.18796) (xy -0.19812 -0.1778) (xy -0.17272 -0.14224)
						(xy -0.1651 -0.13462) (xy -0.1651 0.7366) (xy -0.16256 0.76835) (xy -0.1524 0.8001) (xy -0.13716 0.82804)
						(xy -0.11684 0.85344) (xy -0.09144 0.87376) (xy -0.0635 0.889) (xy -0.03175 0.89916) (xy 0 0.9017)
						(xy 0.03175 0.89916) (xy 0.0635 0.889) (xy 0.09144 0.87376) (xy 0.11684 0.85344) (xy 0.13716 0.82804)
						(xy 0.1524 0.8001) (xy 0.16256 0.76835) (xy 0.1651 0.7366) (xy 0.1651 -0.13462) (xy 0.17272 -0.14224)
						(xy 0.19812 -0.1778) (xy 0.2032 -0.18796) (xy 0.20701 -0.19685) (xy 0.21209 -0.20701) (xy 0.2159 -0.21717)
						(xy 0.21844 -0.22733) (xy 0.22225 -0.23876) (xy 0.22352 -0.24892) (xy 0.22606 -0.25908) (xy 0.22733 -0.27051)
						(xy 0.22733 -0.28067) (xy 0.2286 -0.2921) (xy 0.22733 -0.30353) (xy 0.22733 -0.31369) (xy 0.22606 -0.32512)
						(xy 0.22352 -0.33528) (xy 0.22225 -0.34544) (xy 0.21844 -0.35687) (xy 0.2159 -0.36703) (xy 0.21209 -0.37719)
						(xy 0.20701 -0.38735) (xy 0.2032 -0.39624) (xy 0.19812 -0.4064) (xy 0.17272 -0.44196) (xy 0.1651 -0.44958)
						(xy 0.1651 -0.7366) (xy 0.16256 -0.76835) (xy 0.1524 -0.8001) (xy 0.13716 -0.82804) (xy 0.11684 -0.85344)
						(xy 0.09144 -0.87376) (xy 0.0635 -0.889) (xy 0.03175 -0.89916)
					)
					(width 0)
					(fill yes)
				)
			)
		)
		(pad "190" smd custom
			(at 27.450034 4.100068 180)
			(size 0.1143 0.1143)
			(layers "B.Cu" "B.Mask" "B.Paste")
			(net "GND")
			(options
				(clearance outline)
				(anchor circle)
			)
			(primitives
				(gr_poly
					(pts
						(xy 0 -0.9017) (xy -0.03175 -0.89916) (xy -0.0635 -0.889) (xy -0.09144 -0.87376) (xy -0.11684 -0.85344)
						(xy -0.13716 -0.82804) (xy -0.1524 -0.8001) (xy -0.16256 -0.76835) (xy -0.1651 -0.7366) (xy -0.1651 0.13462)
						(xy -0.17272 0.14224) (xy -0.19812 0.1778) (xy -0.2032 0.18796) (xy -0.20701 0.19685) (xy -0.21209 0.20701)
						(xy -0.2159 0.21717) (xy -0.21844 0.22733) (xy -0.22225 0.23876) (xy -0.22352 0.24892) (xy -0.22606 0.25908)
						(xy -0.22733 0.27051) (xy -0.22733 0.28067) (xy -0.2286 0.2921) (xy -0.22733 0.30353) (xy -0.22733 0.31369)
						(xy -0.22606 0.32512) (xy -0.22352 0.33528) (xy -0.22225 0.34544) (xy -0.21844 0.35687) (xy -0.2159 0.36703)
						(xy -0.21209 0.37719) (xy -0.20701 0.38735) (xy -0.2032 0.39624) (xy -0.19812 0.4064) (xy -0.17272 0.44196)
						(xy -0.1651 0.44958) (xy -0.1651 0.7366) (xy -0.16256 0.76835) (xy -0.1524 0.8001) (xy -0.13716 0.82804)
						(xy -0.11684 0.85344) (xy -0.09144 0.87376) (xy -0.0635 0.889) (xy -0.03175 0.89916) (xy 0 0.9017)
						(xy 0.03175 0.89916) (xy 0.0635 0.889) (xy 0.09144 0.87376) (xy 0.11684 0.85344) (xy 0.13716 0.82804)
						(xy 0.1524 0.8001) (xy 0.16256 0.76835) (xy 0.1651 0.7366) (xy 0.1651 0.44958) (xy 0.17272 0.44196)
						(xy 0.19812 0.4064) (xy 0.2032 0.39624) (xy 0.20701 0.38735) (xy 0.21209 0.37719) (xy 0.2159 0.36703)
						(xy 0.21844 0.35687) (xy 0.22225 0.34544) (xy 0.22352 0.33528) (xy 0.22606 0.32512) (xy 0.22733 0.31369)
						(xy 0.22733 0.30353) (xy 0.2286 0.2921) (xy 0.22733 0.28067) (xy 0.22733 0.27051) (xy 0.22606 0.25908)
						(xy 0.22352 0.24892) (xy 0.22225 0.23876) (xy 0.21844 0.22733) (xy 0.2159 0.21717) (xy 0.21209 0.20701)
						(xy 0.20701 0.19685) (xy 0.2032 0.18796) (xy 0.19812 0.1778) (xy 0.17272 0.14224) (xy 0.1651 0.13462)
						(xy 0.1651 -0.7366) (xy 0.16256 -0.76835) (xy 0.1524 -0.8001) (xy 0.13716 -0.82804) (xy 0.11684 -0.85344)
						(xy 0.09144 -0.87376) (xy 0.0635 -0.889) (xy 0.03175 -0.89916)
					)
					(width 0)
					(fill yes)
				)
			)
		)
		(pad "191" smd custom
			(at 27.750008 -4.100068 180)
			(size 0.1143 0.1143)
			(layers "B.Cu" "B.Mask" "B.Paste")
			(net "M_B_DQ58")
			(options
				(clearance outline)
				(anchor circle)
			)
			(primitives
				(gr_poly
					(pts
						(xy 0 -0.9017) (xy -0.03175 -0.89916) (xy -0.0635 -0.889) (xy -0.09144 -0.87376) (xy -0.11684 -0.85344)
						(xy -0.13716 -0.82804) (xy -0.1524 -0.8001) (xy -0.16256 -0.76835) (xy -0.1651 -0.7366) (xy -0.1651 -0.19685)
						(xy -0.17272 -0.18923) (xy -0.17907 -0.18034) (xy -0.18669 -0.17145) (xy -0.19177 -0.16256) (xy -0.19812 -0.15367)
						(xy -0.20828 -0.13335) (xy -0.21971 -0.10287) (xy -0.22225 -0.09271) (xy -0.22479 -0.08128) (xy -0.22606 -0.07112)
						(xy -0.2286 -0.05969) (xy -0.2286 -0.01651) (xy -0.22606 -0.00508) (xy -0.22479 0.00508) (xy -0.22225 0.01651)
						(xy -0.21971 0.02667) (xy -0.20828 0.05715) (xy -0.19812 0.07747) (xy -0.19177 0.08636) (xy -0.18669 0.09525)
						(xy -0.17907 0.10414) (xy -0.17272 0.11303) (xy -0.1651 0.12065) (xy -0.1651 0.7366) (xy -0.16256 0.76835)
						(xy -0.1524 0.8001) (xy -0.13716 0.82804) (xy -0.11684 0.85344) (xy -0.09144 0.87376) (xy -0.0635 0.889)
						(xy -0.03175 0.89916) (xy 0 0.9017) (xy 0.03175 0.89916) (xy 0.0635 0.889) (xy 0.09144 0.87376)
						(xy 0.11684 0.85344) (xy 0.13716 0.82804) (xy 0.1524 0.8001) (xy 0.16256 0.76835) (xy 0.1651 0.7366)
						(xy 0.1651 0.11938) (xy 0.17272 0.11176) (xy 0.19812 0.0762) (xy 0.2032 0.06604) (xy 0.20701 0.05715)
						(xy 0.21209 0.04699) (xy 0.2159 0.03683) (xy 0.21844 0.02667) (xy 0.22225 0.01524) (xy 0.22352 0.00508)
						(xy 0.22606 -0.00508) (xy 0.22733 -0.01651) (xy 0.22733 -0.02667) (xy 0.2286 -0.0381) (xy 0.22733 -0.04953)
						(xy 0.22733 -0.05969) (xy 0.22606 -0.07112) (xy 0.22352 -0.08128) (xy 0.22225 -0.09144) (xy 0.21844 -0.10287)
						(xy 0.2159 -0.11303) (xy 0.21209 -0.12319) (xy 0.20701 -0.13335) (xy 0.2032 -0.14224) (xy 0.19812 -0.1524)
						(xy 0.17272 -0.18796) (xy 0.1651 -0.19558) (xy 0.1651 -0.7366) (xy 0.16256 -0.76835) (xy 0.1524 -0.8001)
						(xy 0.13716 -0.82804) (xy 0.11684 -0.85344) (xy 0.09144 -0.87376) (xy 0.0635 -0.889) (xy 0.03175 -0.89916)
					)
					(width 0)
					(fill yes)
				)
			)
		)
		(pad "192" smd custom
			(at 28.049982 4.100068 180)
			(size 0.1143 0.1143)
			(layers "B.Cu" "B.Mask" "B.Paste")
			(net "M_B_DQ62")
			(options
				(clearance outline)
				(anchor circle)
			)
			(primitives
				(gr_poly
					(pts
						(xy 0 -0.9017) (xy -0.03175 -0.89916) (xy -0.0635 -0.889) (xy -0.09144 -0.87376) (xy -0.11684 -0.85344)
						(xy -0.13716 -0.82804) (xy -0.1524 -0.8001) (xy -0.16256 -0.76835) (xy -0.1651 -0.7366) (xy -0.1651 -0.11938)
						(xy -0.17272 -0.11176) (xy -0.19812 -0.0762) (xy -0.2032 -0.06604) (xy -0.20701 -0.05715) (xy -0.21209 -0.04699)
						(xy -0.2159 -0.03683) (xy -0.21844 -0.02667) (xy -0.22225 -0.01524) (xy -0.22352 -0.00508) (xy -0.22606 0.00508)
						(xy -0.22733 0.01651) (xy -0.22733 0.02667) (xy -0.2286 0.0381) (xy -0.22733 0.04953) (xy -0.22733 0.05969)
						(xy -0.22606 0.07112) (xy -0.22352 0.08128) (xy -0.22225 0.09144) (xy -0.21844 0.10287) (xy -0.2159 0.11303)
						(xy -0.21209 0.12319) (xy -0.20701 0.13335) (xy -0.2032 0.14224) (xy -0.19812 0.1524) (xy -0.17272 0.18796)
						(xy -0.1651 0.19558) (xy -0.1651 0.7366) (xy -0.16256 0.76835) (xy -0.1524 0.8001) (xy -0.13716 0.82804)
						(xy -0.11684 0.85344) (xy -0.09144 0.87376) (xy -0.0635 0.889) (xy -0.03175 0.89916) (xy 0 0.9017)
						(xy 0.03175 0.89916) (xy 0.0635 0.889) (xy 0.09144 0.87376) (xy 0.11684 0.85344) (xy 0.13716 0.82804)
						(xy 0.1524 0.8001) (xy 0.16256 0.76835) (xy 0.1651 0.7366) (xy 0.1651 0.19685) (xy 0.17272 0.18923)
						(xy 0.17907 0.18034) (xy 0.18669 0.17145) (xy 0.19177 0.16256) (xy 0.19812 0.15367) (xy 0.20828 0.13335)
						(xy 0.21971 0.10287) (xy 0.22225 0.09271) (xy 0.22479 0.08128) (xy 0.22606 0.07112) (xy 0.2286 0.05969)
						(xy 0.2286 0.01651) (xy 0.22606 0.00508) (xy 0.22479 -0.00508) (xy 0.22225 -0.01651) (xy 0.21971 -0.02667)
						(xy 0.20828 -0.05715) (xy 0.19812 -0.07747) (xy 0.19177 -0.08636) (xy 0.18669 -0.09525) (xy 0.17907 -0.10414)
						(xy 0.17272 -0.11303) (xy 0.1651 -0.12065) (xy 0.1651 -0.7366) (xy 0.16256 -0.76835) (xy 0.1524 -0.8001)
						(xy 0.13716 -0.82804) (xy 0.11684 -0.85344) (xy 0.09144 -0.87376) (xy 0.0635 -0.889) (xy 0.03175 -0.89916)
					)
					(width 0)
					(fill yes)
				)
			)
		)
		(pad "193" smd custom
			(at 28.349956 -4.100068 180)
			(size 0.1143 0.1143)
			(layers "B.Cu" "B.Mask" "B.Paste")
			(net "M_B_DQ59")
			(options
				(clearance outline)
				(anchor circle)
			)
			(primitives
				(gr_poly
					(pts
						(xy 0 -0.9017) (xy -0.03175 -0.89916) (xy -0.0635 -0.889) (xy -0.09144 -0.87376) (xy -0.11684 -0.85344)
						(xy -0.13716 -0.82804) (xy -0.1524 -0.8001) (xy -0.16256 -0.76835) (xy -0.1651 -0.7366) (xy -0.1651 -0.44958)
						(xy -0.17272 -0.44196) (xy -0.19812 -0.4064) (xy -0.2032 -0.39624) (xy -0.20701 -0.38735) (xy -0.21209 -0.37719)
						(xy -0.2159 -0.36703) (xy -0.21844 -0.35687) (xy -0.22225 -0.34544) (xy -0.22352 -0.33528) (xy -0.22606 -0.32512)
						(xy -0.22733 -0.31369) (xy -0.22733 -0.30353) (xy -0.2286 -0.2921) (xy -0.22733 -0.28067) (xy -0.22733 -0.27051)
						(xy -0.22606 -0.25908) (xy -0.22352 -0.24892) (xy -0.22225 -0.23876) (xy -0.21844 -0.22733) (xy -0.2159 -0.21717)
						(xy -0.21209 -0.20701) (xy -0.20701 -0.19685) (xy -0.2032 -0.18796) (xy -0.19812 -0.1778) (xy -0.17272 -0.14224)
						(xy -0.1651 -0.13462) (xy -0.1651 0.7366) (xy -0.16256 0.76835) (xy -0.1524 0.8001) (xy -0.13716 0.82804)
						(xy -0.11684 0.85344) (xy -0.09144 0.87376) (xy -0.0635 0.889) (xy -0.03175 0.89916) (xy 0 0.9017)
						(xy 0.03175 0.89916) (xy 0.0635 0.889) (xy 0.09144 0.87376) (xy 0.11684 0.85344) (xy 0.13716 0.82804)
						(xy 0.1524 0.8001) (xy 0.16256 0.76835) (xy 0.1651 0.7366) (xy 0.1651 -0.13462) (xy 0.17272 -0.14224)
						(xy 0.19812 -0.1778) (xy 0.2032 -0.18796) (xy 0.20701 -0.19685) (xy 0.21209 -0.20701) (xy 0.2159 -0.21717)
						(xy 0.21844 -0.22733) (xy 0.22225 -0.23876) (xy 0.22352 -0.24892) (xy 0.22606 -0.25908) (xy 0.22733 -0.27051)
						(xy 0.22733 -0.28067) (xy 0.2286 -0.2921) (xy 0.22733 -0.30353) (xy 0.22733 -0.31369) (xy 0.22606 -0.32512)
						(xy 0.22352 -0.33528) (xy 0.22225 -0.34544) (xy 0.21844 -0.35687) (xy 0.2159 -0.36703) (xy 0.21209 -0.37719)
						(xy 0.20701 -0.38735) (xy 0.2032 -0.39624) (xy 0.19812 -0.4064) (xy 0.17272 -0.44196) (xy 0.1651 -0.44958)
						(xy 0.1651 -0.7366) (xy 0.16256 -0.76835) (xy 0.1524 -0.8001) (xy 0.13716 -0.82804) (xy 0.11684 -0.85344)
						(xy 0.09144 -0.87376) (xy 0.0635 -0.889) (xy 0.03175 -0.89916)
					)
					(width 0)
					(fill yes)
				)
			)
		)
		(pad "194" smd custom
			(at 28.64993 4.100068 180)
			(size 0.1143 0.1143)
			(layers "B.Cu" "B.Mask" "B.Paste")
			(net "M_B_DQ63")
			(options
				(clearance outline)
				(anchor circle)
			)
			(primitives
				(gr_poly
					(pts
						(xy 0 -0.9017) (xy -0.03175 -0.89916) (xy -0.0635 -0.889) (xy -0.09144 -0.87376) (xy -0.11684 -0.85344)
						(xy -0.13716 -0.82804) (xy -0.1524 -0.8001) (xy -0.16256 -0.76835) (xy -0.1651 -0.7366) (xy -0.1651 0.13462)
						(xy -0.17272 0.14224) (xy -0.19812 0.1778) (xy -0.2032 0.18796) (xy -0.20701 0.19685) (xy -0.21209 0.20701)
						(xy -0.2159 0.21717) (xy -0.21844 0.22733) (xy -0.22225 0.23876) (xy -0.22352 0.24892) (xy -0.22606 0.25908)
						(xy -0.22733 0.27051) (xy -0.22733 0.28067) (xy -0.2286 0.2921) (xy -0.22733 0.30353) (xy -0.22733 0.31369)
						(xy -0.22606 0.32512) (xy -0.22352 0.33528) (xy -0.22225 0.34544) (xy -0.21844 0.35687) (xy -0.2159 0.36703)
						(xy -0.21209 0.37719) (xy -0.20701 0.38735) (xy -0.2032 0.39624) (xy -0.19812 0.4064) (xy -0.17272 0.44196)
						(xy -0.1651 0.44958) (xy -0.1651 0.7366) (xy -0.16256 0.76835) (xy -0.1524 0.8001) (xy -0.13716 0.82804)
						(xy -0.11684 0.85344) (xy -0.09144 0.87376) (xy -0.0635 0.889) (xy -0.03175 0.89916) (xy 0 0.9017)
						(xy 0.03175 0.89916) (xy 0.0635 0.889) (xy 0.09144 0.87376) (xy 0.11684 0.85344) (xy 0.13716 0.82804)
						(xy 0.1524 0.8001) (xy 0.16256 0.76835) (xy 0.1651 0.7366) (xy 0.1651 0.44958) (xy 0.17272 0.44196)
						(xy 0.19812 0.4064) (xy 0.2032 0.39624) (xy 0.20701 0.38735) (xy 0.21209 0.37719) (xy 0.2159 0.36703)
						(xy 0.21844 0.35687) (xy 0.22225 0.34544) (xy 0.22352 0.33528) (xy 0.22606 0.32512) (xy 0.22733 0.31369)
						(xy 0.22733 0.30353) (xy 0.2286 0.2921) (xy 0.22733 0.28067) (xy 0.22733 0.27051) (xy 0.22606 0.25908)
						(xy 0.22352 0.24892) (xy 0.22225 0.23876) (xy 0.21844 0.22733) (xy 0.2159 0.21717) (xy 0.21209 0.20701)
						(xy 0.20701 0.19685) (xy 0.2032 0.18796) (xy 0.19812 0.1778) (xy 0.17272 0.14224) (xy 0.1651 0.13462)
						(xy 0.1651 -0.7366) (xy 0.16256 -0.76835) (xy 0.1524 -0.8001) (xy 0.13716 -0.82804) (xy 0.11684 -0.85344)
						(xy 0.09144 -0.87376) (xy 0.0635 -0.889) (xy 0.03175 -0.89916)
					)
					(width 0)
					(fill yes)
				)
			)
		)
		(pad "195" smd custom
			(at 28.949904 -4.100068 180)
			(size 0.1143 0.1143)
			(layers "B.Cu" "B.Mask" "B.Paste")
			(net "GND")
			(options
				(clearance outline)
				(anchor circle)
			)
			(primitives
				(gr_poly
					(pts
						(xy 0 -0.9017) (xy -0.03175 -0.89916) (xy -0.0635 -0.889) (xy -0.09144 -0.87376) (xy -0.11684 -0.85344)
						(xy -0.13716 -0.82804) (xy -0.1524 -0.8001) (xy -0.16256 -0.76835) (xy -0.1651 -0.7366) (xy -0.1651 -0.19685)
						(xy -0.17272 -0.18923) (xy -0.17907 -0.18034) (xy -0.18669 -0.17145) (xy -0.19177 -0.16256) (xy -0.19812 -0.15367)
						(xy -0.20828 -0.13335) (xy -0.21971 -0.10287) (xy -0.22225 -0.09271) (xy -0.22479 -0.08128) (xy -0.22606 -0.07112)
						(xy -0.2286 -0.05969) (xy -0.2286 -0.01651) (xy -0.22606 -0.00508) (xy -0.22479 0.00508) (xy -0.22225 0.01651)
						(xy -0.21971 0.02667) (xy -0.20828 0.05715) (xy -0.19812 0.07747) (xy -0.19177 0.08636) (xy -0.18669 0.09525)
						(xy -0.17907 0.10414) (xy -0.17272 0.11303) (xy -0.1651 0.12065) (xy -0.1651 0.7366) (xy -0.16256 0.76835)
						(xy -0.1524 0.8001) (xy -0.13716 0.82804) (xy -0.11684 0.85344) (xy -0.09144 0.87376) (xy -0.0635 0.889)
						(xy -0.03175 0.89916) (xy 0 0.9017) (xy 0.03175 0.89916) (xy 0.0635 0.889) (xy 0.09144 0.87376)
						(xy 0.11684 0.85344) (xy 0.13716 0.82804) (xy 0.1524 0.8001) (xy 0.16256 0.76835) (xy 0.1651 0.7366)
						(xy 0.1651 0.11938) (xy 0.17272 0.11176) (xy 0.19812 0.0762) (xy 0.2032 0.06604) (xy 0.20701 0.05715)
						(xy 0.21209 0.04699) (xy 0.2159 0.03683) (xy 0.21844 0.02667) (xy 0.22225 0.01524) (xy 0.22352 0.00508)
						(xy 0.22606 -0.00508) (xy 0.22733 -0.01651) (xy 0.22733 -0.02667) (xy 0.2286 -0.0381) (xy 0.22733 -0.04953)
						(xy 0.22733 -0.05969) (xy 0.22606 -0.07112) (xy 0.22352 -0.08128) (xy 0.22225 -0.09144) (xy 0.21844 -0.10287)
						(xy 0.2159 -0.11303) (xy 0.21209 -0.12319) (xy 0.20701 -0.13335) (xy 0.2032 -0.14224) (xy 0.19812 -0.1524)
						(xy 0.17272 -0.18796) (xy 0.1651 -0.19558) (xy 0.1651 -0.7366) (xy 0.16256 -0.76835) (xy 0.1524 -0.8001)
						(xy 0.13716 -0.82804) (xy 0.11684 -0.85344) (xy 0.09144 -0.87376) (xy 0.0635 -0.889) (xy 0.03175 -0.89916)
					)
					(width 0)
					(fill yes)
				)
			)
		)
		(pad "196" smd custom
			(at 29.249878 4.100068 180)
			(size 0.1143 0.1143)
			(layers "B.Cu" "B.Mask" "B.Paste")
			(net "GND")
			(options
				(clearance outline)
				(anchor circle)
			)
			(primitives
				(gr_poly
					(pts
						(xy 0 -0.9017) (xy -0.03175 -0.89916) (xy -0.0635 -0.889) (xy -0.09144 -0.87376) (xy -0.11684 -0.85344)
						(xy -0.13716 -0.82804) (xy -0.1524 -0.8001) (xy -0.16256 -0.76835) (xy -0.1651 -0.7366) (xy -0.1651 -0.11938)
						(xy -0.17272 -0.11176) (xy -0.19812 -0.0762) (xy -0.2032 -0.06604) (xy -0.20701 -0.05715) (xy -0.21209 -0.04699)
						(xy -0.2159 -0.03683) (xy -0.21844 -0.02667) (xy -0.22225 -0.01524) (xy -0.22352 -0.00508) (xy -0.22606 0.00508)
						(xy -0.22733 0.01651) (xy -0.22733 0.02667) (xy -0.2286 0.0381) (xy -0.22733 0.04953) (xy -0.22733 0.05969)
						(xy -0.22606 0.07112) (xy -0.22352 0.08128) (xy -0.22225 0.09144) (xy -0.21844 0.10287) (xy -0.2159 0.11303)
						(xy -0.21209 0.12319) (xy -0.20701 0.13335) (xy -0.2032 0.14224) (xy -0.19812 0.1524) (xy -0.17272 0.18796)
						(xy -0.1651 0.19558) (xy -0.1651 0.7366) (xy -0.16256 0.76835) (xy -0.1524 0.8001) (xy -0.13716 0.82804)
						(xy -0.11684 0.85344) (xy -0.09144 0.87376) (xy -0.0635 0.889) (xy -0.03175 0.89916) (xy 0 0.9017)
						(xy 0.03175 0.89916) (xy 0.0635 0.889) (xy 0.09144 0.87376) (xy 0.11684 0.85344) (xy 0.13716 0.82804)
						(xy 0.1524 0.8001) (xy 0.16256 0.76835) (xy 0.1651 0.7366) (xy 0.1651 0.19685) (xy 0.17272 0.18923)
						(xy 0.17907 0.18034) (xy 0.18669 0.17145) (xy 0.19177 0.16256) (xy 0.19812 0.15367) (xy 0.20828 0.13335)
						(xy 0.21971 0.10287) (xy 0.22225 0.09271) (xy 0.22479 0.08128) (xy 0.22606 0.07112) (xy 0.2286 0.05969)
						(xy 0.2286 0.01651) (xy 0.22606 0.00508) (xy 0.22479 -0.00508) (xy 0.22225 -0.01651) (xy 0.21971 -0.02667)
						(xy 0.20828 -0.05715) (xy 0.19812 -0.07747) (xy 0.19177 -0.08636) (xy 0.18669 -0.09525) (xy 0.17907 -0.10414)
						(xy 0.17272 -0.11303) (xy 0.1651 -0.12065) (xy 0.1651 -0.7366) (xy 0.16256 -0.76835) (xy 0.1524 -0.8001)
						(xy 0.13716 -0.82804) (xy 0.11684 -0.85344) (xy 0.09144 -0.87376) (xy 0.0635 -0.889) (xy 0.03175 -0.89916)
					)
					(width 0)
					(fill yes)
				)
			)
		)
		(pad "197" smd custom
			(at 29.550106 -4.100068 180)
			(size 0.1143 0.1143)
			(layers "B.Cu" "B.Mask" "B.Paste")
			(net "CHB_0_SA0")
			(options
				(clearance outline)
				(anchor circle)
			)
			(primitives
				(gr_poly
					(pts
						(xy 0 -0.9017) (xy -0.03175 -0.89916) (xy -0.0635 -0.889) (xy -0.09144 -0.87376) (xy -0.11684 -0.85344)
						(xy -0.13716 -0.82804) (xy -0.1524 -0.8001) (xy -0.16256 -0.76835) (xy -0.1651 -0.7366) (xy -0.1651 -0.44958)
						(xy -0.17272 -0.44196) (xy -0.19812 -0.4064) (xy -0.2032 -0.39624) (xy -0.20701 -0.38735) (xy -0.21209 -0.37719)
						(xy -0.2159 -0.36703) (xy -0.21844 -0.35687) (xy -0.22225 -0.34544) (xy -0.22352 -0.33528) (xy -0.22606 -0.32512)
						(xy -0.22733 -0.31369) (xy -0.22733 -0.30353) (xy -0.2286 -0.2921) (xy -0.22733 -0.28067) (xy -0.22733 -0.27051)
						(xy -0.22606 -0.25908) (xy -0.22352 -0.24892) (xy -0.22225 -0.23876) (xy -0.21844 -0.22733) (xy -0.2159 -0.21717)
						(xy -0.21209 -0.20701) (xy -0.20701 -0.19685) (xy -0.2032 -0.18796) (xy -0.19812 -0.1778) (xy -0.17272 -0.14224)
						(xy -0.1651 -0.13462) (xy -0.1651 0.7366) (xy -0.16256 0.76835) (xy -0.1524 0.8001) (xy -0.13716 0.82804)
						(xy -0.11684 0.85344) (xy -0.09144 0.87376) (xy -0.0635 0.889) (xy -0.03175 0.89916) (xy 0 0.9017)
						(xy 0.03175 0.89916) (xy 0.0635 0.889) (xy 0.09144 0.87376) (xy 0.11684 0.85344) (xy 0.13716 0.82804)
						(xy 0.1524 0.8001) (xy 0.16256 0.76835) (xy 0.1651 0.7366) (xy 0.1651 -0.13462) (xy 0.17272 -0.14224)
						(xy 0.19812 -0.1778) (xy 0.2032 -0.18796) (xy 0.20701 -0.19685) (xy 0.21209 -0.20701) (xy 0.2159 -0.21717)
						(xy 0.21844 -0.22733) (xy 0.22225 -0.23876) (xy 0.22352 -0.24892) (xy 0.22606 -0.25908) (xy 0.22733 -0.27051)
						(xy 0.22733 -0.28067) (xy 0.2286 -0.2921) (xy 0.22733 -0.30353) (xy 0.22733 -0.31369) (xy 0.22606 -0.32512)
						(xy 0.22352 -0.33528) (xy 0.22225 -0.34544) (xy 0.21844 -0.35687) (xy 0.2159 -0.36703) (xy 0.21209 -0.37719)
						(xy 0.20701 -0.38735) (xy 0.2032 -0.39624) (xy 0.19812 -0.4064) (xy 0.17272 -0.44196) (xy 0.1651 -0.44958)
						(xy 0.1651 -0.7366) (xy 0.16256 -0.76835) (xy 0.1524 -0.8001) (xy 0.13716 -0.82804) (xy 0.11684 -0.85344)
						(xy 0.09144 -0.87376) (xy 0.0635 -0.889) (xy 0.03175 -0.89916)
					)
					(width 0)
					(fill yes)
				)
			)
		)
		(pad "198" smd custom
			(at 29.85008 4.100068 180)
			(size 0.1143 0.1143)
			(layers "B.Cu" "B.Mask" "B.Paste")
			(net "MEMORY_HOT_LV_R#")
			(options
				(clearance outline)
				(anchor circle)
			)
			(primitives
				(gr_poly
					(pts
						(xy 0 -0.9017) (xy -0.03175 -0.89916) (xy -0.0635 -0.889) (xy -0.09144 -0.87376) (xy -0.11684 -0.85344)
						(xy -0.13716 -0.82804) (xy -0.1524 -0.8001) (xy -0.16256 -0.76835) (xy -0.1651 -0.7366) (xy -0.1651 0.13462)
						(xy -0.17272 0.14224) (xy -0.19812 0.1778) (xy -0.2032 0.18796) (xy -0.20701 0.19685) (xy -0.21209 0.20701)
						(xy -0.2159 0.21717) (xy -0.21844 0.22733) (xy -0.22225 0.23876) (xy -0.22352 0.24892) (xy -0.22606 0.25908)
						(xy -0.22733 0.27051) (xy -0.22733 0.28067) (xy -0.2286 0.2921) (xy -0.22733 0.30353) (xy -0.22733 0.31369)
						(xy -0.22606 0.32512) (xy -0.22352 0.33528) (xy -0.22225 0.34544) (xy -0.21844 0.35687) (xy -0.2159 0.36703)
						(xy -0.21209 0.37719) (xy -0.20701 0.38735) (xy -0.2032 0.39624) (xy -0.19812 0.4064) (xy -0.17272 0.44196)
						(xy -0.1651 0.44958) (xy -0.1651 0.7366) (xy -0.16256 0.76835) (xy -0.1524 0.8001) (xy -0.13716 0.82804)
						(xy -0.11684 0.85344) (xy -0.09144 0.87376) (xy -0.0635 0.889) (xy -0.03175 0.89916) (xy 0 0.9017)
						(xy 0.03175 0.89916) (xy 0.0635 0.889) (xy 0.09144 0.87376) (xy 0.11684 0.85344) (xy 0.13716 0.82804)
						(xy 0.1524 0.8001) (xy 0.16256 0.76835) (xy 0.1651 0.7366) (xy 0.1651 0.44958) (xy 0.17272 0.44196)
						(xy 0.19812 0.4064) (xy 0.2032 0.39624) (xy 0.20701 0.38735) (xy 0.21209 0.37719) (xy 0.2159 0.36703)
						(xy 0.21844 0.35687) (xy 0.22225 0.34544) (xy 0.22352 0.33528) (xy 0.22606 0.32512) (xy 0.22733 0.31369)
						(xy 0.22733 0.30353) (xy 0.2286 0.2921) (xy 0.22733 0.28067) (xy 0.22733 0.27051) (xy 0.22606 0.25908)
						(xy 0.22352 0.24892) (xy 0.22225 0.23876) (xy 0.21844 0.22733) (xy 0.2159 0.21717) (xy 0.21209 0.20701)
						(xy 0.20701 0.19685) (xy 0.2032 0.18796) (xy 0.19812 0.1778) (xy 0.17272 0.14224) (xy 0.1651 0.13462)
						(xy 0.1651 -0.7366) (xy 0.16256 -0.76835) (xy 0.1524 -0.8001) (xy 0.13716 -0.82804) (xy 0.11684 -0.85344)
						(xy 0.09144 -0.87376) (xy 0.0635 -0.889) (xy 0.03175 -0.89916)
					)
					(width 0)
					(fill yes)
				)
			)
		)
		(pad "199" smd custom
			(at 30.150054 -4.100068 180)
			(size 0.1143 0.1143)
			(layers "B.Cu" "B.Mask" "B.Paste")
			(net "P3V3_STBY")
			(options
				(clearance outline)
				(anchor circle)
			)
			(primitives
				(gr_poly
					(pts
						(xy 0 -0.9017) (xy -0.03175 -0.89916) (xy -0.0635 -0.889) (xy -0.09144 -0.87376) (xy -0.11684 -0.85344)
						(xy -0.13716 -0.82804) (xy -0.1524 -0.8001) (xy -0.16256 -0.76835) (xy -0.1651 -0.7366) (xy -0.1651 -0.19685)
						(xy -0.17272 -0.18923) (xy -0.17907 -0.18034) (xy -0.18669 -0.17145) (xy -0.19177 -0.16256) (xy -0.19812 -0.15367)
						(xy -0.20828 -0.13335) (xy -0.21971 -0.10287) (xy -0.22225 -0.09271) (xy -0.22479 -0.08128) (xy -0.22606 -0.07112)
						(xy -0.2286 -0.05969) (xy -0.2286 -0.01651) (xy -0.22606 -0.00508) (xy -0.22479 0.00508) (xy -0.22225 0.01651)
						(xy -0.21971 0.02667) (xy -0.20828 0.05715) (xy -0.19812 0.07747) (xy -0.19177 0.08636) (xy -0.18669 0.09525)
						(xy -0.17907 0.10414) (xy -0.17272 0.11303) (xy -0.1651 0.12065) (xy -0.1651 0.7366) (xy -0.16256 0.76835)
						(xy -0.1524 0.8001) (xy -0.13716 0.82804) (xy -0.11684 0.85344) (xy -0.09144 0.87376) (xy -0.0635 0.889)
						(xy -0.03175 0.89916) (xy 0 0.9017) (xy 0.03175 0.89916) (xy 0.0635 0.889) (xy 0.09144 0.87376)
						(xy 0.11684 0.85344) (xy 0.13716 0.82804) (xy 0.1524 0.8001) (xy 0.16256 0.76835) (xy 0.1651 0.7366)
						(xy 0.1651 0.11938) (xy 0.17272 0.11176) (xy 0.19812 0.0762) (xy 0.2032 0.06604) (xy 0.20701 0.05715)
						(xy 0.21209 0.04699) (xy 0.2159 0.03683) (xy 0.21844 0.02667) (xy 0.22225 0.01524) (xy 0.22352 0.00508)
						(xy 0.22606 -0.00508) (xy 0.22733 -0.01651) (xy 0.22733 -0.02667) (xy 0.2286 -0.0381) (xy 0.22733 -0.04953)
						(xy 0.22733 -0.05969) (xy 0.22606 -0.07112) (xy 0.22352 -0.08128) (xy 0.22225 -0.09144) (xy 0.21844 -0.10287)
						(xy 0.2159 -0.11303) (xy 0.21209 -0.12319) (xy 0.20701 -0.13335) (xy 0.2032 -0.14224) (xy 0.19812 -0.1524)
						(xy 0.17272 -0.18796) (xy 0.1651 -0.19558) (xy 0.1651 -0.7366) (xy 0.16256 -0.76835) (xy 0.1524 -0.8001)
						(xy 0.13716 -0.82804) (xy 0.11684 -0.85344) (xy 0.09144 -0.87376) (xy 0.0635 -0.889) (xy 0.03175 -0.89916)
					)
					(width 0)
					(fill yes)
				)
			)
		)
		(pad "200" smd custom
			(at 30.450028 4.100068 180)
			(size 0.1143 0.1143)
			(layers "B.Cu" "B.Mask" "B.Paste")
			(net "SMB_M_B0_R_DATA")
			(options
				(clearance outline)
				(anchor circle)
			)
			(primitives
				(gr_poly
					(pts
						(xy 0 -0.9017) (xy -0.03175 -0.89916) (xy -0.0635 -0.889) (xy -0.09144 -0.87376) (xy -0.11684 -0.85344)
						(xy -0.13716 -0.82804) (xy -0.1524 -0.8001) (xy -0.16256 -0.76835) (xy -0.1651 -0.7366) (xy -0.1651 -0.11938)
						(xy -0.17272 -0.11176) (xy -0.19812 -0.0762) (xy -0.2032 -0.06604) (xy -0.20701 -0.05715) (xy -0.21209 -0.04699)
						(xy -0.2159 -0.03683) (xy -0.21844 -0.02667) (xy -0.22225 -0.01524) (xy -0.22352 -0.00508) (xy -0.22606 0.00508)
						(xy -0.22733 0.01651) (xy -0.22733 0.02667) (xy -0.2286 0.0381) (xy -0.22733 0.04953) (xy -0.22733 0.05969)
						(xy -0.22606 0.07112) (xy -0.22352 0.08128) (xy -0.22225 0.09144) (xy -0.21844 0.10287) (xy -0.2159 0.11303)
						(xy -0.21209 0.12319) (xy -0.20701 0.13335) (xy -0.2032 0.14224) (xy -0.19812 0.1524) (xy -0.17272 0.18796)
						(xy -0.1651 0.19558) (xy -0.1651 0.7366) (xy -0.16256 0.76835) (xy -0.1524 0.8001) (xy -0.13716 0.82804)
						(xy -0.11684 0.85344) (xy -0.09144 0.87376) (xy -0.0635 0.889) (xy -0.03175 0.89916) (xy 0 0.9017)
						(xy 0.03175 0.89916) (xy 0.0635 0.889) (xy 0.09144 0.87376) (xy 0.11684 0.85344) (xy 0.13716 0.82804)
						(xy 0.1524 0.8001) (xy 0.16256 0.76835) (xy 0.1651 0.7366) (xy 0.1651 0.19685) (xy 0.17272 0.18923)
						(xy 0.17907 0.18034) (xy 0.18669 0.17145) (xy 0.19177 0.16256) (xy 0.19812 0.15367) (xy 0.20828 0.13335)
						(xy 0.21971 0.10287) (xy 0.22225 0.09271) (xy 0.22479 0.08128) (xy 0.22606 0.07112) (xy 0.2286 0.05969)
						(xy 0.2286 0.01651) (xy 0.22606 0.00508) (xy 0.22479 -0.00508) (xy 0.22225 -0.01651) (xy 0.21971 -0.02667)
						(xy 0.20828 -0.05715) (xy 0.19812 -0.07747) (xy 0.19177 -0.08636) (xy 0.18669 -0.09525) (xy 0.17907 -0.10414)
						(xy 0.17272 -0.11303) (xy 0.1651 -0.12065) (xy 0.1651 -0.7366) (xy 0.16256 -0.76835) (xy 0.1524 -0.8001)
						(xy 0.13716 -0.82804) (xy 0.11684 -0.85344) (xy 0.09144 -0.87376) (xy 0.0635 -0.889) (xy 0.03175 -0.89916)
					)
					(width 0)
					(fill yes)
				)
			)
		)
		(pad "201" smd custom
			(at 30.750002 -4.100068 180)
			(size 0.1143 0.1143)
			(layers "B.Cu" "B.Mask" "B.Paste")
			(net "CHB_0_SA1")
			(options
				(clearance outline)
				(anchor circle)
			)
			(primitives
				(gr_poly
					(pts
						(xy 0 -0.9017) (xy -0.03175 -0.89916) (xy -0.0635 -0.889) (xy -0.09144 -0.87376) (xy -0.11684 -0.85344)
						(xy -0.13716 -0.82804) (xy -0.1524 -0.8001) (xy -0.16256 -0.76835) (xy -0.1651 -0.7366) (xy -0.1651 -0.44958)
						(xy -0.17272 -0.44196) (xy -0.19812 -0.4064) (xy -0.2032 -0.39624) (xy -0.20701 -0.38735) (xy -0.21209 -0.37719)
						(xy -0.2159 -0.36703) (xy -0.21844 -0.35687) (xy -0.22225 -0.34544) (xy -0.22352 -0.33528) (xy -0.22606 -0.32512)
						(xy -0.22733 -0.31369) (xy -0.22733 -0.30353) (xy -0.2286 -0.2921) (xy -0.22733 -0.28067) (xy -0.22733 -0.27051)
						(xy -0.22606 -0.25908) (xy -0.22352 -0.24892) (xy -0.22225 -0.23876) (xy -0.21844 -0.22733) (xy -0.2159 -0.21717)
						(xy -0.21209 -0.20701) (xy -0.20701 -0.19685) (xy -0.2032 -0.18796) (xy -0.19812 -0.1778) (xy -0.17272 -0.14224)
						(xy -0.1651 -0.13462) (xy -0.1651 0.7366) (xy -0.16256 0.76835) (xy -0.1524 0.8001) (xy -0.13716 0.82804)
						(xy -0.11684 0.85344) (xy -0.09144 0.87376) (xy -0.0635 0.889) (xy -0.03175 0.89916) (xy 0 0.9017)
						(xy 0.03175 0.89916) (xy 0.0635 0.889) (xy 0.09144 0.87376) (xy 0.11684 0.85344) (xy 0.13716 0.82804)
						(xy 0.1524 0.8001) (xy 0.16256 0.76835) (xy 0.1651 0.7366) (xy 0.1651 -0.13462) (xy 0.17272 -0.14224)
						(xy 0.19812 -0.1778) (xy 0.2032 -0.18796) (xy 0.20701 -0.19685) (xy 0.21209 -0.20701) (xy 0.2159 -0.21717)
						(xy 0.21844 -0.22733) (xy 0.22225 -0.23876) (xy 0.22352 -0.24892) (xy 0.22606 -0.25908) (xy 0.22733 -0.27051)
						(xy 0.22733 -0.28067) (xy 0.2286 -0.2921) (xy 0.22733 -0.30353) (xy 0.22733 -0.31369) (xy 0.22606 -0.32512)
						(xy 0.22352 -0.33528) (xy 0.22225 -0.34544) (xy 0.21844 -0.35687) (xy 0.2159 -0.36703) (xy 0.21209 -0.37719)
						(xy 0.20701 -0.38735) (xy 0.2032 -0.39624) (xy 0.19812 -0.4064) (xy 0.17272 -0.44196) (xy 0.1651 -0.44958)
						(xy 0.1651 -0.7366) (xy 0.16256 -0.76835) (xy 0.1524 -0.8001) (xy 0.13716 -0.82804) (xy 0.11684 -0.85344)
						(xy 0.09144 -0.87376) (xy 0.0635 -0.889) (xy 0.03175 -0.89916)
					)
					(width 0)
					(fill yes)
				)
			)
		)
		(pad "202" smd custom
			(at 31.049976 4.100068 180)
			(size 0.1143 0.1143)
			(layers "B.Cu" "B.Mask" "B.Paste")
			(net "SMB_M_B0_R_CLK")
			(options
				(clearance outline)
				(anchor circle)
			)
			(primitives
				(gr_poly
					(pts
						(xy 0 -0.9017) (xy -0.03175 -0.89916) (xy -0.0635 -0.889) (xy -0.09144 -0.87376) (xy -0.11684 -0.85344)
						(xy -0.13716 -0.82804) (xy -0.1524 -0.8001) (xy -0.16256 -0.76835) (xy -0.1651 -0.7366) (xy -0.1651 0.13462)
						(xy -0.17272 0.14224) (xy -0.19812 0.1778) (xy -0.2032 0.18796) (xy -0.20701 0.19685) (xy -0.21209 0.20701)
						(xy -0.2159 0.21717) (xy -0.21844 0.22733) (xy -0.22225 0.23876) (xy -0.22352 0.24892) (xy -0.22606 0.25908)
						(xy -0.22733 0.27051) (xy -0.22733 0.28067) (xy -0.2286 0.2921) (xy -0.22733 0.30353) (xy -0.22733 0.31369)
						(xy -0.22606 0.32512) (xy -0.22352 0.33528) (xy -0.22225 0.34544) (xy -0.21844 0.35687) (xy -0.2159 0.36703)
						(xy -0.21209 0.37719) (xy -0.20701 0.38735) (xy -0.2032 0.39624) (xy -0.19812 0.4064) (xy -0.17272 0.44196)
						(xy -0.1651 0.44958) (xy -0.1651 0.7366) (xy -0.16256 0.76835) (xy -0.1524 0.8001) (xy -0.13716 0.82804)
						(xy -0.11684 0.85344) (xy -0.09144 0.87376) (xy -0.0635 0.889) (xy -0.03175 0.89916) (xy 0 0.9017)
						(xy 0.03175 0.89916) (xy 0.0635 0.889) (xy 0.09144 0.87376) (xy 0.11684 0.85344) (xy 0.13716 0.82804)
						(xy 0.1524 0.8001) (xy 0.16256 0.76835) (xy 0.1651 0.7366) (xy 0.1651 0.44958) (xy 0.17272 0.44196)
						(xy 0.19812 0.4064) (xy 0.2032 0.39624) (xy 0.20701 0.38735) (xy 0.21209 0.37719) (xy 0.2159 0.36703)
						(xy 0.21844 0.35687) (xy 0.22225 0.34544) (xy 0.22352 0.33528) (xy 0.22606 0.32512) (xy 0.22733 0.31369)
						(xy 0.22733 0.30353) (xy 0.2286 0.2921) (xy 0.22733 0.28067) (xy 0.22733 0.27051) (xy 0.22606 0.25908)
						(xy 0.22352 0.24892) (xy 0.22225 0.23876) (xy 0.21844 0.22733) (xy 0.2159 0.21717) (xy 0.21209 0.20701)
						(xy 0.20701 0.19685) (xy 0.2032 0.18796) (xy 0.19812 0.1778) (xy 0.17272 0.14224) (xy 0.1651 0.13462)
						(xy 0.1651 -0.7366) (xy 0.16256 -0.76835) (xy 0.1524 -0.8001) (xy 0.13716 -0.82804) (xy 0.11684 -0.85344)
						(xy 0.09144 -0.87376) (xy 0.0635 -0.889) (xy 0.03175 -0.89916)
					)
					(width 0)
					(fill yes)
				)
			)
		)
		(pad "203" smd custom
			(at 31.34995 -4.100068 180)
			(size 0.1143 0.1143)
			(layers "B.Cu" "B.Mask" "B.Paste")
			(net "PV_VTT_DDR_B")
			(options
				(clearance outline)
				(anchor circle)
			)
			(primitives
				(gr_poly
					(pts
						(xy 0 -0.9017) (xy -0.03175 -0.89916) (xy -0.0635 -0.889) (xy -0.09144 -0.87376) (xy -0.11684 -0.85344)
						(xy -0.13716 -0.82804) (xy -0.1524 -0.8001) (xy -0.16256 -0.76835) (xy -0.1651 -0.7366) (xy -0.1651 -0.19685)
						(xy -0.17272 -0.18923) (xy -0.17907 -0.18034) (xy -0.18669 -0.17145) (xy -0.19177 -0.16256) (xy -0.19812 -0.15367)
						(xy -0.20828 -0.13335) (xy -0.21971 -0.10287) (xy -0.22225 -0.09271) (xy -0.22479 -0.08128) (xy -0.22606 -0.07112)
						(xy -0.2286 -0.05969) (xy -0.2286 -0.01651) (xy -0.22606 -0.00508) (xy -0.22479 0.00508) (xy -0.22225 0.01651)
						(xy -0.21971 0.02667) (xy -0.20828 0.05715) (xy -0.19812 0.07747) (xy -0.19177 0.08636) (xy -0.18669 0.09525)
						(xy -0.17907 0.10414) (xy -0.17272 0.11303) (xy -0.1651 0.12065) (xy -0.1651 0.7366) (xy -0.16256 0.76835)
						(xy -0.1524 0.8001) (xy -0.13716 0.82804) (xy -0.11684 0.85344) (xy -0.09144 0.87376) (xy -0.0635 0.889)
						(xy -0.03175 0.89916) (xy 0 0.9017) (xy 0.03175 0.89916) (xy 0.0635 0.889) (xy 0.09144 0.87376)
						(xy 0.11684 0.85344) (xy 0.13716 0.82804) (xy 0.1524 0.8001) (xy 0.16256 0.76835) (xy 0.1651 0.7366)
						(xy 0.1651 0.11938) (xy 0.17272 0.11176) (xy 0.19812 0.0762) (xy 0.2032 0.06604) (xy 0.20701 0.05715)
						(xy 0.21209 0.04699) (xy 0.2159 0.03683) (xy 0.21844 0.02667) (xy 0.22225 0.01524) (xy 0.22352 0.00508)
						(xy 0.22606 -0.00508) (xy 0.22733 -0.01651) (xy 0.22733 -0.02667) (xy 0.2286 -0.0381) (xy 0.22733 -0.04953)
						(xy 0.22733 -0.05969) (xy 0.22606 -0.07112) (xy 0.22352 -0.08128) (xy 0.22225 -0.09144) (xy 0.21844 -0.10287)
						(xy 0.2159 -0.11303) (xy 0.21209 -0.12319) (xy 0.20701 -0.13335) (xy 0.2032 -0.14224) (xy 0.19812 -0.1524)
						(xy 0.17272 -0.18796) (xy 0.1651 -0.19558) (xy 0.1651 -0.7366) (xy 0.16256 -0.76835) (xy 0.1524 -0.8001)
						(xy 0.13716 -0.82804) (xy 0.11684 -0.85344) (xy 0.09144 -0.87376) (xy 0.0635 -0.889) (xy 0.03175 -0.89916)
					)
					(width 0)
					(fill yes)
				)
			)
		)
		(pad "204" smd custom
			(at 31.649924 4.100068 180)
			(size 0.1143 0.1143)
			(layers "B.Cu" "B.Mask" "B.Paste")
			(net "PV_VTT_DDR_B")
			(options
				(clearance outline)
				(anchor circle)
			)
			(primitives
				(gr_poly
					(pts
						(xy 0 -0.9017) (xy -0.03175 -0.89916) (xy -0.0635 -0.889) (xy -0.09144 -0.87376) (xy -0.11684 -0.85344)
						(xy -0.13716 -0.82804) (xy -0.1524 -0.8001) (xy -0.16256 -0.76835) (xy -0.1651 -0.7366) (xy -0.1651 -0.11938)
						(xy -0.17272 -0.11176) (xy -0.19812 -0.0762) (xy -0.2032 -0.06604) (xy -0.20701 -0.05715) (xy -0.21209 -0.04699)
						(xy -0.2159 -0.03683) (xy -0.21844 -0.02667) (xy -0.22225 -0.01524) (xy -0.22352 -0.00508) (xy -0.22606 0.00508)
						(xy -0.22733 0.01651) (xy -0.22733 0.02667) (xy -0.2286 0.0381) (xy -0.22733 0.04953) (xy -0.22733 0.05969)
						(xy -0.22606 0.07112) (xy -0.22352 0.08128) (xy -0.22225 0.09144) (xy -0.21844 0.10287) (xy -0.2159 0.11303)
						(xy -0.21209 0.12319) (xy -0.20701 0.13335) (xy -0.2032 0.14224) (xy -0.19812 0.1524) (xy -0.17272 0.18796)
						(xy -0.1651 0.19558) (xy -0.1651 0.7366) (xy -0.16256 0.76835) (xy -0.1524 0.8001) (xy -0.13716 0.82804)
						(xy -0.11684 0.85344) (xy -0.09144 0.87376) (xy -0.0635 0.889) (xy -0.03175 0.89916) (xy 0 0.9017)
						(xy 0.03175 0.89916) (xy 0.0635 0.889) (xy 0.09144 0.87376) (xy 0.11684 0.85344) (xy 0.13716 0.82804)
						(xy 0.1524 0.8001) (xy 0.16256 0.76835) (xy 0.1651 0.7366) (xy 0.1651 0.19685) (xy 0.17272 0.18923)
						(xy 0.17907 0.18034) (xy 0.18669 0.17145) (xy 0.19177 0.16256) (xy 0.19812 0.15367) (xy 0.20828 0.13335)
						(xy 0.21971 0.10287) (xy 0.22225 0.09271) (xy 0.22479 0.08128) (xy 0.22606 0.07112) (xy 0.2286 0.05969)
						(xy 0.2286 0.01651) (xy 0.22606 0.00508) (xy 0.22479 -0.00508) (xy 0.22225 -0.01651) (xy 0.21971 -0.02667)
						(xy 0.20828 -0.05715) (xy 0.19812 -0.07747) (xy 0.19177 -0.08636) (xy 0.18669 -0.09525) (xy 0.17907 -0.10414)
						(xy 0.17272 -0.11303) (xy 0.1651 -0.12065) (xy 0.1651 -0.7366) (xy 0.16256 -0.76835) (xy 0.1524 -0.8001)
						(xy 0.13716 -0.82804) (xy 0.11684 -0.85344) (xy 0.09144 -0.87376) (xy 0.0635 -0.889) (xy 0.03175 -0.89916)
					)
					(width 0)
					(fill yes)
				)
			)
		)
		(pad "205" smd rect
			(at 37.450014 -11.999976 180)
			(size 4.4958 4.5974)
			(layers "B.Cu" "B.Mask" "B.Paste")
			(net "GND")
		)
		(pad "206" smd rect
			(at 32.800036 -11.999976 180)
			(size 3.5052 4.5974)
			(layers "B.Cu" "B.Mask" "B.Paste")
			(net "GND")
		)
		(pad "207" smd rect
			(at -32.800036 -11.999976 180)
			(size 3.5052 4.5974)
			(layers "B.Cu" "B.Mask" "B.Paste")
			(net "GND")
		)
		(pad "208" smd rect
			(at -37.450014 -11.999976 180)
			(size 4.4958 4.5974)
			(layers "B.Cu" "B.Mask" "B.Paste")
			(net "GND")
		)
		(zone
			(layers "F.Cu" "B.Cu" "In1.Cu" "In2.Cu" "In3.Cu" "In4.Cu" "In5.Cu" "In6.Cu"
				"In7.Cu" "In8.Cu" "In9.Cu" "In10.Cu"
			)
			(hatch none 0.5)
			(connect_pads
				(clearance 0)
			)
			(min_thickness 0.25)
			(keepout
				(tracks not_allowed)
				(vias allowed)
				(pads allowed)
				(copperpour not_allowed)
				(footprints allowed)
			)
			(placement
				(enabled no)
				(sheetname "")
			)
			(fill
				(thermal_gap 0.5)
				(thermal_bridge_width 0.5)
				(island_removal_mode 0)
			)
			(polygon
				(pts
					(arc
						(start 194.263518 -5.790692)
						(mid 192.536318 -5.790692)
						(end 194.263518 -5.790692)
					)
				)
			)
		)
		(zone
			(layers "F.Cu" "B.Cu" "In1.Cu" "In2.Cu" "In3.Cu" "In4.Cu" "In5.Cu" "In6.Cu"
				"In7.Cu" "In8.Cu" "In9.Cu" "In10.Cu"
			)
			(hatch none 0.5)
			(connect_pads
				(clearance 0)
			)
			(min_thickness 0.25)
			(keepout
				(tracks not_allowed)
				(vias allowed)
				(pads allowed)
				(copperpour not_allowed)
				(footprints allowed)
			)
			(placement
				(enabled no)
				(sheetname "")
			)
			(fill
				(thermal_gap 0.5)
				(thermal_bridge_width 0.5)
				(island_removal_mode 0)
			)
			(polygon
				(pts
					(arc
						(start 127.70485 -5.790692)
						(mid 125.49505 -5.790692)
						(end 127.70485 -5.790692)
					)
				)
			)
		)
		(zone
			(layer "B.Cu")
			(hatch none 0.5)
			(connect_pads
				(clearance 0)
			)
			(min_thickness 0.25)
			(keepout
				(tracks allowed)
				(vias not_allowed)
				(pads allowed)
				(copperpour not_allowed)
				(footprints allowed)
			)
			(placement
				(enabled no)
				(sheetname "")
			)
			(fill
				(thermal_gap 0.5)
				(thermal_bridge_width 0.5)
				(island_removal_mode 0)
			)
			(polygon
				(pts
					(xy 128.12141 -8.98906) (xy 128.12141 -8.68426) (xy 149.578568 -8.68426) (xy 149.578568 -8.98906)
				)
			)
		)
		(zone
			(layer "B.Cu")
			(hatch none 0.5)
			(connect_pads
				(clearance 0)
			)
			(min_thickness 0.25)
			(keepout
				(tracks allowed)
				(vias not_allowed)
				(pads allowed)
				(copperpour not_allowed)
				(footprints allowed)
			)
			(placement
				(enabled no)
				(sheetname "")
			)
			(fill
				(thermal_gap 0.5)
				(thermal_bridge_width 0.5)
				(island_removal_mode 0)
			)
			(polygon
				(pts
					(xy 149.878542 -2.592324) (xy 149.878542 -2.897124) (xy 128.421384 -2.897124) (xy 128.421384 -2.592324)
				)
			)
		)
		(zone
			(layer "B.Cu")
			(hatch none 0.5)
			(connect_pads
				(clearance 0)
			)
			(min_thickness 0.25)
			(keepout
				(tracks allowed)
				(vias not_allowed)
				(pads allowed)
				(copperpour not_allowed)
				(footprints allowed)
			)
			(placement
				(enabled no)
				(sheetname "")
			)
			(fill
				(thermal_gap 0.5)
				(thermal_bridge_width 0.5)
				(island_removal_mode 0)
			)
			(polygon
				(pts
					(xy 152.121362 -8.98906) (xy 191.578484 -8.98906) (xy 191.578484 -8.68426) (xy 152.121362 -8.68426)
				)
			)
		)
		(zone
			(layer "B.Cu")
			(hatch none 0.5)
			(connect_pads
				(clearance 0)
			)
			(min_thickness 0.25)
			(keepout
				(tracks allowed)
				(vias not_allowed)
				(pads allowed)
				(copperpour not_allowed)
				(footprints allowed)
			)
			(placement
				(enabled no)
				(sheetname "")
			)
			(fill
				(thermal_gap 0.5)
				(thermal_bridge_width 0.5)
				(island_removal_mode 0)
			)
			(polygon
				(pts
					(xy 152.421336 -2.897124) (xy 191.878458 -2.897124) (xy 191.878458 -2.592324) (xy 152.421336 -2.592324)
				)
			)
		)
	)
	(footprint ""
		(layer "B.Cu")
		(at 106.426 -27.321002)
		(property "Reference" "C239"
			(at 0 0 0)
			(layer "B.SilkS")
			(hide yes)
			(effects
				(font
					(size 1.27 1.27)
				)
				(justify mirror)
			)
		)
		(property "Value" "SC1U10V2KX-1GP"
			(at -1.1811 -2.7051 0)
			(unlocked yes)
			(layer "B.Fab")
			(hide yes)
			(effects
				(font
					(size 1.016 1.016)
					(thickness 0.1524)
				)
				(justify mirror)
			)
		)
		(property "Device Type" "C402H22"
			(at -1.1811 -4.2291 0)
			(unlocked yes)
			(layer "B.Fab")
			(hide yes)
			(effects
				(font
					(size 1.016 1.016)
					(thickness 0.1524)
				)
				(justify mirror)
			)
		)
		(duplicate_pad_numbers_are_jumpers no)
		(fp_rect
			(start 0.381 0.7366)
			(end -0.381 -0.7366)
			(stroke
				(width 0)
				(type default)
			)
			(fill no)
			(layer "B.CrtYd")
		)
		(fp_rect
			(start 0.381 0.7366)
			(end -0.381 -0.7366)
			(stroke
				(width 0)
				(type default)
			)
			(fill no)
			(layer "B.Fab")
		)
		(pad "1" smd custom
			(at 0 -0.4572 180)
			(size 0.1143 0.1143)
			(layers "B.Cu" "B.Mask" "B.Paste")
			(net "PV_VDDR")
			(options
				(clearance outline)
				(anchor circle)
			)
			(primitives
				(gr_poly
					(pts
						(arc
							(start -0.254 0.1778)
							(mid -0.239121 0.213721)
							(end -0.2032 0.2286)
						)
						(arc
							(start 0.2032 0.2286)
							(mid 0.239121 0.213721)
							(end 0.254 0.1778)
						)
						(arc
							(start 0.254 -0.1778)
							(mid 0.239121 -0.213721)
							(end 0.2032 -0.2286)
						)
						(arc
							(start -0.2032 -0.2286)
							(mid -0.239121 -0.213721)
							(end -0.254 -0.1778)
						)
					)
					(width 0)
					(fill yes)
				)
			)
		)
		(pad "2" smd custom
			(at 0 0.4572 180)
			(size 0.1143 0.1143)
			(layers "B.Cu" "B.Mask" "B.Paste")
			(net "GND")
			(options
				(clearance outline)
				(anchor circle)
			)
			(primitives
				(gr_poly
					(pts
						(arc
							(start -0.254 0.1778)
							(mid -0.239121 0.213721)
							(end -0.2032 0.2286)
						)
						(arc
							(start 0.2032 0.2286)
							(mid 0.239121 0.213721)
							(end 0.254 0.1778)
						)
						(arc
							(start 0.254 -0.1778)
							(mid 0.239121 -0.213721)
							(end 0.2032 -0.2286)
						)
						(arc
							(start -0.2032 -0.2286)
							(mid -0.239121 -0.213721)
							(end -0.254 -0.1778)
						)
					)
					(width 0)
					(fill yes)
				)
			)
		)
	)
	(footprint ""
		(layer "B.Cu")
		(at 59.85002 -31.699962 -90)
		(property "Reference" "CN5"
			(at 0 0 90)
			(layer "B.SilkS")
			(hide yes)
			(effects
				(font
					(size 1.27 1.27)
				)
				(justify mirror)
			)
		)
		(property "Value" "SKT-MINI52P-67-GP-U"
			(at 17.5895 -7.0612 270)
			(unlocked yes)
			(layer "B.Fab")
			(hide yes)
			(effects
				(font
					(size 1.016 1.016)
					(thickness 0.1524)
				)
				(justify mirror)
			)
		)
		(property "Device Type" "80003-3021-U"
			(at 17.5895 -8.5852 270)
			(unlocked yes)
			(layer "B.Fab")
			(hide yes)
			(effects
				(font
					(size 1.016 1.016)
					(thickness 0.1524)
				)
				(justify mirror)
			)
		)
		(duplicate_pad_numbers_are_jumpers no)
		(fp_poly
			(pts
				(xy -12.4714 -5.8928) (xy -11.1506 -5.8928) (xy -11.811 -5.2324)
			)
			(stroke
				(width 0)
				(type default)
			)
			(fill yes)
			(layer "B.SilkS")
		)
		(fp_poly
			(pts
				(xy 12.079478 2.890012)
				(arc
					(start 12.079478 0.754126)
					(mid 11.636603 0)
					(end 12.079478 -0.754126)
				)
				(xy 12.079478 -2.890012) (xy -12.079478 -2.890012)
				(arc
					(start -12.079478 -1.021588)
					(mid -11.395309 0)
					(end -12.079478 1.021588)
				)
				(xy -12.079478 2.890012)
			)
			(stroke
				(width 0)
				(type default)
			)
			(fill yes)
			(layer "B.SilkS")
		)
		(fp_rect
			(start 15.9385 5.2324)
			(end -15.9385 -5.2324)
			(stroke
				(width 0)
				(type default)
			)
			(fill no)
			(layer "B.CrtYd")
		)
		(fp_rect
			(start 15.9385 5.2324)
			(end -15.9385 -5.2324)
			(stroke
				(width 0)
				(type default)
			)
			(fill no)
			(layer "B.Fab")
		)
		(pad "" np_thru_hole circle
			(at -12.500102 0 90)
			(size 0.254 0.254)
			(drill 1.6002)
			(layers "*.Cu" "*.Mask")
			(clearance 1.0287)
			(thermal_gap 1.0287)
		)
		(pad "" np_thru_hole circle
			(at 12.500102 0 90)
			(size 0.254 0.254)
			(drill 1.1176)
			(layers "*.Cu" "*.Mask")
			(clearance 0.7874)
			(thermal_gap 0.7874)
		)
		(pad "1" smd rect
			(at -11.800078 -4.096512 90)
			(size 0.5588 2.0066)
			(layers "B.Cu" "B.Mask" "B.Paste")
			(net "Net_448")
		)
		(pad "2" smd rect
			(at -11.400028 4.096512 90)
			(size 0.5588 2.0066)
			(layers "B.Cu" "B.Mask" "B.Paste")
			(net "P3V3")
		)
		(pad "3" smd rect
			(at -10.999978 -4.096512 90)
			(size 0.5588 2.0066)
			(layers "B.Cu" "B.Mask" "B.Paste")
			(net "Net_454")
		)
		(pad "4" smd rect
			(at -10.599928 4.096512 90)
			(size 0.5588 2.0066)
			(layers "B.Cu" "B.Mask" "B.Paste")
			(net "GND")
		)
		(pad "5" smd rect
			(at -10.199878 -4.096512 90)
			(size 0.5588 2.0066)
			(layers "B.Cu" "B.Mask" "B.Paste")
			(net "Net_453")
		)
		(pad "6" smd rect
			(at -9.800082 4.096512 90)
			(size 0.5588 2.0066)
			(layers "B.Cu" "B.Mask" "B.Paste")
			(net "Net_49")
		)
		(pad "7" smd rect
			(at -9.400032 -4.096512 90)
			(size 0.5588 2.0066)
			(layers "B.Cu" "B.Mask" "B.Paste")
			(net "Net_452")
		)
		(pad "8" smd rect
			(at -8.999982 4.096512 90)
			(size 0.5588 2.0066)
			(layers "B.Cu" "B.Mask" "B.Paste")
			(net "Net_459")
		)
		(pad "9" smd rect
			(at -8.599932 -4.096512 90)
			(size 0.5588 2.0066)
			(layers "B.Cu" "B.Mask" "B.Paste")
			(net "GND")
		)
		(pad "10" smd rect
			(at -8.199882 4.096512 90)
			(size 0.5588 2.0066)
			(layers "B.Cu" "B.Mask" "B.Paste")
			(net "Net_458")
		)
		(pad "11" smd rect
			(at -7.800086 -4.096512 90)
			(size 0.5588 2.0066)
			(layers "B.Cu" "B.Mask" "B.Paste")
			(net "Net_451")
		)
		(pad "12" smd rect
			(at -7.400036 4.096512 90)
			(size 0.5588 2.0066)
			(layers "B.Cu" "B.Mask" "B.Paste")
			(net "Net_457")
		)
		(pad "13" smd rect
			(at -6.999986 -4.096512 90)
			(size 0.5588 2.0066)
			(layers "B.Cu" "B.Mask" "B.Paste")
			(net "Net_450")
		)
		(pad "14" smd rect
			(at -6.599936 4.096512 90)
			(size 0.5588 2.0066)
			(layers "B.Cu" "B.Mask" "B.Paste")
			(net "Net_456")
		)
		(pad "15" smd rect
			(at -6.199886 -4.096512 90)
			(size 0.5588 2.0066)
			(layers "B.Cu" "B.Mask" "B.Paste")
			(net "GND")
		)
		(pad "16" smd rect
			(at -5.80009 4.096512 90)
			(size 0.5588 2.0066)
			(layers "B.Cu" "B.Mask" "B.Paste")
			(net "Net_455")
		)
		(pad "17" smd rect
			(at -2.199894 -4.096512 90)
			(size 0.5588 2.0066)
			(layers "B.Cu" "B.Mask" "B.Paste")
			(net "Net_461")
		)
		(pad "18" smd rect
			(at -1.800098 4.096512 90)
			(size 0.5588 2.0066)
			(layers "B.Cu" "B.Mask" "B.Paste")
			(net "GND")
		)
		(pad "19" smd rect
			(at -1.400048 -4.096512 90)
			(size 0.5588 2.0066)
			(layers "B.Cu" "B.Mask" "B.Paste")
			(net "Net_460")
		)
		(pad "20" smd rect
			(at -0.999998 4.096512 90)
			(size 0.5588 2.0066)
			(layers "B.Cu" "B.Mask" "B.Paste")
			(net "Net_464")
		)
		(pad "21" smd rect
			(at -0.599948 -4.096512 90)
			(size 0.5588 2.0066)
			(layers "B.Cu" "B.Mask" "B.Paste")
			(net "GND")
		)
		(pad "22" smd rect
			(at -0.199898 4.096512 90)
			(size 0.5588 2.0066)
			(layers "B.Cu" "B.Mask" "B.Paste")
			(net "Net_463")
		)
		(pad "23" smd rect
			(at 0.199898 -4.096512 90)
			(size 0.5588 2.0066)
			(layers "B.Cu" "B.Mask" "B.Paste")
			(net "SATA3_RX_C_DP0")
		)
		(pad "24" smd rect
			(at 0.599948 4.096512 90)
			(size 0.5588 2.0066)
			(layers "B.Cu" "B.Mask" "B.Paste")
			(net "P3V3")
		)
		(pad "25" smd rect
			(at 0.999998 -4.096512 90)
			(size 0.5588 2.0066)
			(layers "B.Cu" "B.Mask" "B.Paste")
			(net "SATA3_RX_C_DN0")
		)
		(pad "26" smd rect
			(at 1.400048 4.096512 90)
			(size 0.5588 2.0066)
			(layers "B.Cu" "B.Mask" "B.Paste")
			(net "GND")
		)
		(pad "27" smd rect
			(at 1.800098 -4.096512 90)
			(size 0.5588 2.0066)
			(layers "B.Cu" "B.Mask" "B.Paste")
			(net "GND")
		)
		(pad "28" smd rect
			(at 2.199894 4.096512 90)
			(size 0.5588 2.0066)
			(layers "B.Cu" "B.Mask" "B.Paste")
			(net "Net_47")
		)
		(pad "29" smd rect
			(at 2.599944 -4.096512 90)
			(size 0.5588 2.0066)
			(layers "B.Cu" "B.Mask" "B.Paste")
			(net "GND")
		)
		(pad "30" smd rect
			(at 2.999994 4.096512 90)
			(size 0.5588 2.0066)
			(layers "B.Cu" "B.Mask" "B.Paste")
			(net "Net_462")
		)
		(pad "31" smd rect
			(at 3.400044 -4.096512 90)
			(size 0.5588 2.0066)
			(layers "B.Cu" "B.Mask" "B.Paste")
			(net "SATA3_TX_C_DN0")
		)
		(pad "32" smd rect
			(at 3.800094 4.096512 90)
			(size 0.5588 2.0066)
			(layers "B.Cu" "B.Mask" "B.Paste")
			(net "Net_476")
		)
		(pad "33" smd rect
			(at 4.19989 -4.096512 90)
			(size 0.5588 2.0066)
			(layers "B.Cu" "B.Mask" "B.Paste")
			(net "SATA3_TX_C_DP0")
		)
		(pad "34" smd rect
			(at 4.59994 4.096512 90)
			(size 0.5588 2.0066)
			(layers "B.Cu" "B.Mask" "B.Paste")
			(net "GND")
		)
		(pad "35" smd rect
			(at 4.99999 -4.096512 90)
			(size 0.5588 2.0066)
			(layers "B.Cu" "B.Mask" "B.Paste")
			(net "GND")
		)
		(pad "36" smd rect
			(at 5.40004 4.096512 90)
			(size 0.5588 2.0066)
			(layers "B.Cu" "B.Mask" "B.Paste")
			(net "Net_475")
		)
		(pad "37" smd rect
			(at 5.80009 -4.096512 90)
			(size 0.5588 2.0066)
			(layers "B.Cu" "B.Mask" "B.Paste")
			(net "Net_470")
		)
		(pad "38" smd rect
			(at 6.199886 4.096512 90)
			(size 0.5588 2.0066)
			(layers "B.Cu" "B.Mask" "B.Paste")
			(net "Net_474")
		)
		(pad "39" smd rect
			(at 6.599936 -4.096512 90)
			(size 0.5588 2.0066)
			(layers "B.Cu" "B.Mask" "B.Paste")
			(net "Net_469")
		)
		(pad "40" smd rect
			(at 6.999986 4.096512 90)
			(size 0.5588 2.0066)
			(layers "B.Cu" "B.Mask" "B.Paste")
			(net "GND")
		)
		(pad "41" smd rect
			(at 7.400036 -4.096512 90)
			(size 0.5588 2.0066)
			(layers "B.Cu" "B.Mask" "B.Paste")
			(net "Net_468")
		)
		(pad "42" smd rect
			(at 7.800086 4.096512 90)
			(size 0.5588 2.0066)
			(layers "B.Cu" "B.Mask" "B.Paste")
			(net "Net_473")
		)
		(pad "43" smd rect
			(at 8.199882 -4.096512 90)
			(size 0.5588 2.0066)
			(layers "B.Cu" "B.Mask" "B.Paste")
			(net "Net_467")
		)
		(pad "44" smd rect
			(at 8.599932 4.096512 90)
			(size 0.5588 2.0066)
			(layers "B.Cu" "B.Mask" "B.Paste")
			(net "Net_472")
		)
		(pad "45" smd rect
			(at 8.999982 -4.096512 90)
			(size 0.5588 2.0066)
			(layers "B.Cu" "B.Mask" "B.Paste")
			(net "Net_466")
		)
		(pad "46" smd rect
			(at 9.400032 4.096512 90)
			(size 0.5588 2.0066)
			(layers "B.Cu" "B.Mask" "B.Paste")
			(net "Net_471")
		)
		(pad "47" smd rect
			(at 9.800082 -4.096512 90)
			(size 0.5588 2.0066)
			(layers "B.Cu" "B.Mask" "B.Paste")
			(net "Net_465")
		)
		(pad "48" smd rect
			(at 10.199878 4.096512 90)
			(size 0.5588 2.0066)
			(layers "B.Cu" "B.Mask" "B.Paste")
			(net "Net_48")
		)
		(pad "49" smd rect
			(at 10.599928 -4.096512 90)
			(size 0.5588 2.0066)
			(layers "B.Cu" "B.Mask" "B.Paste")
			(net "MSATA_ACT#")
		)
		(pad "50" smd rect
			(at 10.999978 4.096512 90)
			(size 0.5588 2.0066)
			(layers "B.Cu" "B.Mask" "B.Paste")
			(net "GND")
		)
		(pad "51" smd rect
			(at 11.400028 -4.096512 90)
			(size 0.5588 2.0066)
			(layers "B.Cu" "B.Mask" "B.Paste")
			(net "MSATA_PRESENT_R#")
		)
		(pad "52" smd rect
			(at 11.800078 4.096512 90)
			(size 0.5588 2.0066)
			(layers "B.Cu" "B.Mask" "B.Paste")
			(net "P3V3")
		)
		(pad "53" smd rect
			(at -14.649958 -3.50012 90)
			(size 2.3114 3.2004)
			(layers "B.Cu" "B.Mask" "B.Paste")
			(net "GND")
		)
		(pad "54" smd rect
			(at 14.649958 -3.50012 90)
			(size 2.3114 3.2004)
			(layers "B.Cu" "B.Mask" "B.Paste")
			(net "GND")
		)
		(zone
			(layers "F.Cu" "B.Cu" "In1.Cu" "In2.Cu" "In3.Cu" "In4.Cu" "In5.Cu" "In6.Cu"
				"In7.Cu" "In8.Cu" "In9.Cu" "In10.Cu"
			)
			(hatch none 0.5)
			(connect_pads
				(clearance 0)
			)
			(min_thickness 0.25)
			(keepout
				(tracks not_allowed)
				(vias allowed)
				(pads allowed)
				(copperpour not_allowed)
				(footprints allowed)
			)
			(placement
				(enabled no)
				(sheetname "")
			)
			(fill
				(thermal_gap 0.5)
				(thermal_bridge_width 0.5)
				(island_removal_mode 0)
			)
			(polygon
				(pts
					(arc
						(start 60.71362 -19.19986)
						(mid 58.98642 -19.19986)
						(end 60.71362 -19.19986)
					)
				)
			)
		)
		(zone
			(layers "F.Cu" "B.Cu" "In1.Cu" "In2.Cu" "In3.Cu" "In4.Cu" "In5.Cu" "In6.Cu"
				"In7.Cu" "In8.Cu" "In9.Cu" "In10.Cu"
			)
			(hatch none 0.5)
			(connect_pads
				(clearance 0)
			)
			(min_thickness 0.25)
			(keepout
				(tracks not_allowed)
				(vias allowed)
				(pads allowed)
				(copperpour not_allowed)
				(footprints allowed)
			)
			(placement
				(enabled no)
				(sheetname "")
			)
			(fill
				(thermal_gap 0.5)
				(thermal_bridge_width 0.5)
				(island_removal_mode 0)
			)
			(polygon
				(pts
					(arc
						(start 60.95492 -44.200064)
						(mid 58.74512 -44.200064)
						(end 60.95492 -44.200064)
					)
				)
			)
		)
		(zone
			(layer "B.Cu")
			(hatch none 0.5)
			(connect_pads
				(clearance 0)
			)
			(min_thickness 0.25)
			(keepout
				(tracks allowed)
				(vias not_allowed)
				(pads allowed)
				(copperpour not_allowed)
				(footprints allowed)
			)
			(placement
				(enabled no)
				(sheetname "")
			)
			(fill
				(thermal_gap 0.5)
				(thermal_bridge_width 0.5)
				(island_removal_mode 0)
			)
			(polygon
				(pts
					(xy 56.756808 -37.220652) (xy 56.756808 -43.37939) (xy 57.264808 -43.37939) (xy 57.264808 -37.220652)
				)
			)
		)
		(zone
			(layer "B.Cu")
			(hatch none 0.5)
			(connect_pads
				(clearance 0)
			)
			(min_thickness 0.25)
			(keepout
				(tracks allowed)
				(vias not_allowed)
				(pads allowed)
				(copperpour not_allowed)
				(footprints allowed)
			)
			(placement
				(enabled no)
				(sheetname "")
			)
			(fill
				(thermal_gap 0.5)
				(thermal_bridge_width 0.5)
				(island_removal_mode 0)
			)
			(polygon
				(pts
					(xy 56.756808 -19.620484) (xy 56.756808 -33.77946) (xy 57.264808 -33.77946) (xy 57.264808 -19.620484)
				)
			)
		)
		(zone
			(layer "B.Cu")
			(hatch none 0.5)
			(connect_pads
				(clearance 0)
			)
			(min_thickness 0.25)
			(keepout
				(tracks allowed)
				(vias not_allowed)
				(pads allowed)
				(copperpour not_allowed)
				(footprints allowed)
			)
			(placement
				(enabled no)
				(sheetname "")
			)
			(fill
				(thermal_gap 0.5)
				(thermal_bridge_width 0.5)
				(island_removal_mode 0)
			)
			(polygon
				(pts
					(xy 62.435232 -37.620448) (xy 62.435232 -43.77944) (xy 62.943232 -43.77944) (xy 62.943232 -37.620448)
				)
			)
		)
		(zone
			(layer "B.Cu")
			(hatch none 0.5)
			(connect_pads
				(clearance 0)
			)
			(min_thickness 0.25)
			(keepout
				(tracks allowed)
				(vias not_allowed)
				(pads allowed)
				(copperpour not_allowed)
				(footprints allowed)
			)
			(placement
				(enabled no)
				(sheetname "")
			)
			(fill
				(thermal_gap 0.5)
				(thermal_bridge_width 0.5)
				(island_removal_mode 0)
			)
			(polygon
				(pts
					(xy 62.435232 -20.020534) (xy 62.435232 -34.179256) (xy 62.943232 -34.179256) (xy 62.943232 -20.020534)
				)
			)
		)
	)
	(footprint ""
		(layer "B.Cu")
		(at 38.989 -50.3682 90)
		(property "Reference" "R129"
			(at 0 0 90)
			(layer "B.SilkS")
			(hide yes)
			(effects
				(font
					(size 1.27 1.27)
				)
				(justify mirror)
			)
		)
		(property "Value" "0R2J-2-GP"
			(at -1.7907 -1.1176 90)
			(unlocked yes)
			(layer "B.Fab")
			(hide yes)
			(effects
				(font
					(size 1.016 1.016)
					(thickness 0.1524)
				)
				(justify mirror)
			)
		)
		(property "Device Type" "R402H16"
			(at -1.7907 -2.6416 90)
			(unlocked yes)
			(layer "B.Fab")
			(hide yes)
			(effects
				(font
					(size 1.016 1.016)
					(thickness 0.1524)
				)
				(justify mirror)
			)
		)
		(duplicate_pad_numbers_are_jumpers no)
		(fp_rect
			(start 0.381 0.8382)
			(end -0.381 -0.8382)
			(stroke
				(width 0)
				(type default)
			)
			(fill no)
			(layer "B.CrtYd")
		)
		(fp_rect
			(start 0.381 0.8382)
			(end -0.381 -0.8382)
			(stroke
				(width 0)
				(type default)
			)
			(fill no)
			(layer "B.Fab")
		)
		(pad "1" smd custom
			(at 0 -0.4318 270)
			(size 0.127 0.127)
			(layers "B.Cu" "B.Mask" "B.Paste")
			(net "SMB_HOST_LV_CLK")
			(options
				(clearance outline)
				(anchor circle)
			)
			(primitives
				(gr_poly
					(pts
						(arc
							(start -0.2032 0.2794)
							(mid -0.239121 0.264521)
							(end -0.254 0.2286)
						)
						(arc
							(start -0.254 -0.2286)
							(mid -0.239121 -0.264521)
							(end -0.2032 -0.2794)
						)
						(arc
							(start 0.2032 -0.2794)
							(mid 0.239121 -0.264521)
							(end 0.254 -0.2286)
						)
						(arc
							(start 0.254 0.2286)
							(mid 0.239121 0.264521)
							(end 0.2032 0.2794)
						)
					)
					(width 0)
					(fill yes)
				)
			)
		)
		(pad "2" smd custom
			(at 0 0.4318 270)
			(size 0.127 0.127)
			(layers "B.Cu" "B.Mask" "B.Paste")
			(net "SMB_CLKGEN_R_CLK")
			(options
				(clearance outline)
				(anchor circle)
			)
			(primitives
				(gr_poly
					(pts
						(arc
							(start -0.2032 0.2794)
							(mid -0.239121 0.264521)
							(end -0.254 0.2286)
						)
						(arc
							(start -0.254 -0.2286)
							(mid -0.239121 -0.264521)
							(end -0.2032 -0.2794)
						)
						(arc
							(start 0.2032 -0.2794)
							(mid 0.239121 -0.264521)
							(end 0.254 -0.2286)
						)
						(arc
							(start 0.254 0.2286)
							(mid 0.239121 0.264521)
							(end 0.2032 0.2794)
						)
					)
					(width 0)
					(fill yes)
				)
			)
		)
	)
	(footprint ""
		(layer "B.Cu")
		(at 92.5322 -40.9829 180)
		(property "Reference" "C167"
			(at 0 0 0)
			(layer "B.SilkS")
			(hide yes)
			(effects
				(font
					(size 1.27 1.27)
				)
				(justify mirror)
			)
		)
		(property "Value" "SC1U10V2KX-1GP"
			(at -1.1811 -2.7051 180)
			(unlocked yes)
			(layer "B.Fab")
			(hide yes)
			(effects
				(font
					(size 1.016 1.016)
					(thickness 0.1524)
				)
				(justify mirror)
			)
		)
		(property "Device Type" "C402H22"
			(at -1.1811 -4.2291 180)
			(unlocked yes)
			(layer "B.Fab")
			(hide yes)
			(effects
				(font
					(size 1.016 1.016)
					(thickness 0.1524)
				)
				(justify mirror)
			)
		)
		(duplicate_pad_numbers_are_jumpers no)
		(fp_rect
			(start 0.381 0.7366)
			(end -0.381 -0.7366)
			(stroke
				(width 0)
				(type default)
			)
			(fill no)
			(layer "B.CrtYd")
		)
		(fp_rect
			(start 0.381 0.7366)
			(end -0.381 -0.7366)
			(stroke
				(width 0)
				(type default)
			)
			(fill no)
			(layer "B.Fab")
		)
		(pad "1" smd custom
			(at 0 -0.4572)
			(size 0.1143 0.1143)
			(layers "B.Cu" "B.Mask" "B.Paste")
			(net "PVNN")
			(options
				(clearance outline)
				(anchor circle)
			)
			(primitives
				(gr_poly
					(pts
						(arc
							(start -0.254 0.1778)
							(mid -0.239121 0.213721)
							(end -0.2032 0.2286)
						)
						(arc
							(start 0.2032 0.2286)
							(mid 0.239121 0.213721)
							(end 0.254 0.1778)
						)
						(arc
							(start 0.254 -0.1778)
							(mid 0.239121 -0.213721)
							(end 0.2032 -0.2286)
						)
						(arc
							(start -0.2032 -0.2286)
							(mid -0.239121 -0.213721)
							(end -0.254 -0.1778)
						)
					)
					(width 0)
					(fill yes)
				)
			)
		)
		(pad "2" smd custom
			(at 0 0.4572)
			(size 0.1143 0.1143)
			(layers "B.Cu" "B.Mask" "B.Paste")
			(net "GND")
			(options
				(clearance outline)
				(anchor circle)
			)
			(primitives
				(gr_poly
					(pts
						(arc
							(start -0.254 0.1778)
							(mid -0.239121 0.213721)
							(end -0.2032 0.2286)
						)
						(arc
							(start 0.2032 0.2286)
							(mid 0.239121 0.213721)
							(end 0.254 0.1778)
						)
						(arc
							(start 0.254 -0.1778)
							(mid 0.239121 -0.213721)
							(end 0.2032 -0.2286)
						)
						(arc
							(start -0.2032 -0.2286)
							(mid -0.239121 -0.213721)
							(end -0.254 -0.1778)
						)
					)
					(width 0)
					(fill yes)
				)
			)
		)
	)
	(footprint ""
		(layer "B.Cu")
		(at 44.6024 -28.321 180)
		(property "Reference" "R446"
			(at 0 0 0)
			(layer "B.SilkS")
			(hide yes)
			(effects
				(font
					(size 1.27 1.27)
				)
				(justify mirror)
			)
		)
		(property "Value" "4K7R2F-GP"
			(at -1.7907 -1.1176 180)
			(unlocked yes)
			(layer "B.Fab")
			(hide yes)
			(effects
				(font
					(size 1.016 1.016)
					(thickness 0.1524)
				)
				(justify mirror)
			)
		)
		(property "Device Type" "R402H16"
			(at -1.7907 -2.6416 180)
			(unlocked yes)
			(layer "B.Fab")
			(hide yes)
			(effects
				(font
					(size 1.016 1.016)
					(thickness 0.1524)
				)
				(justify mirror)
			)
		)
		(duplicate_pad_numbers_are_jumpers no)
		(fp_rect
			(start 0.381 0.8382)
			(end -0.381 -0.8382)
			(stroke
				(width 0)
				(type default)
			)
			(fill no)
			(layer "B.CrtYd")
		)
		(fp_rect
			(start 0.381 0.8382)
			(end -0.381 -0.8382)
			(stroke
				(width 0)
				(type default)
			)
			(fill no)
			(layer "B.Fab")
		)
		(pad "1" smd custom
			(at 0 -0.4318)
			(size 0.127 0.127)
			(layers "B.Cu" "B.Mask" "B.Paste")
			(net "CLKBUFF_OE5#")
			(options
				(clearance outline)
				(anchor circle)
			)
			(primitives
				(gr_poly
					(pts
						(arc
							(start -0.2032 0.2794)
							(mid -0.239121 0.264521)
							(end -0.254 0.2286)
						)
						(arc
							(start -0.254 -0.2286)
							(mid -0.239121 -0.264521)
							(end -0.2032 -0.2794)
						)
						(arc
							(start 0.2032 -0.2794)
							(mid 0.239121 -0.264521)
							(end 0.254 -0.2286)
						)
						(arc
							(start 0.254 0.2286)
							(mid 0.239121 0.264521)
							(end 0.2032 0.2794)
						)
					)
					(width 0)
					(fill yes)
				)
			)
		)
		(pad "2" smd custom
			(at 0 0.4318)
			(size 0.127 0.127)
			(layers "B.Cu" "B.Mask" "B.Paste")
			(net "GND")
			(options
				(clearance outline)
				(anchor circle)
			)
			(primitives
				(gr_poly
					(pts
						(arc
							(start -0.2032 0.2794)
							(mid -0.239121 0.264521)
							(end -0.254 0.2286)
						)
						(arc
							(start -0.254 -0.2286)
							(mid -0.239121 -0.264521)
							(end -0.2032 -0.2794)
						)
						(arc
							(start 0.2032 -0.2794)
							(mid 0.239121 -0.264521)
							(end 0.254 -0.2286)
						)
						(arc
							(start 0.254 0.2286)
							(mid 0.239121 0.264521)
							(end 0.2032 0.2794)
						)
					)
					(width 0)
					(fill yes)
				)
			)
		)
	)
	(footprint ""
		(layer "B.Cu")
		(at 160.8582 -12.447778 180)
		(property "Reference" "C334"
			(at 0 0 0)
			(layer "B.SilkS")
			(hide yes)
			(effects
				(font
					(size 1.27 1.27)
				)
				(justify mirror)
			)
		)
		(property "Value" "SCD1U16V2KX-3GP"
			(at -1.8923 -1.2065 180)
			(unlocked yes)
			(layer "B.Fab")
			(hide yes)
			(effects
				(font
					(size 1.016 1.016)
					(thickness 0.1524)
				)
				(justify mirror)
			)
		)
		(property "Device Type" "C402H22"
			(at -1.8923 -2.7305 180)
			(unlocked yes)
			(layer "B.Fab")
			(hide yes)
			(effects
				(font
					(size 1.016 1.016)
					(thickness 0.1524)
				)
				(justify mirror)
			)
		)
		(duplicate_pad_numbers_are_jumpers no)
		(fp_rect
			(start 0.381 0.7366)
			(end -0.381 -0.7366)
			(stroke
				(width 0)
				(type default)
			)
			(fill no)
			(layer "B.CrtYd")
		)
		(fp_rect
			(start 0.381 0.7366)
			(end -0.381 -0.7366)
			(stroke
				(width 0)
				(type default)
			)
			(fill no)
			(layer "B.Fab")
		)
		(pad "1" smd custom
			(at 0 -0.4572)
			(size 0.1143 0.1143)
			(layers "B.Cu" "B.Mask" "B.Paste")
			(net "PV_VDDR")
			(options
				(clearance outline)
				(anchor circle)
			)
			(primitives
				(gr_poly
					(pts
						(arc
							(start -0.254 0.1778)
							(mid -0.239121 0.213721)
							(end -0.2032 0.2286)
						)
						(arc
							(start 0.2032 0.2286)
							(mid 0.239121 0.213721)
							(end 0.254 0.1778)
						)
						(arc
							(start 0.254 -0.1778)
							(mid 0.239121 -0.213721)
							(end 0.2032 -0.2286)
						)
						(arc
							(start -0.2032 -0.2286)
							(mid -0.239121 -0.213721)
							(end -0.254 -0.1778)
						)
					)
					(width 0)
					(fill yes)
				)
			)
		)
		(pad "2" smd custom
			(at 0 0.4572)
			(size 0.1143 0.1143)
			(layers "B.Cu" "B.Mask" "B.Paste")
			(net "GND")
			(options
				(clearance outline)
				(anchor circle)
			)
			(primitives
				(gr_poly
					(pts
						(arc
							(start -0.254 0.1778)
							(mid -0.239121 0.213721)
							(end -0.2032 0.2286)
						)
						(arc
							(start 0.2032 0.2286)
							(mid 0.239121 0.213721)
							(end 0.254 0.1778)
						)
						(arc
							(start 0.254 -0.1778)
							(mid 0.239121 -0.213721)
							(end 0.2032 -0.2286)
						)
						(arc
							(start -0.2032 -0.2286)
							(mid -0.239121 -0.213721)
							(end -0.254 -0.1778)
						)
					)
					(width 0)
					(fill yes)
				)
			)
		)
	)
	(footprint ""
		(layer "B.Cu")
		(at 40.6654 -47.117)
		(property "Reference" "C61"
			(at 0 0 0)
			(layer "B.SilkS")
			(hide yes)
			(effects
				(font
					(size 1.27 1.27)
				)
				(justify mirror)
			)
		)
		(property "Value" "SCD1U10V2KX-5GP"
			(at -1.8923 -1.2065 0)
			(unlocked yes)
			(layer "B.Fab")
			(hide yes)
			(effects
				(font
					(size 1.016 1.016)
					(thickness 0.1524)
				)
				(justify mirror)
			)
		)
		(property "Device Type" "C402H22"
			(at -1.8923 -2.7305 0)
			(unlocked yes)
			(layer "B.Fab")
			(hide yes)
			(effects
				(font
					(size 1.016 1.016)
					(thickness 0.1524)
				)
				(justify mirror)
			)
		)
		(duplicate_pad_numbers_are_jumpers no)
		(fp_rect
			(start 0.381 0.7366)
			(end -0.381 -0.7366)
			(stroke
				(width 0)
				(type default)
			)
			(fill no)
			(layer "B.CrtYd")
		)
		(fp_rect
			(start 0.381 0.7366)
			(end -0.381 -0.7366)
			(stroke
				(width 0)
				(type default)
			)
			(fill no)
			(layer "B.Fab")
		)
		(pad "1" smd custom
			(at 0 -0.4572 180)
			(size 0.1143 0.1143)
			(layers "B.Cu" "B.Mask" "B.Paste")
			(net "P3V3_CLK_XTAL")
			(options
				(clearance outline)
				(anchor circle)
			)
			(primitives
				(gr_poly
					(pts
						(arc
							(start -0.254 0.1778)
							(mid -0.239121 0.213721)
							(end -0.2032 0.2286)
						)
						(arc
							(start 0.2032 0.2286)
							(mid 0.239121 0.213721)
							(end 0.254 0.1778)
						)
						(arc
							(start 0.254 -0.1778)
							(mid 0.239121 -0.213721)
							(end 0.2032 -0.2286)
						)
						(arc
							(start -0.2032 -0.2286)
							(mid -0.239121 -0.213721)
							(end -0.254 -0.1778)
						)
					)
					(width 0)
					(fill yes)
				)
			)
		)
		(pad "2" smd custom
			(at 0 0.4572 180)
			(size 0.1143 0.1143)
			(layers "B.Cu" "B.Mask" "B.Paste")
			(net "GND")
			(options
				(clearance outline)
				(anchor circle)
			)
			(primitives
				(gr_poly
					(pts
						(arc
							(start -0.254 0.1778)
							(mid -0.239121 0.213721)
							(end -0.2032 0.2286)
						)
						(arc
							(start 0.2032 0.2286)
							(mid 0.239121 0.213721)
							(end 0.254 0.1778)
						)
						(arc
							(start 0.254 -0.1778)
							(mid 0.239121 -0.213721)
							(end 0.2032 -0.2286)
						)
						(arc
							(start -0.2032 -0.2286)
							(mid -0.239121 -0.213721)
							(end -0.254 -0.1778)
						)
					)
					(width 0)
					(fill yes)
				)
			)
		)
	)
	(footprint ""
		(layer "B.Cu")
		(at 186.563 -26.797 90)
		(property "Reference" "PR210"
			(at 0 0 90)
			(layer "B.SilkS")
			(hide yes)
			(effects
				(font
					(size 1.27 1.27)
				)
				(justify mirror)
			)
		)
		(property "Value" "11KR2F-L-GP"
			(at -1.7907 -1.1176 90)
			(unlocked yes)
			(layer "B.Fab")
			(hide yes)
			(effects
				(font
					(size 1.016 1.016)
					(thickness 0.1524)
				)
				(justify mirror)
			)
		)
		(property "Device Type" "R402H16"
			(at -1.7907 -2.6416 90)
			(unlocked yes)
			(layer "B.Fab")
			(hide yes)
			(effects
				(font
					(size 1.016 1.016)
					(thickness 0.1524)
				)
				(justify mirror)
			)
		)
		(duplicate_pad_numbers_are_jumpers no)
		(fp_rect
			(start 0.381 0.8382)
			(end -0.381 -0.8382)
			(stroke
				(width 0)
				(type default)
			)
			(fill no)
			(layer "B.CrtYd")
		)
		(fp_rect
			(start 0.381 0.8382)
			(end -0.381 -0.8382)
			(stroke
				(width 0)
				(type default)
			)
			(fill no)
			(layer "B.Fab")
		)
		(pad "1" smd custom
			(at 0 -0.4318 270)
			(size 0.127 0.127)
			(layers "B.Cu" "B.Mask" "B.Paste")
			(net "VR_PVDDRA_ISUMP1")
			(options
				(clearance outline)
				(anchor circle)
			)
			(primitives
				(gr_poly
					(pts
						(arc
							(start -0.2032 0.2794)
							(mid -0.239121 0.264521)
							(end -0.254 0.2286)
						)
						(arc
							(start -0.254 -0.2286)
							(mid -0.239121 -0.264521)
							(end -0.2032 -0.2794)
						)
						(arc
							(start 0.2032 -0.2794)
							(mid 0.239121 -0.264521)
							(end 0.254 -0.2286)
						)
						(arc
							(start 0.254 0.2286)
							(mid 0.239121 0.264521)
							(end 0.2032 0.2794)
						)
					)
					(width 0)
					(fill yes)
				)
			)
		)
		(pad "2" smd custom
			(at 0 0.4318 270)
			(size 0.127 0.127)
			(layers "B.Cu" "B.Mask" "B.Paste")
			(net "VR_PVDDRA_ISUMN1")
			(options
				(clearance outline)
				(anchor circle)
			)
			(primitives
				(gr_poly
					(pts
						(arc
							(start -0.2032 0.2794)
							(mid -0.239121 0.264521)
							(end -0.254 0.2286)
						)
						(arc
							(start -0.254 -0.2286)
							(mid -0.239121 -0.264521)
							(end -0.2032 -0.2794)
						)
						(arc
							(start 0.2032 -0.2794)
							(mid 0.239121 -0.264521)
							(end 0.254 -0.2286)
						)
						(arc
							(start 0.254 0.2286)
							(mid 0.239121 0.264521)
							(end 0.2032 0.2794)
						)
					)
					(width 0)
					(fill yes)
				)
			)
		)
	)
	(footprint ""
		(layer "B.Cu")
		(at 146.05 -23.495 -90)
		(property "Reference" "R104"
			(at 0 0 90)
			(layer "B.SilkS")
			(hide yes)
			(effects
				(font
					(size 1.27 1.27)
				)
				(justify mirror)
			)
		)
		(property "Value" "0R2J-2-GP"
			(at -0.064008 -3.993896 270)
			(unlocked yes)
			(layer "B.Fab")
			(hide yes)
			(effects
				(font
					(size 1.016 1.016)
					(thickness 0.1524)
				)
				(justify mirror)
			)
		)
		(property "Device Type" "R402H16"
			(at -0.064008 -5.517896 270)
			(unlocked yes)
			(layer "B.Fab")
			(hide yes)
			(effects
				(font
					(size 1.016 1.016)
					(thickness 0.1524)
				)
				(justify mirror)
			)
		)
		(duplicate_pad_numbers_are_jumpers no)
		(fp_rect
			(start 0.381 0.8382)
			(end -0.381 -0.8382)
			(stroke
				(width 0)
				(type default)
			)
			(fill no)
			(layer "B.CrtYd")
		)
		(fp_rect
			(start 0.381 0.8382)
			(end -0.381 -0.8382)
			(stroke
				(width 0)
				(type default)
			)
			(fill no)
			(layer "B.Fab")
		)
		(pad "1" smd custom
			(at 0 -0.4318 90)
			(size 0.127 0.127)
			(layers "B.Cu" "B.Mask" "B.Paste")
			(net "MSEL2")
			(options
				(clearance outline)
				(anchor circle)
			)
			(primitives
				(gr_poly
					(pts
						(arc
							(start -0.2032 0.2794)
							(mid -0.239121 0.264521)
							(end -0.254 0.2286)
						)
						(arc
							(start -0.254 -0.2286)
							(mid -0.239121 -0.264521)
							(end -0.2032 -0.2794)
						)
						(arc
							(start 0.2032 -0.2794)
							(mid 0.239121 -0.264521)
							(end 0.254 -0.2286)
						)
						(arc
							(start 0.254 0.2286)
							(mid 0.239121 0.264521)
							(end 0.2032 0.2794)
						)
					)
					(width 0)
					(fill yes)
				)
			)
		)
		(pad "2" smd custom
			(at 0 0.4318 90)
			(size 0.127 0.127)
			(layers "B.Cu" "B.Mask" "B.Paste")
			(net "GND")
			(options
				(clearance outline)
				(anchor circle)
			)
			(primitives
				(gr_poly
					(pts
						(arc
							(start -0.2032 0.2794)
							(mid -0.239121 0.264521)
							(end -0.254 0.2286)
						)
						(arc
							(start -0.254 -0.2286)
							(mid -0.239121 -0.264521)
							(end -0.2032 -0.2794)
						)
						(arc
							(start 0.2032 -0.2794)
							(mid 0.239121 -0.264521)
							(end 0.254 -0.2286)
						)
						(arc
							(start 0.254 0.2286)
							(mid 0.239121 0.264521)
							(end 0.2032 0.2794)
						)
					)
					(width 0)
					(fill yes)
				)
			)
		)
	)
	(footprint ""
		(layer "B.Cu")
		(at 87.757 -42.291)
		(property "Reference" "TP66"
			(at 0 0 0)
			(layer "B.SilkS")
			(hide yes)
			(effects
				(font
					(size 1.27 1.27)
				)
				(justify mirror)
			)
		)
		(property "Value" "TPAD28-1-GP-U"
			(at -0.0508 -1.9304 0)
			(unlocked yes)
			(layer "B.Fab")
			(hide yes)
			(effects
				(font
					(size 1.016 1.016)
					(thickness 0.1524)
				)
				(justify mirror)
			)
		)
		(property "Device Type" "TPAD28-1-U"
			(at -0.0508 -3.4544 0)
			(unlocked yes)
			(layer "B.Fab")
			(hide yes)
			(effects
				(font
					(size 1.016 1.016)
					(thickness 0.1524)
				)
				(justify mirror)
			)
		)
		(duplicate_pad_numbers_are_jumpers no)
		(fp_poly
			(pts
				(arc
					(start 0.3556 0)
					(mid -0.3556 0)
					(end 0.3556 0)
				)
			)
			(stroke
				(width 0)
				(type default)
			)
			(fill no)
			(layer "B.CrtYd")
		)
		(fp_poly
			(pts
				(arc
					(start 0.9525 0)
					(mid -0.9525 0)
					(end 0.9525 0)
				)
			)
			(stroke
				(width 0)
				(type default)
			)
			(fill no)
			(layer "B.Fab")
		)
		(pad "1" smd circle
			(at 0 0 180)
			(size 0.7112 0.7112)
			(layers "B.Cu" "B.Mask" "B.Paste")
			(net "LPC_CPU_R_CLKOUT1")
		)
	)
	(footprint ""
		(layer "B.Cu")
		(at 70.358 -12.954)
		(property "Reference" "R479"
			(at 0 0 0)
			(layer "B.SilkS")
			(hide yes)
			(effects
				(font
					(size 1.27 1.27)
				)
				(justify mirror)
			)
		)
		(property "Value" "4K7R2F-GP"
			(at -1.7907 -1.1176 0)
			(unlocked yes)
			(layer "B.Fab")
			(hide yes)
			(effects
				(font
					(size 1.016 1.016)
					(thickness 0.1524)
				)
				(justify mirror)
			)
		)
		(property "Device Type" "R402H16"
			(at -1.7907 -2.6416 0)
			(unlocked yes)
			(layer "B.Fab")
			(hide yes)
			(effects
				(font
					(size 1.016 1.016)
					(thickness 0.1524)
				)
				(justify mirror)
			)
		)
		(duplicate_pad_numbers_are_jumpers no)
		(fp_rect
			(start 0.381 0.8382)
			(end -0.381 -0.8382)
			(stroke
				(width 0)
				(type default)
			)
			(fill no)
			(layer "B.CrtYd")
		)
		(fp_rect
			(start 0.381 0.8382)
			(end -0.381 -0.8382)
			(stroke
				(width 0)
				(type default)
			)
			(fill no)
			(layer "B.Fab")
		)
		(pad "1" smd custom
			(at 0 -0.4318 180)
			(size 0.127 0.127)
			(layers "B.Cu" "B.Mask" "B.Paste")
			(net "P3V3")
			(options
				(clearance outline)
				(anchor circle)
			)
			(primitives
				(gr_poly
					(pts
						(arc
							(start -0.2032 0.2794)
							(mid -0.239121 0.264521)
							(end -0.254 0.2286)
						)
						(arc
							(start -0.254 -0.2286)
							(mid -0.239121 -0.264521)
							(end -0.2032 -0.2794)
						)
						(arc
							(start 0.2032 -0.2794)
							(mid 0.239121 -0.264521)
							(end 0.254 -0.2286)
						)
						(arc
							(start 0.254 0.2286)
							(mid 0.239121 0.264521)
							(end 0.2032 0.2794)
						)
					)
					(width 0)
					(fill yes)
				)
			)
		)
		(pad "2" smd custom
			(at 0 0.4318 180)
			(size 0.127 0.127)
			(layers "B.Cu" "B.Mask" "B.Paste")
			(net "BMC_SYS_RESET#")
			(options
				(clearance outline)
				(anchor circle)
			)
			(primitives
				(gr_poly
					(pts
						(arc
							(start -0.2032 0.2794)
							(mid -0.239121 0.264521)
							(end -0.254 0.2286)
						)
						(arc
							(start -0.254 -0.2286)
							(mid -0.239121 -0.264521)
							(end -0.2032 -0.2794)
						)
						(arc
							(start 0.2032 -0.2794)
							(mid 0.239121 -0.264521)
							(end 0.254 -0.2286)
						)
						(arc
							(start 0.254 0.2286)
							(mid 0.239121 0.264521)
							(end 0.2032 0.2794)
						)
					)
					(width 0)
					(fill yes)
				)
			)
		)
	)
	(footprint ""
		(layer "B.Cu")
		(at 65.4812 -22.479)
		(property "Reference" "R158"
			(at 0 0 0)
			(layer "B.SilkS")
			(hide yes)
			(effects
				(font
					(size 1.27 1.27)
				)
				(justify mirror)
			)
		)
		(property "Value" "4K7R2F-GP"
			(at -1.7907 -1.1176 0)
			(unlocked yes)
			(layer "B.Fab")
			(hide yes)
			(effects
				(font
					(size 1.016 1.016)
					(thickness 0.1524)
				)
				(justify mirror)
			)
		)
		(property "Device Type" "R402H16"
			(at -1.7907 -2.6416 0)
			(unlocked yes)
			(layer "B.Fab")
			(hide yes)
			(effects
				(font
					(size 1.016 1.016)
					(thickness 0.1524)
				)
				(justify mirror)
			)
		)
		(duplicate_pad_numbers_are_jumpers no)
		(fp_rect
			(start 0.381 0.8382)
			(end -0.381 -0.8382)
			(stroke
				(width 0)
				(type default)
			)
			(fill no)
			(layer "B.CrtYd")
		)
		(fp_rect
			(start 0.381 0.8382)
			(end -0.381 -0.8382)
			(stroke
				(width 0)
				(type default)
			)
			(fill no)
			(layer "B.Fab")
		)
		(pad "1" smd custom
			(at 0 -0.4318 180)
			(size 0.127 0.127)
			(layers "B.Cu" "B.Mask" "B.Paste")
			(net "P3V3")
			(options
				(clearance outline)
				(anchor circle)
			)
			(primitives
				(gr_poly
					(pts
						(arc
							(start -0.2032 0.2794)
							(mid -0.239121 0.264521)
							(end -0.254 0.2286)
						)
						(arc
							(start -0.254 -0.2286)
							(mid -0.239121 -0.264521)
							(end -0.2032 -0.2794)
						)
						(arc
							(start 0.2032 -0.2794)
							(mid 0.239121 -0.264521)
							(end 0.254 -0.2286)
						)
						(arc
							(start 0.254 0.2286)
							(mid 0.239121 0.264521)
							(end 0.2032 0.2794)
						)
					)
					(width 0)
					(fill yes)
				)
			)
		)
		(pad "2" smd custom
			(at 0 0.4318 180)
			(size 0.127 0.127)
			(layers "B.Cu" "B.Mask" "B.Paste")
			(net "MSATA_ACT#")
			(options
				(clearance outline)
				(anchor circle)
			)
			(primitives
				(gr_poly
					(pts
						(arc
							(start -0.2032 0.2794)
							(mid -0.239121 0.264521)
							(end -0.254 0.2286)
						)
						(arc
							(start -0.254 -0.2286)
							(mid -0.239121 -0.264521)
							(end -0.2032 -0.2794)
						)
						(arc
							(start 0.2032 -0.2794)
							(mid 0.239121 -0.264521)
							(end 0.254 -0.2286)
						)
						(arc
							(start 0.254 0.2286)
							(mid 0.239121 0.264521)
							(end 0.2032 0.2794)
						)
					)
					(width 0)
					(fill yes)
				)
			)
		)
	)
	(footprint ""
		(layer "B.Cu")
		(at 69.977 -61.722)
		(property "Reference" "C79"
			(at 0 0 0)
			(layer "B.SilkS")
			(hide yes)
			(effects
				(font
					(size 1.27 1.27)
				)
				(justify mirror)
			)
		)
		(property "Value" "SCD1U16V2KX-3GP"
			(at -1.8923 -1.2065 0)
			(unlocked yes)
			(layer "B.Fab")
			(hide yes)
			(effects
				(font
					(size 1.016 1.016)
					(thickness 0.1524)
				)
				(justify mirror)
			)
		)
		(property "Device Type" "C402H22"
			(at -1.8923 -2.7305 0)
			(unlocked yes)
			(layer "B.Fab")
			(hide yes)
			(effects
				(font
					(size 1.016 1.016)
					(thickness 0.1524)
				)
				(justify mirror)
			)
		)
		(duplicate_pad_numbers_are_jumpers no)
		(fp_rect
			(start 0.381 0.7366)
			(end -0.381 -0.7366)
			(stroke
				(width 0)
				(type default)
			)
			(fill no)
			(layer "B.CrtYd")
		)
		(fp_rect
			(start 0.381 0.7366)
			(end -0.381 -0.7366)
			(stroke
				(width 0)
				(type default)
			)
			(fill no)
			(layer "B.Fab")
		)
		(pad "1" smd custom
			(at 0 -0.4572 180)
			(size 0.1143 0.1143)
			(layers "B.Cu" "B.Mask" "B.Paste")
			(net "P3V3_STBY_SENSE")
			(options
				(clearance outline)
				(anchor circle)
			)
			(primitives
				(gr_poly
					(pts
						(arc
							(start -0.254 0.1778)
							(mid -0.239121 0.213721)
							(end -0.2032 0.2286)
						)
						(arc
							(start 0.2032 0.2286)
							(mid 0.239121 0.213721)
							(end 0.254 0.1778)
						)
						(arc
							(start 0.254 -0.1778)
							(mid 0.239121 -0.213721)
							(end 0.2032 -0.2286)
						)
						(arc
							(start -0.2032 -0.2286)
							(mid -0.239121 -0.213721)
							(end -0.254 -0.1778)
						)
					)
					(width 0)
					(fill yes)
				)
			)
		)
		(pad "2" smd custom
			(at 0 0.4572 180)
			(size 0.1143 0.1143)
			(layers "B.Cu" "B.Mask" "B.Paste")
			(net "GND")
			(options
				(clearance outline)
				(anchor circle)
			)
			(primitives
				(gr_poly
					(pts
						(arc
							(start -0.254 0.1778)
							(mid -0.239121 0.213721)
							(end -0.2032 0.2286)
						)
						(arc
							(start 0.2032 0.2286)
							(mid 0.239121 0.213721)
							(end 0.254 0.1778)
						)
						(arc
							(start 0.254 -0.1778)
							(mid 0.239121 -0.213721)
							(end 0.2032 -0.2286)
						)
						(arc
							(start -0.2032 -0.2286)
							(mid -0.239121 -0.213721)
							(end -0.254 -0.1778)
						)
					)
					(width 0)
					(fill yes)
				)
			)
		)
	)
	(footprint ""
		(layer "B.Cu")
		(at 196.85 -4.6736 180)
		(property "Reference" "R383"
			(at 0 0 0)
			(layer "B.SilkS")
			(hide yes)
			(effects
				(font
					(size 1.27 1.27)
				)
				(justify mirror)
			)
		)
		(property "Value" "0R2J-2-GP"
			(at -0.064008 -3.993896 180)
			(unlocked yes)
			(layer "B.Fab")
			(hide yes)
			(effects
				(font
					(size 1.016 1.016)
					(thickness 0.1524)
				)
				(justify mirror)
			)
		)
		(property "Device Type" "R402H16"
			(at -0.064008 -5.517896 180)
			(unlocked yes)
			(layer "B.Fab")
			(hide yes)
			(effects
				(font
					(size 1.016 1.016)
					(thickness 0.1524)
				)
				(justify mirror)
			)
		)
		(duplicate_pad_numbers_are_jumpers no)
		(fp_rect
			(start 0.381 0.8382)
			(end -0.381 -0.8382)
			(stroke
				(width 0)
				(type default)
			)
			(fill no)
			(layer "B.CrtYd")
		)
		(fp_rect
			(start 0.381 0.8382)
			(end -0.381 -0.8382)
			(stroke
				(width 0)
				(type default)
			)
			(fill no)
			(layer "B.Fab")
		)
		(pad "1" smd custom
			(at 0 -0.4318)
			(size 0.127 0.127)
			(layers "B.Cu" "B.Mask" "B.Paste")
			(net "SMB_M_B0_R_CLK")
			(options
				(clearance outline)
				(anchor circle)
			)
			(primitives
				(gr_poly
					(pts
						(arc
							(start -0.2032 0.2794)
							(mid -0.239121 0.264521)
							(end -0.254 0.2286)
						)
						(arc
							(start -0.254 -0.2286)
							(mid -0.239121 -0.264521)
							(end -0.2032 -0.2794)
						)
						(arc
							(start 0.2032 -0.2794)
							(mid 0.239121 -0.264521)
							(end 0.254 -0.2286)
						)
						(arc
							(start 0.254 0.2286)
							(mid 0.239121 0.264521)
							(end 0.2032 0.2794)
						)
					)
					(width 0)
					(fill yes)
				)
			)
		)
		(pad "2" smd custom
			(at 0 0.4318)
			(size 0.127 0.127)
			(layers "B.Cu" "B.Mask" "B.Paste")
			(net "SMB_HOST_LV_CLK")
			(options
				(clearance outline)
				(anchor circle)
			)
			(primitives
				(gr_poly
					(pts
						(arc
							(start -0.2032 0.2794)
							(mid -0.239121 0.264521)
							(end -0.254 0.2286)
						)
						(arc
							(start -0.254 -0.2286)
							(mid -0.239121 -0.264521)
							(end -0.2032 -0.2794)
						)
						(arc
							(start 0.2032 -0.2794)
							(mid 0.239121 -0.264521)
							(end 0.254 -0.2286)
						)
						(arc
							(start 0.254 0.2286)
							(mid 0.239121 0.264521)
							(end 0.2032 0.2794)
						)
					)
					(width 0)
					(fill yes)
				)
			)
		)
	)
	(footprint ""
		(layer "B.Cu")
		(at 186.69 -17.272 180)
		(property "Reference" "C291"
			(at 0 0 0)
			(layer "B.SilkS")
			(hide yes)
			(effects
				(font
					(size 1.27 1.27)
				)
				(justify mirror)
			)
		)
		(property "Value" "SC1U6D3V2KX-GP"
			(at -1.1811 -2.7051 180)
			(unlocked yes)
			(layer "B.Fab")
			(hide yes)
			(effects
				(font
					(size 1.016 1.016)
					(thickness 0.1524)
				)
				(justify mirror)
			)
		)
		(property "Device Type" "C402H22"
			(at -1.1811 -4.2291 180)
			(unlocked yes)
			(layer "B.Fab")
			(hide yes)
			(effects
				(font
					(size 1.016 1.016)
					(thickness 0.1524)
				)
				(justify mirror)
			)
		)
		(duplicate_pad_numbers_are_jumpers no)
		(fp_rect
			(start 0.381 0.7366)
			(end -0.381 -0.7366)
			(stroke
				(width 0)
				(type default)
			)
			(fill no)
			(layer "B.CrtYd")
		)
		(fp_rect
			(start 0.381 0.7366)
			(end -0.381 -0.7366)
			(stroke
				(width 0)
				(type default)
			)
			(fill no)
			(layer "B.Fab")
		)
		(pad "1" smd custom
			(at 0 -0.4572)
			(size 0.1143 0.1143)
			(layers "B.Cu" "B.Mask" "B.Paste")
			(net "PV_VTT_DDR_B")
			(options
				(clearance outline)
				(anchor circle)
			)
			(primitives
				(gr_poly
					(pts
						(arc
							(start -0.254 0.1778)
							(mid -0.239121 0.213721)
							(end -0.2032 0.2286)
						)
						(arc
							(start 0.2032 0.2286)
							(mid 0.239121 0.213721)
							(end 0.254 0.1778)
						)
						(arc
							(start 0.254 -0.1778)
							(mid 0.239121 -0.213721)
							(end 0.2032 -0.2286)
						)
						(arc
							(start -0.2032 -0.2286)
							(mid -0.239121 -0.213721)
							(end -0.254 -0.1778)
						)
					)
					(width 0)
					(fill yes)
				)
			)
		)
		(pad "2" smd custom
			(at 0 0.4572)
			(size 0.1143 0.1143)
			(layers "B.Cu" "B.Mask" "B.Paste")
			(net "GND")
			(options
				(clearance outline)
				(anchor circle)
			)
			(primitives
				(gr_poly
					(pts
						(arc
							(start -0.254 0.1778)
							(mid -0.239121 0.213721)
							(end -0.2032 0.2286)
						)
						(arc
							(start 0.2032 0.2286)
							(mid 0.239121 0.213721)
							(end 0.254 0.1778)
						)
						(arc
							(start 0.254 -0.1778)
							(mid 0.239121 -0.213721)
							(end 0.2032 -0.2286)
						)
						(arc
							(start -0.2032 -0.2286)
							(mid -0.239121 -0.213721)
							(end -0.254 -0.1778)
						)
					)
					(width 0)
					(fill yes)
				)
			)
		)
	)
	(footprint ""
		(layer "B.Cu")
		(at 71.501 -35.179 90)
		(property "Reference" "C191"
			(at 0 0 90)
			(layer "B.SilkS")
			(hide yes)
			(effects
				(font
					(size 1.27 1.27)
				)
				(justify mirror)
			)
		)
		(property "Value" "SC2D2U10V2KX-GP"
			(at -1.1811 -2.7051 90)
			(unlocked yes)
			(layer "B.Fab")
			(hide yes)
			(effects
				(font
					(size 1.016 1.016)
					(thickness 0.1524)
				)
				(justify mirror)
			)
		)
		(property "Device Type" "C402H22"
			(at -1.1811 -4.2291 90)
			(unlocked yes)
			(layer "B.Fab")
			(hide yes)
			(effects
				(font
					(size 1.016 1.016)
					(thickness 0.1524)
				)
				(justify mirror)
			)
		)
		(duplicate_pad_numbers_are_jumpers no)
		(fp_rect
			(start 0.381 0.7366)
			(end -0.381 -0.7366)
			(stroke
				(width 0)
				(type default)
			)
			(fill no)
			(layer "B.CrtYd")
		)
		(fp_rect
			(start 0.381 0.7366)
			(end -0.381 -0.7366)
			(stroke
				(width 0)
				(type default)
			)
			(fill no)
			(layer "B.Fab")
		)
		(pad "1" smd custom
			(at 0 -0.4572 270)
			(size 0.1143 0.1143)
			(layers "B.Cu" "B.Mask" "B.Paste")
			(net "SRTCRST_BUF_IN#")
			(options
				(clearance outline)
				(anchor circle)
			)
			(primitives
				(gr_poly
					(pts
						(arc
							(start -0.254 0.1778)
							(mid -0.239121 0.213721)
							(end -0.2032 0.2286)
						)
						(arc
							(start 0.2032 0.2286)
							(mid 0.239121 0.213721)
							(end 0.254 0.1778)
						)
						(arc
							(start 0.254 -0.1778)
							(mid 0.239121 -0.213721)
							(end 0.2032 -0.2286)
						)
						(arc
							(start -0.2032 -0.2286)
							(mid -0.239121 -0.213721)
							(end -0.254 -0.1778)
						)
					)
					(width 0)
					(fill yes)
				)
			)
		)
		(pad "2" smd custom
			(at 0 0.4572 270)
			(size 0.1143 0.1143)
			(layers "B.Cu" "B.Mask" "B.Paste")
			(net "GND")
			(options
				(clearance outline)
				(anchor circle)
			)
			(primitives
				(gr_poly
					(pts
						(arc
							(start -0.254 0.1778)
							(mid -0.239121 0.213721)
							(end -0.2032 0.2286)
						)
						(arc
							(start 0.2032 0.2286)
							(mid 0.239121 0.213721)
							(end 0.254 0.1778)
						)
						(arc
							(start 0.254 -0.1778)
							(mid 0.239121 -0.213721)
							(end 0.2032 -0.2286)
						)
						(arc
							(start -0.2032 -0.2286)
							(mid -0.239121 -0.213721)
							(end -0.254 -0.1778)
						)
					)
					(width 0)
					(fill yes)
				)
			)
		)
	)
	(footprint ""
		(layer "B.Cu")
		(at 74.168 -42.672 90)
		(property "Reference" "R308"
			(at 0 0 90)
			(layer "B.SilkS")
			(hide yes)
			(effects
				(font
					(size 1.27 1.27)
				)
				(justify mirror)
			)
		)
		(property "Value" "4K7R2F-GP"
			(at -0.064008 -3.993896 90)
			(unlocked yes)
			(layer "B.Fab")
			(hide yes)
			(effects
				(font
					(size 1.016 1.016)
					(thickness 0.1524)
				)
				(justify mirror)
			)
		)
		(property "Device Type" "R402H16"
			(at -0.064008 -5.517896 90)
			(unlocked yes)
			(layer "B.Fab")
			(hide yes)
			(effects
				(font
					(size 1.016 1.016)
					(thickness 0.1524)
				)
				(justify mirror)
			)
		)
		(duplicate_pad_numbers_are_jumpers no)
		(fp_rect
			(start 0.381 0.8382)
			(end -0.381 -0.8382)
			(stroke
				(width 0)
				(type default)
			)
			(fill no)
			(layer "B.CrtYd")
		)
		(fp_rect
			(start 0.381 0.8382)
			(end -0.381 -0.8382)
			(stroke
				(width 0)
				(type default)
			)
			(fill no)
			(layer "B.Fab")
		)
		(pad "1" smd custom
			(at 0 -0.4318 270)
			(size 0.127 0.127)
			(layers "B.Cu" "B.Mask" "B.Paste")
			(net "P3V3")
			(options
				(clearance outline)
				(anchor circle)
			)
			(primitives
				(gr_poly
					(pts
						(arc
							(start -0.2032 0.2794)
							(mid -0.239121 0.264521)
							(end -0.254 0.2286)
						)
						(arc
							(start -0.254 -0.2286)
							(mid -0.239121 -0.264521)
							(end -0.2032 -0.2794)
						)
						(arc
							(start 0.2032 -0.2794)
							(mid 0.239121 -0.264521)
							(end 0.254 -0.2286)
						)
						(arc
							(start 0.254 0.2286)
							(mid 0.239121 0.264521)
							(end 0.2032 0.2794)
						)
					)
					(width 0)
					(fill yes)
				)
			)
		)
		(pad "2" smd custom
			(at 0 0.4318 270)
			(size 0.127 0.127)
			(layers "B.Cu" "B.Mask" "B.Paste")
			(net "CPU_DIAG_LED")
			(options
				(clearance outline)
				(anchor circle)
			)
			(primitives
				(gr_poly
					(pts
						(arc
							(start -0.2032 0.2794)
							(mid -0.239121 0.264521)
							(end -0.254 0.2286)
						)
						(arc
							(start -0.254 -0.2286)
							(mid -0.239121 -0.264521)
							(end -0.2032 -0.2794)
						)
						(arc
							(start 0.2032 -0.2794)
							(mid 0.239121 -0.264521)
							(end 0.254 -0.2286)
						)
						(arc
							(start 0.254 0.2286)
							(mid 0.239121 0.264521)
							(end 0.2032 0.2794)
						)
					)
					(width 0)
					(fill yes)
				)
			)
		)
	)
	(footprint ""
		(layer "B.Cu")
		(at 116.078 -64.008 90)
		(property "Reference" "R402"
			(at 0 0 90)
			(layer "B.SilkS")
			(hide yes)
			(effects
				(font
					(size 1.27 1.27)
				)
				(justify mirror)
			)
		)
		(property "Value" "1KR2F-3-GP"
			(at -1.7907 -1.1176 90)
			(unlocked yes)
			(layer "B.Fab")
			(hide yes)
			(effects
				(font
					(size 1.016 1.016)
					(thickness 0.1524)
				)
				(justify mirror)
			)
		)
		(property "Device Type" "R402H16"
			(at -1.7907 -2.6416 90)
			(unlocked yes)
			(layer "B.Fab")
			(hide yes)
			(effects
				(font
					(size 1.016 1.016)
					(thickness 0.1524)
				)
				(justify mirror)
			)
		)
		(duplicate_pad_numbers_are_jumpers no)
		(fp_rect
			(start 0.381 0.8382)
			(end -0.381 -0.8382)
			(stroke
				(width 0)
				(type default)
			)
			(fill no)
			(layer "B.CrtYd")
		)
		(fp_rect
			(start 0.381 0.8382)
			(end -0.381 -0.8382)
			(stroke
				(width 0)
				(type default)
			)
			(fill no)
			(layer "B.Fab")
		)
		(pad "1" smd custom
			(at 0 -0.4318 270)
			(size 0.127 0.127)
			(layers "B.Cu" "B.Mask" "B.Paste")
			(net "P3V0_BAT")
			(options
				(clearance outline)
				(anchor circle)
			)
			(primitives
				(gr_poly
					(pts
						(arc
							(start -0.2032 0.2794)
							(mid -0.239121 0.264521)
							(end -0.254 0.2286)
						)
						(arc
							(start -0.254 -0.2286)
							(mid -0.239121 -0.264521)
							(end -0.2032 -0.2794)
						)
						(arc
							(start 0.2032 -0.2794)
							(mid 0.239121 -0.264521)
							(end 0.254 -0.2286)
						)
						(arc
							(start 0.254 0.2286)
							(mid 0.239121 0.264521)
							(end 0.2032 0.2794)
						)
					)
					(width 0)
					(fill yes)
				)
			)
		)
		(pad "2" smd custom
			(at 0 0.4318 270)
			(size 0.127 0.127)
			(layers "B.Cu" "B.Mask" "B.Paste")
			(net "P3V0_BAT_R")
			(options
				(clearance outline)
				(anchor circle)
			)
			(primitives
				(gr_poly
					(pts
						(arc
							(start -0.2032 0.2794)
							(mid -0.239121 0.264521)
							(end -0.254 0.2286)
						)
						(arc
							(start -0.254 -0.2286)
							(mid -0.239121 -0.264521)
							(end -0.2032 -0.2794)
						)
						(arc
							(start 0.2032 -0.2794)
							(mid 0.239121 -0.264521)
							(end 0.254 -0.2286)
						)
						(arc
							(start 0.254 0.2286)
							(mid 0.239121 0.264521)
							(end 0.2032 0.2794)
						)
					)
					(width 0)
					(fill yes)
				)
			)
		)
	)
	(footprint ""
		(layer "B.Cu")
		(at 92.583 -33.02)
		(property "Reference" "C220"
			(at 0 0 0)
			(layer "B.SilkS")
			(hide yes)
			(effects
				(font
					(size 1.27 1.27)
				)
				(justify mirror)
			)
		)
		(property "Value" "SC1U10V2KX-1GP"
			(at -1.1811 -2.7051 0)
			(unlocked yes)
			(layer "B.Fab")
			(hide yes)
			(effects
				(font
					(size 1.016 1.016)
					(thickness 0.1524)
				)
				(justify mirror)
			)
		)
		(property "Device Type" "C402H22"
			(at -1.1811 -4.2291 0)
			(unlocked yes)
			(layer "B.Fab")
			(hide yes)
			(effects
				(font
					(size 1.016 1.016)
					(thickness 0.1524)
				)
				(justify mirror)
			)
		)
		(duplicate_pad_numbers_are_jumpers no)
		(fp_rect
			(start 0.381 0.7366)
			(end -0.381 -0.7366)
			(stroke
				(width 0)
				(type default)
			)
			(fill no)
			(layer "B.CrtYd")
		)
		(fp_rect
			(start 0.381 0.7366)
			(end -0.381 -0.7366)
			(stroke
				(width 0)
				(type default)
			)
			(fill no)
			(layer "B.Fab")
		)
		(pad "1" smd custom
			(at 0 -0.4572 180)
			(size 0.1143 0.1143)
			(layers "B.Cu" "B.Mask" "B.Paste")
			(net "P1V0_STBY")
			(options
				(clearance outline)
				(anchor circle)
			)
			(primitives
				(gr_poly
					(pts
						(arc
							(start -0.254 0.1778)
							(mid -0.239121 0.213721)
							(end -0.2032 0.2286)
						)
						(arc
							(start 0.2032 0.2286)
							(mid 0.239121 0.213721)
							(end 0.254 0.1778)
						)
						(arc
							(start 0.254 -0.1778)
							(mid 0.239121 -0.213721)
							(end 0.2032 -0.2286)
						)
						(arc
							(start -0.2032 -0.2286)
							(mid -0.239121 -0.213721)
							(end -0.254 -0.1778)
						)
					)
					(width 0)
					(fill yes)
				)
			)
		)
		(pad "2" smd custom
			(at 0 0.4572 180)
			(size 0.1143 0.1143)
			(layers "B.Cu" "B.Mask" "B.Paste")
			(net "GND")
			(options
				(clearance outline)
				(anchor circle)
			)
			(primitives
				(gr_poly
					(pts
						(arc
							(start -0.254 0.1778)
							(mid -0.239121 0.213721)
							(end -0.2032 0.2286)
						)
						(arc
							(start 0.2032 0.2286)
							(mid 0.239121 0.213721)
							(end 0.254 0.1778)
						)
						(arc
							(start 0.254 -0.1778)
							(mid 0.239121 -0.213721)
							(end 0.2032 -0.2286)
						)
						(arc
							(start -0.2032 -0.2286)
							(mid -0.239121 -0.213721)
							(end -0.254 -0.1778)
						)
					)
					(width 0)
					(fill yes)
				)
			)
		)
	)
	(footprint ""
		(layer "B.Cu")
		(at 102.489 -27.321002)
		(property "Reference" "R373"
			(at 0 0 0)
			(layer "B.SilkS")
			(hide yes)
			(effects
				(font
					(size 1.27 1.27)
				)
				(justify mirror)
			)
		)
		(property "Value" "100R2F-L1-GP-U"
			(at -0.064008 -3.993896 0)
			(unlocked yes)
			(layer "B.Fab")
			(hide yes)
			(effects
				(font
					(size 1.016 1.016)
					(thickness 0.1524)
				)
				(justify mirror)
			)
		)
		(property "Device Type" "R402H14"
			(at -0.064008 -5.517896 0)
			(unlocked yes)
			(layer "B.Fab")
			(hide yes)
			(effects
				(font
					(size 1.016 1.016)
					(thickness 0.1524)
				)
				(justify mirror)
			)
		)
		(duplicate_pad_numbers_are_jumpers no)
		(fp_rect
			(start 0.381 0.8382)
			(end -0.381 -0.8382)
			(stroke
				(width 0)
				(type default)
			)
			(fill no)
			(layer "B.CrtYd")
		)
		(fp_rect
			(start 0.381 0.8382)
			(end -0.381 -0.8382)
			(stroke
				(width 0)
				(type default)
			)
			(fill no)
			(layer "B.Fab")
		)
		(pad "1" smd custom
			(at 0 -0.4318 180)
			(size 0.127 0.127)
			(layers "B.Cu" "B.Mask" "B.Paste")
			(net "PV_VDDR")
			(options
				(clearance outline)
				(anchor circle)
			)
			(primitives
				(gr_poly
					(pts
						(arc
							(start -0.2032 0.2794)
							(mid -0.239121 0.264521)
							(end -0.254 0.2286)
						)
						(arc
							(start -0.254 -0.2286)
							(mid -0.239121 -0.264521)
							(end -0.2032 -0.2794)
						)
						(arc
							(start 0.2032 -0.2794)
							(mid 0.239121 -0.264521)
							(end 0.254 -0.2286)
						)
						(arc
							(start 0.254 0.2286)
							(mid 0.239121 0.264521)
							(end 0.2032 0.2794)
						)
					)
					(width 0)
					(fill yes)
				)
			)
		)
		(pad "2" smd custom
			(at 0 0.4318 180)
			(size 0.127 0.127)
			(layers "B.Cu" "B.Mask" "B.Paste")
			(net "M_B_VREF")
			(options
				(clearance outline)
				(anchor circle)
			)
			(primitives
				(gr_poly
					(pts
						(arc
							(start -0.2032 0.2794)
							(mid -0.239121 0.264521)
							(end -0.254 0.2286)
						)
						(arc
							(start -0.254 -0.2286)
							(mid -0.239121 -0.264521)
							(end -0.2032 -0.2794)
						)
						(arc
							(start 0.2032 -0.2794)
							(mid 0.239121 -0.264521)
							(end 0.254 -0.2286)
						)
						(arc
							(start 0.254 0.2286)
							(mid 0.239121 0.264521)
							(end 0.2032 0.2794)
						)
					)
					(width 0)
					(fill yes)
				)
			)
		)
	)
	(footprint ""
		(layer "B.Cu")
		(at 86.106 -21.463 90)
		(property "Reference" "PR223"
			(at 0 0 90)
			(layer "B.SilkS")
			(hide yes)
			(effects
				(font
					(size 1.27 1.27)
				)
				(justify mirror)
			)
		)
		(property "Value" "4K75R2F-1-GP"
			(at -0.064008 -3.993896 90)
			(unlocked yes)
			(layer "B.Fab")
			(hide yes)
			(effects
				(font
					(size 1.016 1.016)
					(thickness 0.1524)
				)
				(justify mirror)
			)
		)
		(property "Device Type" "R402H16"
			(at -0.064008 -5.517896 90)
			(unlocked yes)
			(layer "B.Fab")
			(hide yes)
			(effects
				(font
					(size 1.016 1.016)
					(thickness 0.1524)
				)
				(justify mirror)
			)
		)
		(duplicate_pad_numbers_are_jumpers no)
		(fp_rect
			(start 0.381 0.8382)
			(end -0.381 -0.8382)
			(stroke
				(width 0)
				(type default)
			)
			(fill no)
			(layer "B.CrtYd")
		)
		(fp_rect
			(start 0.381 0.8382)
			(end -0.381 -0.8382)
			(stroke
				(width 0)
				(type default)
			)
			(fill no)
			(layer "B.Fab")
		)
		(pad "1" smd custom
			(at 0 -0.4318 270)
			(size 0.127 0.127)
			(layers "B.Cu" "B.Mask" "B.Paste")
			(net "TPS74801_1V35_FB")
			(options
				(clearance outline)
				(anchor circle)
			)
			(primitives
				(gr_poly
					(pts
						(arc
							(start -0.2032 0.2794)
							(mid -0.239121 0.264521)
							(end -0.254 0.2286)
						)
						(arc
							(start -0.254 -0.2286)
							(mid -0.239121 -0.264521)
							(end -0.2032 -0.2794)
						)
						(arc
							(start 0.2032 -0.2794)
							(mid 0.239121 -0.264521)
							(end 0.254 -0.2286)
						)
						(arc
							(start 0.254 0.2286)
							(mid 0.239121 0.264521)
							(end 0.2032 0.2794)
						)
					)
					(width 0)
					(fill yes)
				)
			)
		)
		(pad "2" smd custom
			(at 0 0.4318 270)
			(size 0.127 0.127)
			(layers "B.Cu" "B.Mask" "B.Paste")
			(net "GND")
			(options
				(clearance outline)
				(anchor circle)
			)
			(primitives
				(gr_poly
					(pts
						(arc
							(start -0.2032 0.2794)
							(mid -0.239121 0.264521)
							(end -0.254 0.2286)
						)
						(arc
							(start -0.254 -0.2286)
							(mid -0.239121 -0.264521)
							(end -0.2032 -0.2794)
						)
						(arc
							(start 0.2032 -0.2794)
							(mid 0.239121 -0.264521)
							(end 0.254 -0.2286)
						)
						(arc
							(start 0.254 0.2286)
							(mid 0.239121 0.264521)
							(end 0.2032 0.2794)
						)
					)
					(width 0)
					(fill yes)
				)
			)
		)
	)
	(footprint ""
		(layer "B.Cu")
		(at 187.071 -11.812778 -90)
		(property "Reference" "R195"
			(at 0 0 90)
			(layer "B.SilkS")
			(hide yes)
			(effects
				(font
					(size 1.27 1.27)
				)
				(justify mirror)
			)
		)
		(property "Value" "4K7R2F-GP"
			(at -0.064008 -3.993896 270)
			(unlocked yes)
			(layer "B.Fab")
			(hide yes)
			(effects
				(font
					(size 1.016 1.016)
					(thickness 0.1524)
				)
				(justify mirror)
			)
		)
		(property "Device Type" "R402H16"
			(at -0.064008 -5.517896 270)
			(unlocked yes)
			(layer "B.Fab")
			(hide yes)
			(effects
				(font
					(size 1.016 1.016)
					(thickness 0.1524)
				)
				(justify mirror)
			)
		)
		(duplicate_pad_numbers_are_jumpers no)
		(fp_rect
			(start 0.381 0.8382)
			(end -0.381 -0.8382)
			(stroke
				(width 0)
				(type default)
			)
			(fill no)
			(layer "B.CrtYd")
		)
		(fp_rect
			(start 0.381 0.8382)
			(end -0.381 -0.8382)
			(stroke
				(width 0)
				(type default)
			)
			(fill no)
			(layer "B.Fab")
		)
		(pad "1" smd custom
			(at 0 -0.4318 90)
			(size 0.127 0.127)
			(layers "B.Cu" "B.Mask" "B.Paste")
			(net "CHB_0_SA0")
			(options
				(clearance outline)
				(anchor circle)
			)
			(primitives
				(gr_poly
					(pts
						(arc
							(start -0.2032 0.2794)
							(mid -0.239121 0.264521)
							(end -0.254 0.2286)
						)
						(arc
							(start -0.254 -0.2286)
							(mid -0.239121 -0.264521)
							(end -0.2032 -0.2794)
						)
						(arc
							(start 0.2032 -0.2794)
							(mid 0.239121 -0.264521)
							(end 0.254 -0.2286)
						)
						(arc
							(start 0.254 0.2286)
							(mid 0.239121 0.264521)
							(end 0.2032 0.2794)
						)
					)
					(width 0)
					(fill yes)
				)
			)
		)
		(pad "2" smd custom
			(at 0 0.4318 90)
			(size 0.127 0.127)
			(layers "B.Cu" "B.Mask" "B.Paste")
			(net "GND")
			(options
				(clearance outline)
				(anchor circle)
			)
			(primitives
				(gr_poly
					(pts
						(arc
							(start -0.2032 0.2794)
							(mid -0.239121 0.264521)
							(end -0.254 0.2286)
						)
						(arc
							(start -0.254 -0.2286)
							(mid -0.239121 -0.264521)
							(end -0.2032 -0.2794)
						)
						(arc
							(start 0.2032 -0.2794)
							(mid 0.239121 -0.264521)
							(end 0.254 -0.2286)
						)
						(arc
							(start 0.254 0.2286)
							(mid 0.239121 0.264521)
							(end 0.2032 0.2794)
						)
					)
					(width 0)
					(fill yes)
				)
			)
		)
	)
	(footprint ""
		(layer "B.Cu")
		(at 200.787 -27.559 -90)
		(property "Reference" "PC92"
			(at 0 0 90)
			(layer "B.SilkS")
			(hide yes)
			(effects
				(font
					(size 1.27 1.27)
				)
				(justify mirror)
			)
		)
		(property "Value" "SC22U25V5MX-GP"
			(at 0 -4.9022 270)
			(unlocked yes)
			(layer "B.Fab")
			(hide yes)
			(effects
				(font
					(size 1.016 1.016)
					(thickness 0.1524)
				)
				(justify mirror)
			)
		)
		(property "Device Type" "C805H58"
			(at 0 -6.8072 270)
			(unlocked yes)
			(layer "B.Fab")
			(hide yes)
			(effects
				(font
					(size 1.016 1.016)
					(thickness 0.1524)
				)
				(justify mirror)
			)
		)
		(duplicate_pad_numbers_are_jumpers no)
		(fp_line
			(start -0.6096 0)
			(end 0.6096 0)
			(stroke
				(width 0.3048)
				(type default)
			)
			(layer "B.SilkS")
		)
		(fp_poly
			(pts
				(xy 0.9017 1.4351) (xy -0.9017 1.4351) (xy -0.9017 -1.4351) (xy 0.9017 -1.4351)
			)
			(stroke
				(width 0)
				(type default)
			)
			(fill no)
			(layer "B.CrtYd")
		)
		(fp_poly
			(pts
				(xy -0.9017 1.4351) (xy -0.9017 -1.4351) (xy 0.9017 -1.4351) (xy 0.9017 1.4351)
			)
			(stroke
				(width 0)
				(type default)
			)
			(fill no)
			(layer "B.Fab")
		)
		(pad "1" smd rect
			(at 0 -0.8382 90)
			(size 1.5494 0.9398)
			(layers "B.Cu" "B.Mask" "B.Paste")
			(net "PVDDR_VIN")
		)
		(pad "2" smd rect
			(at 0 0.8382 90)
			(size 1.5494 0.9398)
			(layers "B.Cu" "B.Mask" "B.Paste")
			(net "GND")
		)
	)
	(footprint ""
		(layer "B.Cu")
		(at 92.71 -46.4058 -90)
		(property "Reference" "C150"
			(at 0 0 90)
			(layer "B.SilkS")
			(hide yes)
			(effects
				(font
					(size 1.27 1.27)
				)
				(justify mirror)
			)
		)
		(property "Value" "SC1U10V2KX-1GP"
			(at -1.1811 -2.7051 270)
			(unlocked yes)
			(layer "B.Fab")
			(hide yes)
			(effects
				(font
					(size 1.016 1.016)
					(thickness 0.1524)
				)
				(justify mirror)
			)
		)
		(property "Device Type" "C402H22"
			(at -1.1811 -4.2291 270)
			(unlocked yes)
			(layer "B.Fab")
			(hide yes)
			(effects
				(font
					(size 1.016 1.016)
					(thickness 0.1524)
				)
				(justify mirror)
			)
		)
		(duplicate_pad_numbers_are_jumpers no)
		(fp_rect
			(start 0.381 0.7366)
			(end -0.381 -0.7366)
			(stroke
				(width 0)
				(type default)
			)
			(fill no)
			(layer "B.CrtYd")
		)
		(fp_rect
			(start 0.381 0.7366)
			(end -0.381 -0.7366)
			(stroke
				(width 0)
				(type default)
			)
			(fill no)
			(layer "B.Fab")
		)
		(pad "1" smd custom
			(at 0 -0.4572 90)
			(size 0.1143 0.1143)
			(layers "B.Cu" "B.Mask" "B.Paste")
			(net "P1V0")
			(options
				(clearance outline)
				(anchor circle)
			)
			(primitives
				(gr_poly
					(pts
						(arc
							(start -0.254 0.1778)
							(mid -0.239121 0.213721)
							(end -0.2032 0.2286)
						)
						(arc
							(start 0.2032 0.2286)
							(mid 0.239121 0.213721)
							(end 0.254 0.1778)
						)
						(arc
							(start 0.254 -0.1778)
							(mid 0.239121 -0.213721)
							(end 0.2032 -0.2286)
						)
						(arc
							(start -0.2032 -0.2286)
							(mid -0.239121 -0.213721)
							(end -0.254 -0.1778)
						)
					)
					(width 0)
					(fill yes)
				)
			)
		)
		(pad "2" smd custom
			(at 0 0.4572 90)
			(size 0.1143 0.1143)
			(layers "B.Cu" "B.Mask" "B.Paste")
			(net "GND")
			(options
				(clearance outline)
				(anchor circle)
			)
			(primitives
				(gr_poly
					(pts
						(arc
							(start -0.254 0.1778)
							(mid -0.239121 0.213721)
							(end -0.2032 0.2286)
						)
						(arc
							(start 0.2032 0.2286)
							(mid 0.239121 0.213721)
							(end 0.254 0.1778)
						)
						(arc
							(start 0.254 -0.1778)
							(mid 0.239121 -0.213721)
							(end 0.2032 -0.2286)
						)
						(arc
							(start -0.2032 -0.2286)
							(mid -0.239121 -0.213721)
							(end -0.254 -0.1778)
						)
					)
					(width 0)
					(fill yes)
				)
			)
		)
	)
	(footprint ""
		(layer "B.Cu")
		(at 202.438 -44.704 180)
		(property "Reference" "PC69"
			(at 0 0 0)
			(layer "B.SilkS")
			(hide yes)
			(effects
				(font
					(size 1.27 1.27)
				)
				(justify mirror)
			)
		)
		(property "Value" "SC3300P50V3KX-1GP"
			(at 0.0254 -2.0193 180)
			(unlocked yes)
			(layer "B.Fab")
			(hide yes)
			(effects
				(font
					(size 1.016 1.016)
					(thickness 0.1524)
				)
				(justify mirror)
			)
		)
		(property "Device Type" "C603H36"
			(at 0.0254 -3.5433 180)
			(unlocked yes)
			(layer "B.Fab")
			(hide yes)
			(effects
				(font
					(size 1.016 1.016)
					(thickness 0.1524)
				)
				(justify mirror)
			)
		)
		(duplicate_pad_numbers_are_jumpers no)
		(fp_line
			(start 0.4064 0)
			(end -0.4064 0)
			(stroke
				(width 0.2286)
				(type default)
			)
			(layer "B.SilkS")
		)
		(fp_rect
			(start 0.635 1.1811)
			(end -0.635 -1.1811)
			(stroke
				(width 0)
				(type default)
			)
			(fill no)
			(layer "B.CrtYd")
		)
		(fp_rect
			(start 0.635 1.1811)
			(end -0.635 -1.1811)
			(stroke
				(width 0)
				(type default)
			)
			(fill no)
			(layer "B.Fab")
		)
		(pad "1" smd custom
			(at 0 -0.6604)
			(size 0.19685 0.19685)
			(layers "B.Cu" "B.Mask" "B.Paste")
			(net "VR_PVDDR_A_VSW")
			(options
				(clearance outline)
				(anchor circle)
			)
			(primitives
				(gr_poly
					(pts
						(arc
							(start 0.508 0.2921)
							(mid 0.478242 0.363942)
							(end 0.4064 0.3937)
						)
						(arc
							(start -0.4064 0.3937)
							(mid -0.478242 0.363942)
							(end -0.508 0.2921)
						)
						(arc
							(start -0.508 -0.2921)
							(mid -0.478242 -0.363942)
							(end -0.4064 -0.3937)
						)
						(arc
							(start 0.4064 -0.3937)
							(mid 0.478242 -0.363942)
							(end 0.508 -0.2921)
						)
					)
					(width 0)
					(fill yes)
				)
			)
		)
		(pad "2" smd custom
			(at 0 0.6604)
			(size 0.19685 0.19685)
			(layers "B.Cu" "B.Mask" "B.Paste")
			(net "VR_PVDDR_A_VSW_R")
			(options
				(clearance outline)
				(anchor circle)
			)
			(primitives
				(gr_poly
					(pts
						(arc
							(start 0.508 0.2921)
							(mid 0.478242 0.363942)
							(end 0.4064 0.3937)
						)
						(arc
							(start -0.4064 0.3937)
							(mid -0.478242 0.363942)
							(end -0.508 0.2921)
						)
						(arc
							(start -0.508 -0.2921)
							(mid -0.478242 -0.363942)
							(end -0.4064 -0.3937)
						)
						(arc
							(start 0.4064 -0.3937)
							(mid 0.478242 -0.363942)
							(end 0.508 -0.2921)
						)
					)
					(width 0)
					(fill yes)
				)
			)
		)
	)
	(footprint ""
		(layer "B.Cu")
		(at 70.4596 -45.593 180)
		(property "Reference" "R295"
			(at 0 0 0)
			(layer "B.SilkS")
			(hide yes)
			(effects
				(font
					(size 1.27 1.27)
				)
				(justify mirror)
			)
		)
		(property "Value" "10KR2F-2-GP"
			(at -0.064008 -3.993896 180)
			(unlocked yes)
			(layer "B.Fab")
			(hide yes)
			(effects
				(font
					(size 1.016 1.016)
					(thickness 0.1524)
				)
				(justify mirror)
			)
		)
		(property "Device Type" "R402H16"
			(at -0.064008 -5.517896 180)
			(unlocked yes)
			(layer "B.Fab")
			(hide yes)
			(effects
				(font
					(size 1.016 1.016)
					(thickness 0.1524)
				)
				(justify mirror)
			)
		)
		(duplicate_pad_numbers_are_jumpers no)
		(fp_rect
			(start 0.381 0.8382)
			(end -0.381 -0.8382)
			(stroke
				(width 0)
				(type default)
			)
			(fill no)
			(layer "B.CrtYd")
		)
		(fp_rect
			(start 0.381 0.8382)
			(end -0.381 -0.8382)
			(stroke
				(width 0)
				(type default)
			)
			(fill no)
			(layer "B.Fab")
		)
		(pad "1" smd custom
			(at 0 -0.4318)
			(size 0.127 0.127)
			(layers "B.Cu" "B.Mask" "B.Paste")
			(net "P3V3")
			(options
				(clearance outline)
				(anchor circle)
			)
			(primitives
				(gr_poly
					(pts
						(arc
							(start -0.2032 0.2794)
							(mid -0.239121 0.264521)
							(end -0.254 0.2286)
						)
						(arc
							(start -0.254 -0.2286)
							(mid -0.239121 -0.264521)
							(end -0.2032 -0.2794)
						)
						(arc
							(start 0.2032 -0.2794)
							(mid 0.239121 -0.264521)
							(end 0.254 -0.2286)
						)
						(arc
							(start 0.254 0.2286)
							(mid 0.239121 0.264521)
							(end 0.2032 0.2794)
						)
					)
					(width 0)
					(fill yes)
				)
			)
		)
		(pad "2" smd custom
			(at 0 0.4318)
			(size 0.127 0.127)
			(layers "B.Cu" "B.Mask" "B.Paste")
			(net "IRQ_NMI_R")
			(options
				(clearance outline)
				(anchor circle)
			)
			(primitives
				(gr_poly
					(pts
						(arc
							(start -0.2032 0.2794)
							(mid -0.239121 0.264521)
							(end -0.254 0.2286)
						)
						(arc
							(start -0.254 -0.2286)
							(mid -0.239121 -0.264521)
							(end -0.2032 -0.2794)
						)
						(arc
							(start 0.2032 -0.2794)
							(mid 0.239121 -0.264521)
							(end 0.254 -0.2286)
						)
						(arc
							(start 0.254 0.2286)
							(mid 0.239121 0.264521)
							(end 0.2032 0.2794)
						)
					)
					(width 0)
					(fill yes)
				)
			)
		)
	)
	(footprint ""
		(layer "B.Cu")
		(at 17.145 -48.133)
		(property "Reference" "C247"
			(at 0 0 0)
			(layer "B.SilkS")
			(hide yes)
			(effects
				(font
					(size 1.27 1.27)
				)
				(justify mirror)
			)
		)
		(property "Value" "SC1U6D3V2KX-GP"
			(at -1.8923 -1.2065 0)
			(unlocked yes)
			(layer "B.Fab")
			(hide yes)
			(effects
				(font
					(size 1.016 1.016)
					(thickness 0.1524)
				)
				(justify mirror)
			)
		)
		(property "Device Type" "C402H22"
			(at -1.8923 -2.7305 0)
			(unlocked yes)
			(layer "B.Fab")
			(hide yes)
			(effects
				(font
					(size 1.016 1.016)
					(thickness 0.1524)
				)
				(justify mirror)
			)
		)
		(duplicate_pad_numbers_are_jumpers no)
		(fp_rect
			(start 0.381 0.7366)
			(end -0.381 -0.7366)
			(stroke
				(width 0)
				(type default)
			)
			(fill no)
			(layer "B.CrtYd")
		)
		(fp_rect
			(start 0.381 0.7366)
			(end -0.381 -0.7366)
			(stroke
				(width 0)
				(type default)
			)
			(fill no)
			(layer "B.Fab")
		)
		(pad "1" smd custom
			(at 0 -0.4572 180)
			(size 0.1143 0.1143)
			(layers "B.Cu" "B.Mask" "B.Paste")
			(net "P3V3")
			(options
				(clearance outline)
				(anchor circle)
			)
			(primitives
				(gr_poly
					(pts
						(arc
							(start -0.254 0.1778)
							(mid -0.239121 0.213721)
							(end -0.2032 0.2286)
						)
						(arc
							(start 0.2032 0.2286)
							(mid 0.239121 0.213721)
							(end 0.254 0.1778)
						)
						(arc
							(start 0.254 -0.1778)
							(mid 0.239121 -0.213721)
							(end 0.2032 -0.2286)
						)
						(arc
							(start -0.2032 -0.2286)
							(mid -0.239121 -0.213721)
							(end -0.254 -0.1778)
						)
					)
					(width 0)
					(fill yes)
				)
			)
		)
		(pad "2" smd custom
			(at 0 0.4572 180)
			(size 0.1143 0.1143)
			(layers "B.Cu" "B.Mask" "B.Paste")
			(net "GND")
			(options
				(clearance outline)
				(anchor circle)
			)
			(primitives
				(gr_poly
					(pts
						(arc
							(start -0.254 0.1778)
							(mid -0.239121 0.213721)
							(end -0.2032 0.2286)
						)
						(arc
							(start 0.2032 0.2286)
							(mid 0.239121 0.213721)
							(end 0.254 0.1778)
						)
						(arc
							(start 0.254 -0.1778)
							(mid 0.239121 -0.213721)
							(end 0.2032 -0.2286)
						)
						(arc
							(start -0.2032 -0.2286)
							(mid -0.239121 -0.213721)
							(end -0.254 -0.1778)
						)
					)
					(width 0)
					(fill yes)
				)
			)
		)
	)
	(footprint ""
		(layer "B.Cu")
		(at 37.719 -23.495 -90)
		(property "Reference" "R349"
			(at 0 0 90)
			(layer "B.SilkS")
			(hide yes)
			(effects
				(font
					(size 1.27 1.27)
				)
				(justify mirror)
			)
		)
		(property "Value" "33R2F-3-GP"
			(at -0.064008 -3.993896 270)
			(unlocked yes)
			(layer "B.Fab")
			(hide yes)
			(effects
				(font
					(size 1.016 1.016)
					(thickness 0.1524)
				)
				(justify mirror)
			)
		)
		(property "Device Type" "R402H16"
			(at -0.064008 -5.517896 270)
			(unlocked yes)
			(layer "B.Fab")
			(hide yes)
			(effects
				(font
					(size 1.016 1.016)
					(thickness 0.1524)
				)
				(justify mirror)
			)
		)
		(duplicate_pad_numbers_are_jumpers no)
		(fp_rect
			(start 0.381 0.8382)
			(end -0.381 -0.8382)
			(stroke
				(width 0)
				(type default)
			)
			(fill no)
			(layer "B.CrtYd")
		)
		(fp_rect
			(start 0.381 0.8382)
			(end -0.381 -0.8382)
			(stroke
				(width 0)
				(type default)
			)
			(fill no)
			(layer "B.Fab")
		)
		(pad "1" smd custom
			(at 0 -0.4318 90)
			(size 0.127 0.127)
			(layers "B.Cu" "B.Mask" "B.Paste")
			(net "CLK_100M_CLKBUFF_NGFF_R_DP")
			(options
				(clearance outline)
				(anchor circle)
			)
			(primitives
				(gr_poly
					(pts
						(arc
							(start -0.2032 0.2794)
							(mid -0.239121 0.264521)
							(end -0.254 0.2286)
						)
						(arc
							(start -0.254 -0.2286)
							(mid -0.239121 -0.264521)
							(end -0.2032 -0.2794)
						)
						(arc
							(start 0.2032 -0.2794)
							(mid 0.239121 -0.264521)
							(end 0.254 -0.2286)
						)
						(arc
							(start 0.254 0.2286)
							(mid 0.239121 0.264521)
							(end 0.2032 0.2794)
						)
					)
					(width 0)
					(fill yes)
				)
			)
		)
		(pad "2" smd custom
			(at 0 0.4318 90)
			(size 0.127 0.127)
			(layers "B.Cu" "B.Mask" "B.Paste")
			(net "CLK_100M_CLKBUFF_NGFF_DP")
			(options
				(clearance outline)
				(anchor circle)
			)
			(primitives
				(gr_poly
					(pts
						(arc
							(start -0.2032 0.2794)
							(mid -0.239121 0.264521)
							(end -0.254 0.2286)
						)
						(arc
							(start -0.254 -0.2286)
							(mid -0.239121 -0.264521)
							(end -0.2032 -0.2794)
						)
						(arc
							(start 0.2032 -0.2794)
							(mid 0.239121 -0.264521)
							(end 0.254 -0.2286)
						)
						(arc
							(start 0.254 0.2286)
							(mid 0.239121 0.264521)
							(end 0.2032 0.2794)
						)
					)
					(width 0)
					(fill yes)
				)
			)
		)
	)
	(footprint ""
		(layer "B.Cu")
		(at 107.442 -52.721002 180)
		(property "Reference" "C127"
			(at 0 0 0)
			(layer "B.SilkS")
			(hide yes)
			(effects
				(font
					(size 1.27 1.27)
				)
				(justify mirror)
			)
		)
		(property "Value" "SCD1U16V2KX-3GP"
			(at -1.1811 -2.7051 180)
			(unlocked yes)
			(layer "B.Fab")
			(hide yes)
			(effects
				(font
					(size 1.016 1.016)
					(thickness 0.1524)
				)
				(justify mirror)
			)
		)
		(property "Device Type" "C402H22"
			(at -1.1811 -4.2291 180)
			(unlocked yes)
			(layer "B.Fab")
			(hide yes)
			(effects
				(font
					(size 1.016 1.016)
					(thickness 0.1524)
				)
				(justify mirror)
			)
		)
		(duplicate_pad_numbers_are_jumpers no)
		(fp_rect
			(start 0.381 0.7366)
			(end -0.381 -0.7366)
			(stroke
				(width 0)
				(type default)
			)
			(fill no)
			(layer "B.CrtYd")
		)
		(fp_rect
			(start 0.381 0.7366)
			(end -0.381 -0.7366)
			(stroke
				(width 0)
				(type default)
			)
			(fill no)
			(layer "B.Fab")
		)
		(pad "1" smd custom
			(at 0 -0.4572)
			(size 0.1143 0.1143)
			(layers "B.Cu" "B.Mask" "B.Paste")
			(net "PV_VDDR")
			(options
				(clearance outline)
				(anchor circle)
			)
			(primitives
				(gr_poly
					(pts
						(arc
							(start -0.254 0.1778)
							(mid -0.239121 0.213721)
							(end -0.2032 0.2286)
						)
						(arc
							(start 0.2032 0.2286)
							(mid 0.239121 0.213721)
							(end 0.254 0.1778)
						)
						(arc
							(start 0.254 -0.1778)
							(mid 0.239121 -0.213721)
							(end 0.2032 -0.2286)
						)
						(arc
							(start -0.2032 -0.2286)
							(mid -0.239121 -0.213721)
							(end -0.254 -0.1778)
						)
					)
					(width 0)
					(fill yes)
				)
			)
		)
		(pad "2" smd custom
			(at 0 0.4572)
			(size 0.1143 0.1143)
			(layers "B.Cu" "B.Mask" "B.Paste")
			(net "GND")
			(options
				(clearance outline)
				(anchor circle)
			)
			(primitives
				(gr_poly
					(pts
						(arc
							(start -0.254 0.1778)
							(mid -0.239121 0.213721)
							(end -0.2032 0.2286)
						)
						(arc
							(start 0.2032 0.2286)
							(mid 0.239121 0.213721)
							(end 0.254 0.1778)
						)
						(arc
							(start 0.254 -0.1778)
							(mid 0.239121 -0.213721)
							(end 0.2032 -0.2286)
						)
						(arc
							(start -0.2032 -0.2286)
							(mid -0.239121 -0.213721)
							(end -0.254 -0.1778)
						)
					)
					(width 0)
					(fill yes)
				)
			)
		)
	)
	(footprint ""
		(layer "B.Cu")
		(at 88.392 -46.228)
		(property "Reference" "R296"
			(at 0 0 0)
			(layer "B.SilkS")
			(hide yes)
			(effects
				(font
					(size 1.27 1.27)
				)
				(justify mirror)
			)
		)
		(property "Value" "10KR2F-2-GP"
			(at -0.064008 -3.993896 0)
			(unlocked yes)
			(layer "B.Fab")
			(hide yes)
			(effects
				(font
					(size 1.016 1.016)
					(thickness 0.1524)
				)
				(justify mirror)
			)
		)
		(property "Device Type" "R402H16"
			(at -0.064008 -5.517896 0)
			(unlocked yes)
			(layer "B.Fab")
			(hide yes)
			(effects
				(font
					(size 1.016 1.016)
					(thickness 0.1524)
				)
				(justify mirror)
			)
		)
		(duplicate_pad_numbers_are_jumpers no)
		(fp_rect
			(start 0.381 0.8382)
			(end -0.381 -0.8382)
			(stroke
				(width 0)
				(type default)
			)
			(fill no)
			(layer "B.CrtYd")
		)
		(fp_rect
			(start 0.381 0.8382)
			(end -0.381 -0.8382)
			(stroke
				(width 0)
				(type default)
			)
			(fill no)
			(layer "B.Fab")
		)
		(pad "1" smd custom
			(at 0 -0.4318 180)
			(size 0.127 0.127)
			(layers "B.Cu" "B.Mask" "B.Paste")
			(net "P3V3")
			(options
				(clearance outline)
				(anchor circle)
			)
			(primitives
				(gr_poly
					(pts
						(arc
							(start -0.2032 0.2794)
							(mid -0.239121 0.264521)
							(end -0.254 0.2286)
						)
						(arc
							(start -0.254 -0.2286)
							(mid -0.239121 -0.264521)
							(end -0.2032 -0.2794)
						)
						(arc
							(start 0.2032 -0.2794)
							(mid 0.239121 -0.264521)
							(end 0.254 -0.2286)
						)
						(arc
							(start 0.254 0.2286)
							(mid 0.239121 0.264521)
							(end 0.2032 0.2794)
						)
					)
					(width 0)
					(fill yes)
				)
			)
		)
		(pad "2" smd custom
			(at 0 0.4318 180)
			(size 0.127 0.127)
			(layers "B.Cu" "B.Mask" "B.Paste")
			(net "IRQ_CPU_SERIAL")
			(options
				(clearance outline)
				(anchor circle)
			)
			(primitives
				(gr_poly
					(pts
						(arc
							(start -0.2032 0.2794)
							(mid -0.239121 0.264521)
							(end -0.254 0.2286)
						)
						(arc
							(start -0.254 -0.2286)
							(mid -0.239121 -0.264521)
							(end -0.2032 -0.2794)
						)
						(arc
							(start 0.2032 -0.2794)
							(mid 0.239121 -0.264521)
							(end 0.254 -0.2286)
						)
						(arc
							(start 0.254 0.2286)
							(mid 0.239121 0.264521)
							(end 0.2032 0.2794)
						)
					)
					(width 0)
					(fill yes)
				)
			)
		)
	)
	(footprint ""
		(layer "B.Cu")
		(at 69.596 -46.863 180)
		(property "Reference" "R300"
			(at 0 0 0)
			(layer "B.SilkS")
			(hide yes)
			(effects
				(font
					(size 1.27 1.27)
				)
				(justify mirror)
			)
		)
		(property "Value" "0R2J-2-GP"
			(at -0.064008 -3.993896 180)
			(unlocked yes)
			(layer "B.Fab")
			(hide yes)
			(effects
				(font
					(size 1.016 1.016)
					(thickness 0.1524)
				)
				(justify mirror)
			)
		)
		(property "Device Type" "R402H16"
			(at -0.064008 -5.517896 180)
			(unlocked yes)
			(layer "B.Fab")
			(hide yes)
			(effects
				(font
					(size 1.016 1.016)
					(thickness 0.1524)
				)
				(justify mirror)
			)
		)
		(duplicate_pad_numbers_are_jumpers no)
		(fp_rect
			(start 0.381 0.8382)
			(end -0.381 -0.8382)
			(stroke
				(width 0)
				(type default)
			)
			(fill no)
			(layer "B.CrtYd")
		)
		(fp_rect
			(start 0.381 0.8382)
			(end -0.381 -0.8382)
			(stroke
				(width 0)
				(type default)
			)
			(fill no)
			(layer "B.Fab")
		)
		(pad "1" smd custom
			(at 0 -0.4318)
			(size 0.127 0.127)
			(layers "B.Cu" "B.Mask" "B.Paste")
			(net "IRQ_NMI_R")
			(options
				(clearance outline)
				(anchor circle)
			)
			(primitives
				(gr_poly
					(pts
						(arc
							(start -0.2032 0.2794)
							(mid -0.239121 0.264521)
							(end -0.254 0.2286)
						)
						(arc
							(start -0.254 -0.2286)
							(mid -0.239121 -0.264521)
							(end -0.2032 -0.2794)
						)
						(arc
							(start 0.2032 -0.2794)
							(mid 0.239121 -0.264521)
							(end 0.254 -0.2286)
						)
						(arc
							(start 0.254 0.2286)
							(mid 0.239121 0.264521)
							(end 0.2032 0.2794)
						)
					)
					(width 0)
					(fill yes)
				)
			)
		)
		(pad "2" smd custom
			(at 0 0.4318)
			(size 0.127 0.127)
			(layers "B.Cu" "B.Mask" "B.Paste")
			(net "IRQ_NMI")
			(options
				(clearance outline)
				(anchor circle)
			)
			(primitives
				(gr_poly
					(pts
						(arc
							(start -0.2032 0.2794)
							(mid -0.239121 0.264521)
							(end -0.254 0.2286)
						)
						(arc
							(start -0.254 -0.2286)
							(mid -0.239121 -0.264521)
							(end -0.2032 -0.2794)
						)
						(arc
							(start 0.2032 -0.2794)
							(mid 0.239121 -0.264521)
							(end 0.254 -0.2286)
						)
						(arc
							(start 0.254 0.2286)
							(mid 0.239121 0.264521)
							(end 0.2032 0.2794)
						)
					)
					(width 0)
					(fill yes)
				)
			)
		)
	)
	(footprint ""
		(layer "B.Cu")
		(at 53.467 -18.796 -90)
		(property "Reference" "C303"
			(at 0 0 90)
			(layer "B.SilkS")
			(hide yes)
			(effects
				(font
					(size 1.27 1.27)
				)
				(justify mirror)
			)
		)
		(property "Value" "SCD1U16V2KX-3GP"
			(at -1.8923 -1.2065 270)
			(unlocked yes)
			(layer "B.Fab")
			(hide yes)
			(effects
				(font
					(size 1.016 1.016)
					(thickness 0.1524)
				)
				(justify mirror)
			)
		)
		(property "Device Type" "C402H22"
			(at -1.8923 -2.7305 270)
			(unlocked yes)
			(layer "B.Fab")
			(hide yes)
			(effects
				(font
					(size 1.016 1.016)
					(thickness 0.1524)
				)
				(justify mirror)
			)
		)
		(duplicate_pad_numbers_are_jumpers no)
		(fp_rect
			(start 0.381 0.7366)
			(end -0.381 -0.7366)
			(stroke
				(width 0)
				(type default)
			)
			(fill no)
			(layer "B.CrtYd")
		)
		(fp_rect
			(start 0.381 0.7366)
			(end -0.381 -0.7366)
			(stroke
				(width 0)
				(type default)
			)
			(fill no)
			(layer "B.Fab")
		)
		(pad "1" smd custom
			(at 0 -0.4572 90)
			(size 0.1143 0.1143)
			(layers "B.Cu" "B.Mask" "B.Paste")
			(net "P3V3")
			(options
				(clearance outline)
				(anchor circle)
			)
			(primitives
				(gr_poly
					(pts
						(arc
							(start -0.254 0.1778)
							(mid -0.239121 0.213721)
							(end -0.2032 0.2286)
						)
						(arc
							(start 0.2032 0.2286)
							(mid 0.239121 0.213721)
							(end 0.254 0.1778)
						)
						(arc
							(start 0.254 -0.1778)
							(mid 0.239121 -0.213721)
							(end 0.2032 -0.2286)
						)
						(arc
							(start -0.2032 -0.2286)
							(mid -0.239121 -0.213721)
							(end -0.254 -0.1778)
						)
					)
					(width 0)
					(fill yes)
				)
			)
		)
		(pad "2" smd custom
			(at 0 0.4572 90)
			(size 0.1143 0.1143)
			(layers "B.Cu" "B.Mask" "B.Paste")
			(net "GND")
			(options
				(clearance outline)
				(anchor circle)
			)
			(primitives
				(gr_poly
					(pts
						(arc
							(start -0.254 0.1778)
							(mid -0.239121 0.213721)
							(end -0.2032 0.2286)
						)
						(arc
							(start 0.2032 0.2286)
							(mid 0.239121 0.213721)
							(end 0.254 0.1778)
						)
						(arc
							(start 0.254 -0.1778)
							(mid 0.239121 -0.213721)
							(end 0.2032 -0.2286)
						)
						(arc
							(start -0.2032 -0.2286)
							(mid -0.239121 -0.213721)
							(end -0.254 -0.1778)
						)
					)
					(width 0)
					(fill yes)
				)
			)
		)
	)
	(footprint ""
		(layer "B.Cu")
		(at 23.5712 -56.642 180)
		(property "Reference" "PR66"
			(at 0 0 0)
			(layer "B.SilkS")
			(hide yes)
			(effects
				(font
					(size 1.27 1.27)
				)
				(justify mirror)
			)
		)
		(property "Value" "7K87R2F-GP"
			(at -1.7907 -1.1176 180)
			(unlocked yes)
			(layer "B.Fab")
			(hide yes)
			(effects
				(font
					(size 1.016 1.016)
					(thickness 0.1524)
				)
				(justify mirror)
			)
		)
		(property "Device Type" "R402H16"
			(at -1.7907 -2.6416 180)
			(unlocked yes)
			(layer "B.Fab")
			(hide yes)
			(effects
				(font
					(size 1.016 1.016)
					(thickness 0.1524)
				)
				(justify mirror)
			)
		)
		(duplicate_pad_numbers_are_jumpers no)
		(fp_rect
			(start 0.381 0.8382)
			(end -0.381 -0.8382)
			(stroke
				(width 0)
				(type default)
			)
			(fill no)
			(layer "B.CrtYd")
		)
		(fp_rect
			(start 0.381 0.8382)
			(end -0.381 -0.8382)
			(stroke
				(width 0)
				(type default)
			)
			(fill no)
			(layer "B.Fab")
		)
		(pad "1" smd custom
			(at 0 -0.4318)
			(size 0.127 0.127)
			(layers "B.Cu" "B.Mask" "B.Paste")
			(net "VR_PVCCP_PROG1")
			(options
				(clearance outline)
				(anchor circle)
			)
			(primitives
				(gr_poly
					(pts
						(arc
							(start -0.2032 0.2794)
							(mid -0.239121 0.264521)
							(end -0.254 0.2286)
						)
						(arc
							(start -0.254 -0.2286)
							(mid -0.239121 -0.264521)
							(end -0.2032 -0.2794)
						)
						(arc
							(start 0.2032 -0.2794)
							(mid 0.239121 -0.264521)
							(end 0.254 -0.2286)
						)
						(arc
							(start 0.254 0.2286)
							(mid 0.239121 0.264521)
							(end 0.2032 0.2794)
						)
					)
					(width 0)
					(fill yes)
				)
			)
		)
		(pad "2" smd custom
			(at 0 0.4318)
			(size 0.127 0.127)
			(layers "B.Cu" "B.Mask" "B.Paste")
			(net "GND")
			(options
				(clearance outline)
				(anchor circle)
			)
			(primitives
				(gr_poly
					(pts
						(arc
							(start -0.2032 0.2794)
							(mid -0.239121 0.264521)
							(end -0.254 0.2286)
						)
						(arc
							(start -0.254 -0.2286)
							(mid -0.239121 -0.264521)
							(end -0.2032 -0.2794)
						)
						(arc
							(start 0.2032 -0.2794)
							(mid 0.239121 -0.264521)
							(end 0.254 -0.2286)
						)
						(arc
							(start 0.254 0.2286)
							(mid 0.239121 0.264521)
							(end 0.2032 0.2794)
						)
					)
					(width 0)
					(fill yes)
				)
			)
		)
	)
	(footprint ""
		(layer "B.Cu")
		(at 16.764 -35.179 90)
		(property "Reference" "PR190"
			(at 0 0 90)
			(layer "B.SilkS")
			(hide yes)
			(effects
				(font
					(size 1.27 1.27)
				)
				(justify mirror)
			)
		)
		(property "Value" "0R2J-2-GP"
			(at -1.7907 -1.1176 90)
			(unlocked yes)
			(layer "B.Fab")
			(hide yes)
			(effects
				(font
					(size 1.016 1.016)
					(thickness 0.1524)
				)
				(justify mirror)
			)
		)
		(property "Device Type" "R402H16"
			(at -1.7907 -2.6416 90)
			(unlocked yes)
			(layer "B.Fab")
			(hide yes)
			(effects
				(font
					(size 1.016 1.016)
					(thickness 0.1524)
				)
				(justify mirror)
			)
		)
		(duplicate_pad_numbers_are_jumpers no)
		(fp_rect
			(start 0.381 0.8382)
			(end -0.381 -0.8382)
			(stroke
				(width 0)
				(type default)
			)
			(fill no)
			(layer "B.CrtYd")
		)
		(fp_rect
			(start 0.381 0.8382)
			(end -0.381 -0.8382)
			(stroke
				(width 0)
				(type default)
			)
			(fill no)
			(layer "B.Fab")
		)
		(pad "1" smd custom
			(at 0 -0.4318 270)
			(size 0.127 0.127)
			(layers "B.Cu" "B.Mask" "B.Paste")
			(net "P3V3_STBY_ROVP")
			(options
				(clearance outline)
				(anchor circle)
			)
			(primitives
				(gr_poly
					(pts
						(arc
							(start -0.2032 0.2794)
							(mid -0.239121 0.264521)
							(end -0.254 0.2286)
						)
						(arc
							(start -0.254 -0.2286)
							(mid -0.239121 -0.264521)
							(end -0.2032 -0.2794)
						)
						(arc
							(start 0.2032 -0.2794)
							(mid 0.239121 -0.264521)
							(end 0.254 -0.2286)
						)
						(arc
							(start 0.254 0.2286)
							(mid 0.239121 0.264521)
							(end 0.2032 0.2794)
						)
					)
					(width 0)
					(fill yes)
				)
			)
		)
		(pad "2" smd custom
			(at 0 0.4318 270)
			(size 0.127 0.127)
			(layers "B.Cu" "B.Mask" "B.Paste")
			(net "P3V3_STBY")
			(options
				(clearance outline)
				(anchor circle)
			)
			(primitives
				(gr_poly
					(pts
						(arc
							(start -0.2032 0.2794)
							(mid -0.239121 0.264521)
							(end -0.254 0.2286)
						)
						(arc
							(start -0.254 -0.2286)
							(mid -0.239121 -0.264521)
							(end -0.2032 -0.2794)
						)
						(arc
							(start 0.2032 -0.2794)
							(mid 0.239121 -0.264521)
							(end 0.254 -0.2286)
						)
						(arc
							(start 0.254 0.2286)
							(mid 0.239121 0.264521)
							(end 0.2032 0.2794)
						)
					)
					(width 0)
					(fill yes)
				)
			)
		)
	)
	(footprint ""
		(layer "B.Cu")
		(at 39.878 -15.9004)
		(property "Reference" "R369"
			(at 0 0 0)
			(layer "B.SilkS")
			(hide yes)
			(effects
				(font
					(size 1.27 1.27)
				)
				(justify mirror)
			)
		)
		(property "Value" "33R2F-3-GP"
			(at -0.064008 -3.993896 0)
			(unlocked yes)
			(layer "B.Fab")
			(hide yes)
			(effects
				(font
					(size 1.016 1.016)
					(thickness 0.1524)
				)
				(justify mirror)
			)
		)
		(property "Device Type" "R402H16"
			(at -0.064008 -5.517896 0)
			(unlocked yes)
			(layer "B.Fab")
			(hide yes)
			(effects
				(font
					(size 1.016 1.016)
					(thickness 0.1524)
				)
				(justify mirror)
			)
		)
		(duplicate_pad_numbers_are_jumpers no)
		(fp_rect
			(start 0.381 0.8382)
			(end -0.381 -0.8382)
			(stroke
				(width 0)
				(type default)
			)
			(fill no)
			(layer "B.CrtYd")
		)
		(fp_rect
			(start 0.381 0.8382)
			(end -0.381 -0.8382)
			(stroke
				(width 0)
				(type default)
			)
			(fill no)
			(layer "B.Fab")
		)
		(pad "1" smd custom
			(at 0 -0.4318 180)
			(size 0.127 0.127)
			(layers "B.Cu" "B.Mask" "B.Paste")
			(net "CLK_100M_CLKBUFF_SAS_R_DN")
			(options
				(clearance outline)
				(anchor circle)
			)
			(primitives
				(gr_poly
					(pts
						(arc
							(start -0.2032 0.2794)
							(mid -0.239121 0.264521)
							(end -0.254 0.2286)
						)
						(arc
							(start -0.254 -0.2286)
							(mid -0.239121 -0.264521)
							(end -0.2032 -0.2794)
						)
						(arc
							(start 0.2032 -0.2794)
							(mid 0.239121 -0.264521)
							(end 0.254 -0.2286)
						)
						(arc
							(start 0.254 0.2286)
							(mid 0.239121 0.264521)
							(end 0.2032 0.2794)
						)
					)
					(width 0)
					(fill yes)
				)
			)
		)
		(pad "2" smd custom
			(at 0 0.4318 180)
			(size 0.127 0.127)
			(layers "B.Cu" "B.Mask" "B.Paste")
			(net "CLK_100M_PCIE_SAS_DN")
			(options
				(clearance outline)
				(anchor circle)
			)
			(primitives
				(gr_poly
					(pts
						(arc
							(start -0.2032 0.2794)
							(mid -0.239121 0.264521)
							(end -0.254 0.2286)
						)
						(arc
							(start -0.254 -0.2286)
							(mid -0.239121 -0.264521)
							(end -0.2032 -0.2794)
						)
						(arc
							(start 0.2032 -0.2794)
							(mid 0.239121 -0.264521)
							(end 0.254 -0.2286)
						)
						(arc
							(start 0.254 0.2286)
							(mid 0.239121 0.264521)
							(end 0.2032 0.2794)
						)
					)
					(width 0)
					(fill yes)
				)
			)
		)
	)
	(footprint ""
		(layer "B.Cu")
		(at 34.671 -16.256 90)
		(property "Reference" "R436"
			(at 0 0 90)
			(layer "B.SilkS")
			(hide yes)
			(effects
				(font
					(size 1.27 1.27)
				)
				(justify mirror)
			)
		)
		(property "Value" "0R2J-2-GP"
			(at -1.7907 -1.1176 90)
			(unlocked yes)
			(layer "B.Fab")
			(hide yes)
			(effects
				(font
					(size 1.016 1.016)
					(thickness 0.1524)
				)
				(justify mirror)
			)
		)
		(property "Device Type" "R402H16"
			(at -1.7907 -2.6416 90)
			(unlocked yes)
			(layer "B.Fab")
			(hide yes)
			(effects
				(font
					(size 1.016 1.016)
					(thickness 0.1524)
				)
				(justify mirror)
			)
		)
		(duplicate_pad_numbers_are_jumpers no)
		(fp_rect
			(start 0.381 0.8382)
			(end -0.381 -0.8382)
			(stroke
				(width 0)
				(type default)
			)
			(fill no)
			(layer "B.CrtYd")
		)
		(fp_rect
			(start 0.381 0.8382)
			(end -0.381 -0.8382)
			(stroke
				(width 0)
				(type default)
			)
			(fill no)
			(layer "B.Fab")
		)
		(pad "1" smd custom
			(at 0 -0.4318 270)
			(size 0.127 0.127)
			(layers "B.Cu" "B.Mask" "B.Paste")
			(net "SMBUS_HOST_DATA")
			(options
				(clearance outline)
				(anchor circle)
			)
			(primitives
				(gr_poly
					(pts
						(arc
							(start -0.2032 0.2794)
							(mid -0.239121 0.264521)
							(end -0.254 0.2286)
						)
						(arc
							(start -0.254 -0.2286)
							(mid -0.239121 -0.264521)
							(end -0.2032 -0.2794)
						)
						(arc
							(start 0.2032 -0.2794)
							(mid 0.239121 -0.264521)
							(end 0.254 -0.2286)
						)
						(arc
							(start 0.254 0.2286)
							(mid 0.239121 0.264521)
							(end 0.2032 0.2794)
						)
					)
					(width 0)
					(fill yes)
				)
			)
		)
		(pad "2" smd custom
			(at 0 0.4318 270)
			(size 0.127 0.127)
			(layers "B.Cu" "B.Mask" "B.Paste")
			(net "SMB_CLKBUFF_R_DATA")
			(options
				(clearance outline)
				(anchor circle)
			)
			(primitives
				(gr_poly
					(pts
						(arc
							(start -0.2032 0.2794)
							(mid -0.239121 0.264521)
							(end -0.254 0.2286)
						)
						(arc
							(start -0.254 -0.2286)
							(mid -0.239121 -0.264521)
							(end -0.2032 -0.2794)
						)
						(arc
							(start 0.2032 -0.2794)
							(mid 0.239121 -0.264521)
							(end 0.254 -0.2286)
						)
						(arc
							(start 0.254 0.2286)
							(mid 0.239121 0.264521)
							(end 0.2032 0.2794)
						)
					)
					(width 0)
					(fill yes)
				)
			)
		)
	)
	(footprint ""
		(layer "B.Cu")
		(at 74.041 -27.94 90)
		(property "Reference" "R362"
			(at 0 0 90)
			(layer "B.SilkS")
			(hide yes)
			(effects
				(font
					(size 1.27 1.27)
				)
				(justify mirror)
			)
		)
		(property "Value" "10KR2F-2-GP"
			(at -0.064008 -3.993896 90)
			(unlocked yes)
			(layer "B.Fab")
			(hide yes)
			(effects
				(font
					(size 1.016 1.016)
					(thickness 0.1524)
				)
				(justify mirror)
			)
		)
		(property "Device Type" "R402H16"
			(at -0.064008 -5.517896 90)
			(unlocked yes)
			(layer "B.Fab")
			(hide yes)
			(effects
				(font
					(size 1.016 1.016)
					(thickness 0.1524)
				)
				(justify mirror)
			)
		)
		(duplicate_pad_numbers_are_jumpers no)
		(fp_rect
			(start 0.381 0.8382)
			(end -0.381 -0.8382)
			(stroke
				(width 0)
				(type default)
			)
			(fill no)
			(layer "B.CrtYd")
		)
		(fp_rect
			(start 0.381 0.8382)
			(end -0.381 -0.8382)
			(stroke
				(width 0)
				(type default)
			)
			(fill no)
			(layer "B.Fab")
		)
		(pad "1" smd custom
			(at 0 -0.4318 270)
			(size 0.127 0.127)
			(layers "B.Cu" "B.Mask" "B.Paste")
			(net "P3V3_CPU")
			(options
				(clearance outline)
				(anchor circle)
			)
			(primitives
				(gr_poly
					(pts
						(arc
							(start -0.2032 0.2794)
							(mid -0.239121 0.264521)
							(end -0.254 0.2286)
						)
						(arc
							(start -0.254 -0.2286)
							(mid -0.239121 -0.264521)
							(end -0.2032 -0.2794)
						)
						(arc
							(start 0.2032 -0.2794)
							(mid 0.239121 -0.264521)
							(end 0.254 -0.2286)
						)
						(arc
							(start 0.254 0.2286)
							(mid 0.239121 0.264521)
							(end 0.2032 0.2794)
						)
					)
					(width 0)
					(fill yes)
				)
			)
		)
		(pad "2" smd custom
			(at 0 0.4318 270)
			(size 0.127 0.127)
			(layers "B.Cu" "B.Mask" "B.Paste")
			(net "GBE_SMBALRT#")
			(options
				(clearance outline)
				(anchor circle)
			)
			(primitives
				(gr_poly
					(pts
						(arc
							(start -0.2032 0.2794)
							(mid -0.239121 0.264521)
							(end -0.254 0.2286)
						)
						(arc
							(start -0.254 -0.2286)
							(mid -0.239121 -0.264521)
							(end -0.2032 -0.2794)
						)
						(arc
							(start 0.2032 -0.2794)
							(mid 0.239121 -0.264521)
							(end 0.254 -0.2286)
						)
						(arc
							(start 0.254 0.2286)
							(mid 0.239121 0.264521)
							(end 0.2032 0.2794)
						)
					)
					(width 0)
					(fill yes)
				)
			)
		)
	)
	(footprint ""
		(layer "B.Cu")
		(at 49.657 -30.5308 -90)
		(property "Reference" "L10"
			(at 0 0 90)
			(layer "B.SilkS")
			(hide yes)
			(effects
				(font
					(size 1.27 1.27)
				)
				(justify mirror)
			)
		)
		(property "Value" "BLM18PG330SN1D-GP"
			(at 0.0254 -2.0193 270)
			(unlocked yes)
			(layer "B.Fab")
			(hide yes)
			(effects
				(font
					(size 1.016 1.016)
					(thickness 0.1524)
				)
				(justify mirror)
			)
		)
		(property "Device Type" "L1608-UH38"
			(at 0.0254 -3.5433 270)
			(unlocked yes)
			(layer "B.Fab")
			(hide yes)
			(effects
				(font
					(size 1.016 1.016)
					(thickness 0.1524)
				)
				(justify mirror)
			)
		)
		(duplicate_pad_numbers_are_jumpers no)
		(fp_line
			(start 0.4064 0)
			(end -0.4064 0)
			(stroke
				(width 0.2032)
				(type default)
			)
			(layer "B.SilkS")
		)
		(fp_rect
			(start 0.635 1.1811)
			(end -0.635 -1.1811)
			(stroke
				(width 0)
				(type default)
			)
			(fill no)
			(layer "B.CrtYd")
		)
		(fp_rect
			(start 0.635 1.1811)
			(end -0.635 -1.1811)
			(stroke
				(width 0)
				(type default)
			)
			(fill no)
			(layer "B.Fab")
		)
		(pad "1" smd custom
			(at 0 -0.6604 90)
			(size 0.19685 0.19685)
			(layers "B.Cu" "B.Mask" "B.Paste")
			(net "P3V3")
			(options
				(clearance outline)
				(anchor circle)
			)
			(primitives
				(gr_poly
					(pts
						(arc
							(start 0.508 0.2921)
							(mid 0.478242 0.363942)
							(end 0.4064 0.3937)
						)
						(arc
							(start -0.4064 0.3937)
							(mid -0.478242 0.363942)
							(end -0.508 0.2921)
						)
						(arc
							(start -0.508 -0.2921)
							(mid -0.478242 -0.363942)
							(end -0.4064 -0.3937)
						)
						(arc
							(start 0.4064 -0.3937)
							(mid 0.478242 -0.363942)
							(end 0.508 -0.2921)
						)
					)
					(width 0)
					(fill yes)
				)
			)
		)
		(pad "2" smd custom
			(at 0 0.6604 90)
			(size 0.19685 0.19685)
			(layers "B.Cu" "B.Mask" "B.Paste")
			(net "P3V3_VDDA_CLKBUFF_R")
			(options
				(clearance outline)
				(anchor circle)
			)
			(primitives
				(gr_poly
					(pts
						(arc
							(start 0.508 0.2921)
							(mid 0.478242 0.363942)
							(end 0.4064 0.3937)
						)
						(arc
							(start -0.4064 0.3937)
							(mid -0.478242 0.363942)
							(end -0.508 0.2921)
						)
						(arc
							(start -0.508 -0.2921)
							(mid -0.478242 -0.363942)
							(end -0.4064 -0.3937)
						)
						(arc
							(start 0.4064 -0.3937)
							(mid 0.478242 -0.363942)
							(end 0.508 -0.2921)
						)
					)
					(width 0)
					(fill yes)
				)
			)
		)
	)
	(footprint ""
		(layer "B.Cu")
		(at 133.731 -38.481 -90)
		(property "Reference" "C135"
			(at 0 0 90)
			(layer "B.SilkS")
			(hide yes)
			(effects
				(font
					(size 1.27 1.27)
				)
				(justify mirror)
			)
		)
		(property "Value" "SCD1U10V2KX-5GP"
			(at -1.1811 -2.7051 270)
			(unlocked yes)
			(layer "B.Fab")
			(hide yes)
			(effects
				(font
					(size 1.016 1.016)
					(thickness 0.1524)
				)
				(justify mirror)
			)
		)
		(property "Device Type" "C402H22"
			(at -1.1811 -4.2291 270)
			(unlocked yes)
			(layer "B.Fab")
			(hide yes)
			(effects
				(font
					(size 1.016 1.016)
					(thickness 0.1524)
				)
				(justify mirror)
			)
		)
		(duplicate_pad_numbers_are_jumpers no)
		(fp_rect
			(start 0.381 0.7366)
			(end -0.381 -0.7366)
			(stroke
				(width 0)
				(type default)
			)
			(fill no)
			(layer "B.CrtYd")
		)
		(fp_rect
			(start 0.381 0.7366)
			(end -0.381 -0.7366)
			(stroke
				(width 0)
				(type default)
			)
			(fill no)
			(layer "B.Fab")
		)
		(pad "1" smd custom
			(at 0 -0.4572 90)
			(size 0.1143 0.1143)
			(layers "B.Cu" "B.Mask" "B.Paste")
			(net "P3V3_STBY")
			(options
				(clearance outline)
				(anchor circle)
			)
			(primitives
				(gr_poly
					(pts
						(arc
							(start -0.254 0.1778)
							(mid -0.239121 0.213721)
							(end -0.2032 0.2286)
						)
						(arc
							(start 0.2032 0.2286)
							(mid 0.239121 0.213721)
							(end 0.254 0.1778)
						)
						(arc
							(start 0.254 -0.1778)
							(mid 0.239121 -0.213721)
							(end 0.2032 -0.2286)
						)
						(arc
							(start -0.2032 -0.2286)
							(mid -0.239121 -0.213721)
							(end -0.254 -0.1778)
						)
					)
					(width 0)
					(fill yes)
				)
			)
		)
		(pad "2" smd custom
			(at 0 0.4572 90)
			(size 0.1143 0.1143)
			(layers "B.Cu" "B.Mask" "B.Paste")
			(net "GND")
			(options
				(clearance outline)
				(anchor circle)
			)
			(primitives
				(gr_poly
					(pts
						(arc
							(start -0.254 0.1778)
							(mid -0.239121 0.213721)
							(end -0.2032 0.2286)
						)
						(arc
							(start 0.2032 0.2286)
							(mid 0.239121 0.213721)
							(end 0.254 0.1778)
						)
						(arc
							(start 0.254 -0.1778)
							(mid 0.239121 -0.213721)
							(end 0.2032 -0.2286)
						)
						(arc
							(start -0.2032 -0.2286)
							(mid -0.239121 -0.213721)
							(end -0.254 -0.1778)
						)
					)
					(width 0)
					(fill yes)
				)
			)
		)
	)
	(footprint ""
		(layer "B.Cu")
		(at 36.957 -27.686 -90)
		(property "Reference" "R453"
			(at 0 0 90)
			(layer "B.SilkS")
			(hide yes)
			(effects
				(font
					(size 1.27 1.27)
				)
				(justify mirror)
			)
		)
		(property "Value" "4K7R2F-GP"
			(at -1.7907 -1.1176 270)
			(unlocked yes)
			(layer "B.Fab")
			(hide yes)
			(effects
				(font
					(size 1.016 1.016)
					(thickness 0.1524)
				)
				(justify mirror)
			)
		)
		(property "Device Type" "R402H16"
			(at -1.7907 -2.6416 270)
			(unlocked yes)
			(layer "B.Fab")
			(hide yes)
			(effects
				(font
					(size 1.016 1.016)
					(thickness 0.1524)
				)
				(justify mirror)
			)
		)
		(duplicate_pad_numbers_are_jumpers no)
		(fp_rect
			(start 0.381 0.8382)
			(end -0.381 -0.8382)
			(stroke
				(width 0)
				(type default)
			)
			(fill no)
			(layer "B.CrtYd")
		)
		(fp_rect
			(start 0.381 0.8382)
			(end -0.381 -0.8382)
			(stroke
				(width 0)
				(type default)
			)
			(fill no)
			(layer "B.Fab")
		)
		(pad "1" smd custom
			(at 0 -0.4318 90)
			(size 0.127 0.127)
			(layers "B.Cu" "B.Mask" "B.Paste")
			(net "CLKCUFF_SMB_ADDR")
			(options
				(clearance outline)
				(anchor circle)
			)
			(primitives
				(gr_poly
					(pts
						(arc
							(start -0.2032 0.2794)
							(mid -0.239121 0.264521)
							(end -0.254 0.2286)
						)
						(arc
							(start -0.254 -0.2286)
							(mid -0.239121 -0.264521)
							(end -0.2032 -0.2794)
						)
						(arc
							(start 0.2032 -0.2794)
							(mid 0.239121 -0.264521)
							(end 0.254 -0.2286)
						)
						(arc
							(start 0.254 0.2286)
							(mid 0.239121 0.264521)
							(end 0.2032 0.2794)
						)
					)
					(width 0)
					(fill yes)
				)
			)
		)
		(pad "2" smd custom
			(at 0 0.4318 90)
			(size 0.127 0.127)
			(layers "B.Cu" "B.Mask" "B.Paste")
			(net "GND")
			(options
				(clearance outline)
				(anchor circle)
			)
			(primitives
				(gr_poly
					(pts
						(arc
							(start -0.2032 0.2794)
							(mid -0.239121 0.264521)
							(end -0.254 0.2286)
						)
						(arc
							(start -0.254 -0.2286)
							(mid -0.239121 -0.264521)
							(end -0.2032 -0.2794)
						)
						(arc
							(start 0.2032 -0.2794)
							(mid 0.239121 -0.264521)
							(end 0.254 -0.2286)
						)
						(arc
							(start 0.254 0.2286)
							(mid 0.239121 0.264521)
							(end 0.2032 0.2794)
						)
					)
					(width 0)
					(fill yes)
				)
			)
		)
	)
	(footprint ""
		(layer "B.Cu")
		(at 100.074984 -33.290002 -90)
		(property "Reference" "C219"
			(at 0 0 90)
			(layer "B.SilkS")
			(hide yes)
			(effects
				(font
					(size 1.27 1.27)
				)
				(justify mirror)
			)
		)
		(property "Value" "SC1U10V2KX-1GP"
			(at -1.1811 -2.7051 270)
			(unlocked yes)
			(layer "B.Fab")
			(hide yes)
			(effects
				(font
					(size 1.016 1.016)
					(thickness 0.1524)
				)
				(justify mirror)
			)
		)
		(property "Device Type" "C402H22"
			(at -1.1811 -4.2291 270)
			(unlocked yes)
			(layer "B.Fab")
			(hide yes)
			(effects
				(font
					(size 1.016 1.016)
					(thickness 0.1524)
				)
				(justify mirror)
			)
		)
		(duplicate_pad_numbers_are_jumpers no)
		(fp_rect
			(start 0.381 0.7366)
			(end -0.381 -0.7366)
			(stroke
				(width 0)
				(type default)
			)
			(fill no)
			(layer "B.CrtYd")
		)
		(fp_rect
			(start 0.381 0.7366)
			(end -0.381 -0.7366)
			(stroke
				(width 0)
				(type default)
			)
			(fill no)
			(layer "B.Fab")
		)
		(pad "1" smd custom
			(at 0 -0.4572 90)
			(size 0.1143 0.1143)
			(layers "B.Cu" "B.Mask" "B.Paste")
			(net "P1V0")
			(options
				(clearance outline)
				(anchor circle)
			)
			(primitives
				(gr_poly
					(pts
						(arc
							(start -0.254 0.1778)
							(mid -0.239121 0.213721)
							(end -0.2032 0.2286)
						)
						(arc
							(start 0.2032 0.2286)
							(mid 0.239121 0.213721)
							(end 0.254 0.1778)
						)
						(arc
							(start 0.254 -0.1778)
							(mid 0.239121 -0.213721)
							(end 0.2032 -0.2286)
						)
						(arc
							(start -0.2032 -0.2286)
							(mid -0.239121 -0.213721)
							(end -0.254 -0.1778)
						)
					)
					(width 0)
					(fill yes)
				)
			)
		)
		(pad "2" smd custom
			(at 0 0.4572 90)
			(size 0.1143 0.1143)
			(layers "B.Cu" "B.Mask" "B.Paste")
			(net "GND")
			(options
				(clearance outline)
				(anchor circle)
			)
			(primitives
				(gr_poly
					(pts
						(arc
							(start -0.254 0.1778)
							(mid -0.239121 0.213721)
							(end -0.2032 0.2286)
						)
						(arc
							(start 0.2032 0.2286)
							(mid 0.239121 0.213721)
							(end 0.254 0.1778)
						)
						(arc
							(start 0.254 -0.1778)
							(mid 0.239121 -0.213721)
							(end 0.2032 -0.2286)
						)
						(arc
							(start -0.2032 -0.2286)
							(mid -0.239121 -0.213721)
							(end -0.254 -0.1778)
						)
					)
					(width 0)
					(fill yes)
				)
			)
		)
	)
	(footprint ""
		(layer "B.Cu")
		(at 9.017 -22.606 180)
		(property "Reference" "PR112"
			(at 0 0 0)
			(layer "B.SilkS")
			(hide yes)
			(effects
				(font
					(size 1.27 1.27)
				)
				(justify mirror)
			)
		)
		(property "Value" "100KR2F-L2-GP"
			(at -1.7907 -1.1176 180)
			(unlocked yes)
			(layer "B.Fab")
			(hide yes)
			(effects
				(font
					(size 1.016 1.016)
					(thickness 0.1524)
				)
				(justify mirror)
			)
		)
		(property "Device Type" "R402H16"
			(at -1.7907 -2.6416 180)
			(unlocked yes)
			(layer "B.Fab")
			(hide yes)
			(effects
				(font
					(size 1.016 1.016)
					(thickness 0.1524)
				)
				(justify mirror)
			)
		)
		(duplicate_pad_numbers_are_jumpers no)
		(fp_rect
			(start 0.381 0.8382)
			(end -0.381 -0.8382)
			(stroke
				(width 0)
				(type default)
			)
			(fill no)
			(layer "B.CrtYd")
		)
		(fp_rect
			(start 0.381 0.8382)
			(end -0.381 -0.8382)
			(stroke
				(width 0)
				(type default)
			)
			(fill no)
			(layer "B.Fab")
		)
		(pad "1" smd custom
			(at 0 -0.4318)
			(size 0.127 0.127)
			(layers "B.Cu" "B.Mask" "B.Paste")
			(net "P1V0_VREG")
			(options
				(clearance outline)
				(anchor circle)
			)
			(primitives
				(gr_poly
					(pts
						(arc
							(start -0.2032 0.2794)
							(mid -0.239121 0.264521)
							(end -0.254 0.2286)
						)
						(arc
							(start -0.254 -0.2286)
							(mid -0.239121 -0.264521)
							(end -0.2032 -0.2794)
						)
						(arc
							(start 0.2032 -0.2794)
							(mid 0.239121 -0.264521)
							(end 0.254 -0.2286)
						)
						(arc
							(start 0.254 0.2286)
							(mid 0.239121 0.264521)
							(end 0.2032 0.2794)
						)
					)
					(width 0)
					(fill yes)
				)
			)
		)
		(pad "2" smd custom
			(at 0 0.4318)
			(size 0.127 0.127)
			(layers "B.Cu" "B.Mask" "B.Paste")
			(net "P1V0_RF")
			(options
				(clearance outline)
				(anchor circle)
			)
			(primitives
				(gr_poly
					(pts
						(arc
							(start -0.2032 0.2794)
							(mid -0.239121 0.264521)
							(end -0.254 0.2286)
						)
						(arc
							(start -0.254 -0.2286)
							(mid -0.239121 -0.264521)
							(end -0.2032 -0.2794)
						)
						(arc
							(start 0.2032 -0.2794)
							(mid 0.239121 -0.264521)
							(end 0.254 -0.2286)
						)
						(arc
							(start 0.254 0.2286)
							(mid 0.239121 0.264521)
							(end 0.2032 0.2794)
						)
					)
					(width 0)
					(fill yes)
				)
			)
		)
	)
	(footprint ""
		(layer "B.Cu")
		(at 114.173 -67.691)
		(property "Reference" "C322"
			(at 0 0 0)
			(layer "B.SilkS")
			(hide yes)
			(effects
				(font
					(size 1.27 1.27)
				)
				(justify mirror)
			)
		)
		(property "Value" "SC22U6D3V5MX-2GP"
			(at 0 -4.9022 0)
			(unlocked yes)
			(layer "B.Fab")
			(hide yes)
			(effects
				(font
					(size 1.016 1.016)
					(thickness 0.1524)
				)
				(justify mirror)
			)
		)
		(property "Device Type" "C805H58"
			(at 0 -6.8072 0)
			(unlocked yes)
			(layer "B.Fab")
			(hide yes)
			(effects
				(font
					(size 1.016 1.016)
					(thickness 0.1524)
				)
				(justify mirror)
			)
		)
		(duplicate_pad_numbers_are_jumpers no)
		(fp_line
			(start -0.6096 0)
			(end 0.6096 0)
			(stroke
				(width 0.3048)
				(type default)
			)
			(layer "B.SilkS")
		)
		(fp_poly
			(pts
				(xy 0.9017 1.4351) (xy -0.9017 1.4351) (xy -0.9017 -1.4351) (xy 0.9017 -1.4351)
			)
			(stroke
				(width 0)
				(type default)
			)
			(fill no)
			(layer "B.CrtYd")
		)
		(fp_poly
			(pts
				(xy -0.9017 1.4351) (xy -0.9017 -1.4351) (xy 0.9017 -1.4351) (xy 0.9017 1.4351)
			)
			(stroke
				(width 0)
				(type default)
			)
			(fill no)
			(layer "B.Fab")
		)
		(pad "1" smd rect
			(at 0 -0.8382 180)
			(size 1.5494 0.9398)
			(layers "B.Cu" "B.Mask" "B.Paste")
			(net "P3V3_RTC")
		)
		(pad "2" smd rect
			(at 0 0.8382 180)
			(size 1.5494 0.9398)
			(layers "B.Cu" "B.Mask" "B.Paste")
			(net "GND")
		)
	)
	(footprint ""
		(layer "B.Cu")
		(at 87.4903 -40.4368 90)
		(property "Reference" "R302"
			(at 0 0 90)
			(layer "B.SilkS")
			(hide yes)
			(effects
				(font
					(size 1.27 1.27)
				)
				(justify mirror)
			)
		)
		(property "Value" "0R2J-2-GP"
			(at -0.064008 -3.993896 90)
			(unlocked yes)
			(layer "B.Fab")
			(hide yes)
			(effects
				(font
					(size 1.016 1.016)
					(thickness 0.1524)
				)
				(justify mirror)
			)
		)
		(property "Device Type" "R402H16"
			(at -0.064008 -5.517896 90)
			(unlocked yes)
			(layer "B.Fab")
			(hide yes)
			(effects
				(font
					(size 1.016 1.016)
					(thickness 0.1524)
				)
				(justify mirror)
			)
		)
		(duplicate_pad_numbers_are_jumpers no)
		(fp_rect
			(start 0.381 0.8382)
			(end -0.381 -0.8382)
			(stroke
				(width 0)
				(type default)
			)
			(fill no)
			(layer "B.CrtYd")
		)
		(fp_rect
			(start 0.381 0.8382)
			(end -0.381 -0.8382)
			(stroke
				(width 0)
				(type default)
			)
			(fill no)
			(layer "B.Fab")
		)
		(pad "1" smd custom
			(at 0 -0.4318 270)
			(size 0.127 0.127)
			(layers "B.Cu" "B.Mask" "B.Paste")
			(net "IRQ_MCERR_R#")
			(options
				(clearance outline)
				(anchor circle)
			)
			(primitives
				(gr_poly
					(pts
						(arc
							(start -0.2032 0.2794)
							(mid -0.239121 0.264521)
							(end -0.254 0.2286)
						)
						(arc
							(start -0.254 -0.2286)
							(mid -0.239121 -0.264521)
							(end -0.2032 -0.2794)
						)
						(arc
							(start 0.2032 -0.2794)
							(mid 0.239121 -0.264521)
							(end 0.254 -0.2286)
						)
						(arc
							(start 0.254 0.2286)
							(mid 0.239121 0.264521)
							(end 0.2032 0.2794)
						)
					)
					(width 0)
					(fill yes)
				)
			)
		)
		(pad "2" smd custom
			(at 0 0.4318 270)
			(size 0.127 0.127)
			(layers "B.Cu" "B.Mask" "B.Paste")
			(net "IRQ_MCERR#")
			(options
				(clearance outline)
				(anchor circle)
			)
			(primitives
				(gr_poly
					(pts
						(arc
							(start -0.2032 0.2794)
							(mid -0.239121 0.264521)
							(end -0.254 0.2286)
						)
						(arc
							(start -0.254 -0.2286)
							(mid -0.239121 -0.264521)
							(end -0.2032 -0.2794)
						)
						(arc
							(start 0.2032 -0.2794)
							(mid 0.239121 -0.264521)
							(end 0.254 -0.2286)
						)
						(arc
							(start 0.254 0.2286)
							(mid 0.239121 0.264521)
							(end 0.2032 0.2794)
						)
					)
					(width 0)
					(fill yes)
				)
			)
		)
	)
	(footprint ""
		(layer "B.Cu")
		(at 31.369 -30.734 90)
		(property "Reference" "R273"
			(at 0 0 90)
			(layer "B.SilkS")
			(hide yes)
			(effects
				(font
					(size 1.27 1.27)
				)
				(justify mirror)
			)
		)
		(property "Value" "0R3J-0-U-GP"
			(at 0.0254 -2.5146 90)
			(unlocked yes)
			(layer "B.Fab")
			(hide yes)
			(effects
				(font
					(size 1.016 1.016)
					(thickness 0.1524)
				)
				(justify mirror)
			)
		)
		(property "Device Type" "R603H22"
			(at 0.0254 -4.0386 90)
			(unlocked yes)
			(layer "B.Fab")
			(hide yes)
			(effects
				(font
					(size 1.016 1.016)
					(thickness 0.1524)
				)
				(justify mirror)
			)
		)
		(duplicate_pad_numbers_are_jumpers no)
		(fp_line
			(start 0.2032 0)
			(end 0.4191 0)
			(stroke
				(width 0.2032)
				(type default)
			)
			(layer "B.SilkS")
		)
		(fp_line
			(start -0.4318 0)
			(end -0.2032 0)
			(stroke
				(width 0.2032)
				(type default)
			)
			(layer "B.SilkS")
		)
		(fp_rect
			(start 0.635 1.1811)
			(end -0.635 -1.1811)
			(stroke
				(width 0)
				(type default)
			)
			(fill no)
			(layer "B.CrtYd")
		)
		(fp_rect
			(start 0.635 1.1811)
			(end -0.635 -1.1811)
			(stroke
				(width 0)
				(type default)
			)
			(fill no)
			(layer "B.Fab")
		)
		(pad "1" smd custom
			(at 0 -0.6604 270)
			(size 0.19685 0.19685)
			(layers "B.Cu" "B.Mask" "B.Paste")
			(net "P1V0")
			(options
				(clearance outline)
				(anchor circle)
			)
			(primitives
				(gr_poly
					(pts
						(arc
							(start 0.508 0.2921)
							(mid 0.478242 0.363942)
							(end 0.4064 0.3937)
						)
						(arc
							(start -0.4064 0.3937)
							(mid -0.478242 0.363942)
							(end -0.508 0.2921)
						)
						(arc
							(start -0.508 -0.2921)
							(mid -0.478242 -0.363942)
							(end -0.4064 -0.3937)
						)
						(arc
							(start 0.4064 -0.3937)
							(mid 0.478242 -0.363942)
							(end 0.508 -0.2921)
						)
					)
					(width 0)
					(fill yes)
				)
			)
		)
		(pad "2" smd custom
			(at 0 0.6604 270)
			(size 0.19685 0.19685)
			(layers "B.Cu" "B.Mask" "B.Paste")
			(net "VCC_OBS_CD")
			(options
				(clearance outline)
				(anchor circle)
			)
			(primitives
				(gr_poly
					(pts
						(arc
							(start 0.508 0.2921)
							(mid 0.478242 0.363942)
							(end 0.4064 0.3937)
						)
						(arc
							(start -0.4064 0.3937)
							(mid -0.478242 0.363942)
							(end -0.508 0.2921)
						)
						(arc
							(start -0.508 -0.2921)
							(mid -0.478242 -0.363942)
							(end -0.4064 -0.3937)
						)
						(arc
							(start 0.4064 -0.3937)
							(mid 0.478242 -0.363942)
							(end 0.508 -0.2921)
						)
					)
					(width 0)
					(fill yes)
				)
			)
		)
	)
	(footprint ""
		(layer "B.Cu")
		(at 74.93 -49.149 90)
		(property "Reference" "R313"
			(at 0 0 90)
			(layer "B.SilkS")
			(hide yes)
			(effects
				(font
					(size 1.27 1.27)
				)
				(justify mirror)
			)
		)
		(property "Value" "4K7R2F-GP"
			(at -0.064008 -3.993896 90)
			(unlocked yes)
			(layer "B.Fab")
			(hide yes)
			(effects
				(font
					(size 1.016 1.016)
					(thickness 0.1524)
				)
				(justify mirror)
			)
		)
		(property "Device Type" "R402H16"
			(at -0.064008 -5.517896 90)
			(unlocked yes)
			(layer "B.Fab")
			(hide yes)
			(effects
				(font
					(size 1.016 1.016)
					(thickness 0.1524)
				)
				(justify mirror)
			)
		)
		(duplicate_pad_numbers_are_jumpers no)
		(fp_rect
			(start 0.381 0.8382)
			(end -0.381 -0.8382)
			(stroke
				(width 0)
				(type default)
			)
			(fill no)
			(layer "B.CrtYd")
		)
		(fp_rect
			(start 0.381 0.8382)
			(end -0.381 -0.8382)
			(stroke
				(width 0)
				(type default)
			)
			(fill no)
			(layer "B.Fab")
		)
		(pad "1" smd custom
			(at 0 -0.4318 270)
			(size 0.127 0.127)
			(layers "B.Cu" "B.Mask" "B.Paste")
			(net "P3V3")
			(options
				(clearance outline)
				(anchor circle)
			)
			(primitives
				(gr_poly
					(pts
						(arc
							(start -0.2032 0.2794)
							(mid -0.239121 0.264521)
							(end -0.254 0.2286)
						)
						(arc
							(start -0.254 -0.2286)
							(mid -0.239121 -0.264521)
							(end -0.2032 -0.2794)
						)
						(arc
							(start 0.2032 -0.2794)
							(mid 0.239121 -0.264521)
							(end 0.254 -0.2286)
						)
						(arc
							(start 0.254 0.2286)
							(mid 0.239121 0.264521)
							(end 0.2032 0.2794)
						)
					)
					(width 0)
					(fill yes)
				)
			)
		)
		(pad "2" smd custom
			(at 0 0.4318 270)
			(size 0.127 0.127)
			(layers "B.Cu" "B.Mask" "B.Paste")
			(net "SMBUS_HOST_DATA")
			(options
				(clearance outline)
				(anchor circle)
			)
			(primitives
				(gr_poly
					(pts
						(arc
							(start -0.2032 0.2794)
							(mid -0.239121 0.264521)
							(end -0.254 0.2286)
						)
						(arc
							(start -0.254 -0.2286)
							(mid -0.239121 -0.264521)
							(end -0.2032 -0.2794)
						)
						(arc
							(start 0.2032 -0.2794)
							(mid 0.239121 -0.264521)
							(end 0.254 -0.2286)
						)
						(arc
							(start 0.254 0.2286)
							(mid 0.239121 0.264521)
							(end 0.2032 0.2794)
						)
					)
					(width 0)
					(fill yes)
				)
			)
		)
	)
	(footprint ""
		(layer "B.Cu")
		(at 22.098 -27.94 -90)
		(property "Reference" "PC63"
			(at 0 0 90)
			(layer "B.SilkS")
			(hide yes)
			(effects
				(font
					(size 1.27 1.27)
				)
				(justify mirror)
			)
		)
		(property "Value" "SCD1U16V2KX-3GP"
			(at -1.8923 -1.2065 270)
			(unlocked yes)
			(layer "B.Fab")
			(hide yes)
			(effects
				(font
					(size 1.016 1.016)
					(thickness 0.1524)
				)
				(justify mirror)
			)
		)
		(property "Device Type" "C402H22"
			(at -1.8923 -2.7305 270)
			(unlocked yes)
			(layer "B.Fab")
			(hide yes)
			(effects
				(font
					(size 1.016 1.016)
					(thickness 0.1524)
				)
				(justify mirror)
			)
		)
		(duplicate_pad_numbers_are_jumpers no)
		(fp_rect
			(start 0.381 0.7366)
			(end -0.381 -0.7366)
			(stroke
				(width 0)
				(type default)
			)
			(fill no)
			(layer "B.CrtYd")
		)
		(fp_rect
			(start 0.381 0.7366)
			(end -0.381 -0.7366)
			(stroke
				(width 0)
				(type default)
			)
			(fill no)
			(layer "B.Fab")
		)
		(pad "1" smd custom
			(at 0 -0.4572 90)
			(size 0.1143 0.1143)
			(layers "B.Cu" "B.Mask" "B.Paste")
			(net "P1V0")
			(options
				(clearance outline)
				(anchor circle)
			)
			(primitives
				(gr_poly
					(pts
						(arc
							(start -0.254 0.1778)
							(mid -0.239121 0.213721)
							(end -0.2032 0.2286)
						)
						(arc
							(start 0.2032 0.2286)
							(mid 0.239121 0.213721)
							(end 0.254 0.1778)
						)
						(arc
							(start 0.254 -0.1778)
							(mid 0.239121 -0.213721)
							(end 0.2032 -0.2286)
						)
						(arc
							(start -0.2032 -0.2286)
							(mid -0.239121 -0.213721)
							(end -0.254 -0.1778)
						)
					)
					(width 0)
					(fill yes)
				)
			)
		)
		(pad "2" smd custom
			(at 0 0.4572 90)
			(size 0.1143 0.1143)
			(layers "B.Cu" "B.Mask" "B.Paste")
			(net "P1V0_SW_R")
			(options
				(clearance outline)
				(anchor circle)
			)
			(primitives
				(gr_poly
					(pts
						(arc
							(start -0.254 0.1778)
							(mid -0.239121 0.213721)
							(end -0.2032 0.2286)
						)
						(arc
							(start 0.2032 0.2286)
							(mid 0.239121 0.213721)
							(end 0.254 0.1778)
						)
						(arc
							(start 0.254 -0.1778)
							(mid 0.239121 -0.213721)
							(end 0.2032 -0.2286)
						)
						(arc
							(start -0.2032 -0.2286)
							(mid -0.239121 -0.213721)
							(end -0.254 -0.1778)
						)
					)
					(width 0)
					(fill yes)
				)
			)
		)
	)
	(footprint ""
		(layer "B.Cu")
		(at 116.967 -67.056)
		(property "Reference" "D1"
			(at 0 0 0)
			(layer "B.SilkS")
			(hide yes)
			(effects
				(font
					(size 1.27 1.27)
				)
				(justify mirror)
			)
		)
		(property "Value" "BAT54C-7-F-3-GP"
			(at 3.040634 -3.610864 0)
			(unlocked yes)
			(layer "B.Fab")
			(hide yes)
			(effects
				(font
					(size 1.016 1.016)
					(thickness 0.1524)
				)
				(justify mirror)
			)
		)
		(property "Device Type" "SOT23-2D4-312H48"
			(at 3.040634 -5.134864 0)
			(unlocked yes)
			(layer "B.Fab")
			(hide yes)
			(effects
				(font
					(size 1.016 1.016)
					(thickness 0.1524)
				)
				(justify mirror)
			)
		)
		(duplicate_pad_numbers_are_jumpers no)
		(fp_line
			(start -1.7145 -0.4445)
			(end 1.7145 -0.4445)
			(stroke
				(width 0.1524)
				(type default)
			)
			(layer "B.SilkS")
		)
		(fp_line
			(start -1.7145 0.4445)
			(end -1.7145 -0.4445)
			(stroke
				(width 0.1524)
				(type default)
			)
			(layer "B.SilkS")
		)
		(fp_line
			(start 1.7145 -0.4445)
			(end 1.7145 0.4445)
			(stroke
				(width 0.1524)
				(type default)
			)
			(layer "B.SilkS")
		)
		(fp_line
			(start 1.7145 0.4445)
			(end -1.7145 0.4445)
			(stroke
				(width 0.1524)
				(type default)
			)
			(layer "B.SilkS")
		)
		(fp_poly
			(pts
				(xy 1.4224 1.5621) (xy 1.4224 0.9017) (xy 1.7145 0.9017) (xy 1.7145 -0.9017) (xy 0.4699 -0.9017)
				(xy 0.4699 -1.5621) (xy -0.4699 -1.5621) (xy -0.4699 -0.9017) (xy -1.7145 -0.9017) (xy -1.7145 0.9017)
				(xy -1.4224 0.9017) (xy -1.4224 1.5621) (xy -0.4826 1.5621) (xy -0.4826 0.9017) (xy 0.4826 0.9017)
				(xy 0.4826 1.5621)
			)
			(stroke
				(width 0)
				(type default)
			)
			(fill no)
			(layer "B.CrtYd")
		)
		(fp_poly
			(pts
				(xy 1.4224 1.5621) (xy 1.4224 0.9017) (xy 1.7145 0.9017) (xy 1.7145 -0.9017) (xy 0.4699 -0.9017)
				(xy 0.4699 -1.5621) (xy -0.4699 -1.5621) (xy -0.4699 -0.9017) (xy -1.7145 -0.9017) (xy -1.7145 0.9017)
				(xy -1.4224 0.9017) (xy -1.4224 1.5621) (xy -0.4826 1.5621) (xy -0.4826 0.9017) (xy 0.4826 0.9017)
				(xy 0.4826 1.5621)
			)
			(stroke
				(width 0)
				(type default)
			)
			(fill no)
			(layer "B.Fab")
		)
		(pad "1" smd custom
			(at 0.94996 1.069086 180)
			(size 0.17145 0.17145)
			(layers "B.Cu" "B.Mask" "B.Paste")
			(net "P3V3_STBY")
			(options
				(clearance outline)
				(anchor circle)
			)
			(primitives
				(gr_poly
					(pts
						(arc
							(start -0.1397 -0.3683)
							(mid -0.283384 -0.308784)
							(end -0.3429 -0.1651)
						)
						(arc
							(start -0.3429 0.1651)
							(mid -0.283384 0.308784)
							(end -0.1397 0.3683)
						)
						(arc
							(start 0.1397 0.3683)
							(mid 0.283384 0.308784)
							(end 0.3429 0.1651)
						)
						(arc
							(start 0.3429 -0.1651)
							(mid 0.283384 -0.308784)
							(end 0.1397 -0.3683)
						)
					)
					(width 0)
					(fill yes)
				)
			)
		)
		(pad "2" smd custom
			(at -0.94996 1.069086 180)
			(size 0.17145 0.17145)
			(layers "B.Cu" "B.Mask" "B.Paste")
			(net "P3V0_BAT_R")
			(options
				(clearance outline)
				(anchor circle)
			)
			(primitives
				(gr_poly
					(pts
						(arc
							(start -0.1397 -0.3683)
							(mid -0.283384 -0.308784)
							(end -0.3429 -0.1651)
						)
						(arc
							(start -0.3429 0.1651)
							(mid -0.283384 0.308784)
							(end -0.1397 0.3683)
						)
						(arc
							(start 0.1397 0.3683)
							(mid 0.283384 0.308784)
							(end 0.3429 0.1651)
						)
						(arc
							(start 0.3429 -0.1651)
							(mid 0.283384 -0.308784)
							(end 0.1397 -0.3683)
						)
					)
					(width 0)
					(fill yes)
				)
			)
		)
		(pad "3" smd custom
			(at 0 -1.069086 180)
			(size 0.17145 0.17145)
			(layers "B.Cu" "B.Mask" "B.Paste")
			(net "P3V3_RTC")
			(options
				(clearance outline)
				(anchor circle)
			)
			(primitives
				(gr_poly
					(pts
						(arc
							(start -0.1397 -0.3683)
							(mid -0.283384 -0.308784)
							(end -0.3429 -0.1651)
						)
						(arc
							(start -0.3429 0.1651)
							(mid -0.283384 0.308784)
							(end -0.1397 0.3683)
						)
						(arc
							(start 0.1397 0.3683)
							(mid 0.283384 0.308784)
							(end 0.3429 0.1651)
						)
						(arc
							(start 0.3429 -0.1651)
							(mid 0.283384 -0.308784)
							(end 0.1397 -0.3683)
						)
					)
					(width 0)
					(fill yes)
				)
			)
		)
	)
	(footprint ""
		(layer "B.Cu")
		(at 66.548 -13.589 180)
		(property "Reference" "C305"
			(at 0 0 0)
			(layer "B.SilkS")
			(hide yes)
			(effects
				(font
					(size 1.27 1.27)
				)
				(justify mirror)
			)
		)
		(property "Value" "SCD01U16V2KX-3GP"
			(at -1.8923 -1.2065 180)
			(unlocked yes)
			(layer "B.Fab")
			(hide yes)
			(effects
				(font
					(size 1.016 1.016)
					(thickness 0.1524)
				)
				(justify mirror)
			)
		)
		(property "Device Type" "C402H22"
			(at -1.8923 -2.7305 180)
			(unlocked yes)
			(layer "B.Fab")
			(hide yes)
			(effects
				(font
					(size 1.016 1.016)
					(thickness 0.1524)
				)
				(justify mirror)
			)
		)
		(duplicate_pad_numbers_are_jumpers no)
		(fp_rect
			(start 0.381 0.7366)
			(end -0.381 -0.7366)
			(stroke
				(width 0)
				(type default)
			)
			(fill no)
			(layer "B.CrtYd")
		)
		(fp_rect
			(start 0.381 0.7366)
			(end -0.381 -0.7366)
			(stroke
				(width 0)
				(type default)
			)
			(fill no)
			(layer "B.Fab")
		)
		(pad "1" smd custom
			(at 0 -0.4572)
			(size 0.1143 0.1143)
			(layers "B.Cu" "B.Mask" "B.Paste")
			(net "SATA2_TX_C_DP0")
			(options
				(clearance outline)
				(anchor circle)
			)
			(primitives
				(gr_poly
					(pts
						(arc
							(start -0.254 0.1778)
							(mid -0.239121 0.213721)
							(end -0.2032 0.2286)
						)
						(arc
							(start 0.2032 0.2286)
							(mid 0.239121 0.213721)
							(end 0.254 0.1778)
						)
						(arc
							(start 0.254 -0.1778)
							(mid 0.239121 -0.213721)
							(end 0.2032 -0.2286)
						)
						(arc
							(start -0.2032 -0.2286)
							(mid -0.239121 -0.213721)
							(end -0.254 -0.1778)
						)
					)
					(width 0)
					(fill yes)
				)
			)
		)
		(pad "2" smd custom
			(at 0 0.4572)
			(size 0.1143 0.1143)
			(layers "B.Cu" "B.Mask" "B.Paste")
			(net "SATA2_TX_DP0")
			(options
				(clearance outline)
				(anchor circle)
			)
			(primitives
				(gr_poly
					(pts
						(arc
							(start -0.254 0.1778)
							(mid -0.239121 0.213721)
							(end -0.2032 0.2286)
						)
						(arc
							(start 0.2032 0.2286)
							(mid 0.239121 0.213721)
							(end 0.254 0.1778)
						)
						(arc
							(start 0.254 -0.1778)
							(mid 0.239121 -0.213721)
							(end 0.2032 -0.2286)
						)
						(arc
							(start -0.2032 -0.2286)
							(mid -0.239121 -0.213721)
							(end -0.254 -0.1778)
						)
					)
					(width 0)
					(fill yes)
				)
			)
		)
	)
	(footprint ""
		(layer "B.Cu")
		(at 91.186 -37.4142 180)
		(property "Reference" "C198"
			(at 0 0 0)
			(layer "B.SilkS")
			(hide yes)
			(effects
				(font
					(size 1.27 1.27)
				)
				(justify mirror)
			)
		)
		(property "Value" "SC1U10V2KX-1GP"
			(at -1.1811 -2.7051 180)
			(unlocked yes)
			(layer "B.Fab")
			(hide yes)
			(effects
				(font
					(size 1.016 1.016)
					(thickness 0.1524)
				)
				(justify mirror)
			)
		)
		(property "Device Type" "C402H22"
			(at -1.1811 -4.2291 180)
			(unlocked yes)
			(layer "B.Fab")
			(hide yes)
			(effects
				(font
					(size 1.016 1.016)
					(thickness 0.1524)
				)
				(justify mirror)
			)
		)
		(duplicate_pad_numbers_are_jumpers no)
		(fp_rect
			(start 0.381 0.7366)
			(end -0.381 -0.7366)
			(stroke
				(width 0)
				(type default)
			)
			(fill no)
			(layer "B.CrtYd")
		)
		(fp_rect
			(start 0.381 0.7366)
			(end -0.381 -0.7366)
			(stroke
				(width 0)
				(type default)
			)
			(fill no)
			(layer "B.Fab")
		)
		(pad "1" smd custom
			(at 0 -0.4572)
			(size 0.1143 0.1143)
			(layers "B.Cu" "B.Mask" "B.Paste")
			(net "P3V3_CPU")
			(options
				(clearance outline)
				(anchor circle)
			)
			(primitives
				(gr_poly
					(pts
						(arc
							(start -0.254 0.1778)
							(mid -0.239121 0.213721)
							(end -0.2032 0.2286)
						)
						(arc
							(start 0.2032 0.2286)
							(mid 0.239121 0.213721)
							(end 0.254 0.1778)
						)
						(arc
							(start 0.254 -0.1778)
							(mid 0.239121 -0.213721)
							(end 0.2032 -0.2286)
						)
						(arc
							(start -0.2032 -0.2286)
							(mid -0.239121 -0.213721)
							(end -0.254 -0.1778)
						)
					)
					(width 0)
					(fill yes)
				)
			)
		)
		(pad "2" smd custom
			(at 0 0.4572)
			(size 0.1143 0.1143)
			(layers "B.Cu" "B.Mask" "B.Paste")
			(net "GND")
			(options
				(clearance outline)
				(anchor circle)
			)
			(primitives
				(gr_poly
					(pts
						(arc
							(start -0.254 0.1778)
							(mid -0.239121 0.213721)
							(end -0.2032 0.2286)
						)
						(arc
							(start 0.2032 0.2286)
							(mid 0.239121 0.213721)
							(end 0.254 0.1778)
						)
						(arc
							(start 0.254 -0.1778)
							(mid 0.239121 -0.213721)
							(end 0.2032 -0.2286)
						)
						(arc
							(start -0.2032 -0.2286)
							(mid -0.239121 -0.213721)
							(end -0.254 -0.1778)
						)
					)
					(width 0)
					(fill yes)
				)
			)
		)
	)
	(footprint ""
		(layer "B.Cu")
		(at 152.6794 -59.69)
		(property "Reference" "C331"
			(at 0 0 0)
			(layer "B.SilkS")
			(hide yes)
			(effects
				(font
					(size 1.27 1.27)
				)
				(justify mirror)
			)
		)
		(property "Value" "SCD1U16V2KX-3GP"
			(at -1.8923 -1.2065 0)
			(unlocked yes)
			(layer "B.Fab")
			(hide yes)
			(effects
				(font
					(size 1.016 1.016)
					(thickness 0.1524)
				)
				(justify mirror)
			)
		)
		(property "Device Type" "C402H22"
			(at -1.8923 -2.7305 0)
			(unlocked yes)
			(layer "B.Fab")
			(hide yes)
			(effects
				(font
					(size 1.016 1.016)
					(thickness 0.1524)
				)
				(justify mirror)
			)
		)
		(duplicate_pad_numbers_are_jumpers no)
		(fp_rect
			(start 0.381 0.7366)
			(end -0.381 -0.7366)
			(stroke
				(width 0)
				(type default)
			)
			(fill no)
			(layer "B.CrtYd")
		)
		(fp_rect
			(start 0.381 0.7366)
			(end -0.381 -0.7366)
			(stroke
				(width 0)
				(type default)
			)
			(fill no)
			(layer "B.Fab")
		)
		(pad "1" smd custom
			(at 0 -0.4572 180)
			(size 0.1143 0.1143)
			(layers "B.Cu" "B.Mask" "B.Paste")
			(net "PV_VDDR")
			(options
				(clearance outline)
				(anchor circle)
			)
			(primitives
				(gr_poly
					(pts
						(arc
							(start -0.254 0.1778)
							(mid -0.239121 0.213721)
							(end -0.2032 0.2286)
						)
						(arc
							(start 0.2032 0.2286)
							(mid 0.239121 0.213721)
							(end 0.254 0.1778)
						)
						(arc
							(start 0.254 -0.1778)
							(mid 0.239121 -0.213721)
							(end 0.2032 -0.2286)
						)
						(arc
							(start -0.2032 -0.2286)
							(mid -0.239121 -0.213721)
							(end -0.254 -0.1778)
						)
					)
					(width 0)
					(fill yes)
				)
			)
		)
		(pad "2" smd custom
			(at 0 0.4572 180)
			(size 0.1143 0.1143)
			(layers "B.Cu" "B.Mask" "B.Paste")
			(net "GND")
			(options
				(clearance outline)
				(anchor circle)
			)
			(primitives
				(gr_poly
					(pts
						(arc
							(start -0.254 0.1778)
							(mid -0.239121 0.213721)
							(end -0.2032 0.2286)
						)
						(arc
							(start 0.2032 0.2286)
							(mid 0.239121 0.213721)
							(end 0.254 0.1778)
						)
						(arc
							(start 0.254 -0.1778)
							(mid 0.239121 -0.213721)
							(end 0.2032 -0.2286)
						)
						(arc
							(start -0.2032 -0.2286)
							(mid -0.239121 -0.213721)
							(end -0.254 -0.1778)
						)
					)
					(width 0)
					(fill yes)
				)
			)
		)
	)
	(footprint ""
		(layer "B.Cu")
		(at 77.47 -13.462)
		(property "Reference" "C277"
			(at 0 0 0)
			(layer "B.SilkS")
			(hide yes)
			(effects
				(font
					(size 1.27 1.27)
				)
				(justify mirror)
			)
		)
		(property "Value" "SCD1U16V2KX-3GP"
			(at -1.1811 -2.7051 0)
			(unlocked yes)
			(layer "B.Fab")
			(hide yes)
			(effects
				(font
					(size 1.016 1.016)
					(thickness 0.1524)
				)
				(justify mirror)
			)
		)
		(property "Device Type" "C402H22"
			(at -1.1811 -4.2291 0)
			(unlocked yes)
			(layer "B.Fab")
			(hide yes)
			(effects
				(font
					(size 1.016 1.016)
					(thickness 0.1524)
				)
				(justify mirror)
			)
		)
		(duplicate_pad_numbers_are_jumpers no)
		(fp_rect
			(start 0.381 0.7366)
			(end -0.381 -0.7366)
			(stroke
				(width 0)
				(type default)
			)
			(fill no)
			(layer "B.CrtYd")
		)
		(fp_rect
			(start 0.381 0.7366)
			(end -0.381 -0.7366)
			(stroke
				(width 0)
				(type default)
			)
			(fill no)
			(layer "B.Fab")
		)
		(pad "1" smd custom
			(at 0 -0.4572 180)
			(size 0.1143 0.1143)
			(layers "B.Cu" "B.Mask" "B.Paste")
			(net "P2E_CPU_SAS_C_TX_DN1")
			(options
				(clearance outline)
				(anchor circle)
			)
			(primitives
				(gr_poly
					(pts
						(arc
							(start -0.254 0.1778)
							(mid -0.239121 0.213721)
							(end -0.2032 0.2286)
						)
						(arc
							(start 0.2032 0.2286)
							(mid 0.239121 0.213721)
							(end 0.254 0.1778)
						)
						(arc
							(start 0.254 -0.1778)
							(mid 0.239121 -0.213721)
							(end 0.2032 -0.2286)
						)
						(arc
							(start -0.2032 -0.2286)
							(mid -0.239121 -0.213721)
							(end -0.254 -0.1778)
						)
					)
					(width 0)
					(fill yes)
				)
			)
		)
		(pad "2" smd custom
			(at 0 0.4572 180)
			(size 0.1143 0.1143)
			(layers "B.Cu" "B.Mask" "B.Paste")
			(net "P2E_CPU_SAS_TX_DN1")
			(options
				(clearance outline)
				(anchor circle)
			)
			(primitives
				(gr_poly
					(pts
						(arc
							(start -0.254 0.1778)
							(mid -0.239121 0.213721)
							(end -0.2032 0.2286)
						)
						(arc
							(start 0.2032 0.2286)
							(mid 0.239121 0.213721)
							(end 0.254 0.1778)
						)
						(arc
							(start 0.254 -0.1778)
							(mid 0.239121 -0.213721)
							(end 0.2032 -0.2286)
						)
						(arc
							(start -0.2032 -0.2286)
							(mid -0.239121 -0.213721)
							(end -0.254 -0.1778)
						)
					)
					(width 0)
					(fill yes)
				)
			)
		)
	)
	(footprint ""
		(layer "B.Cu")
		(at 91.186 -35.941)
		(property "Reference" "C204"
			(at 0 0 0)
			(layer "B.SilkS")
			(hide yes)
			(effects
				(font
					(size 1.27 1.27)
				)
				(justify mirror)
			)
		)
		(property "Value" "SC1U10V2KX-1GP"
			(at -1.1811 -2.7051 0)
			(unlocked yes)
			(layer "B.Fab")
			(hide yes)
			(effects
				(font
					(size 1.016 1.016)
					(thickness 0.1524)
				)
				(justify mirror)
			)
		)
		(property "Device Type" "C402H22"
			(at -1.1811 -4.2291 0)
			(unlocked yes)
			(layer "B.Fab")
			(hide yes)
			(effects
				(font
					(size 1.016 1.016)
					(thickness 0.1524)
				)
				(justify mirror)
			)
		)
		(duplicate_pad_numbers_are_jumpers no)
		(fp_rect
			(start 0.381 0.7366)
			(end -0.381 -0.7366)
			(stroke
				(width 0)
				(type default)
			)
			(fill no)
			(layer "B.CrtYd")
		)
		(fp_rect
			(start 0.381 0.7366)
			(end -0.381 -0.7366)
			(stroke
				(width 0)
				(type default)
			)
			(fill no)
			(layer "B.Fab")
		)
		(pad "1" smd custom
			(at 0 -0.4572 180)
			(size 0.1143 0.1143)
			(layers "B.Cu" "B.Mask" "B.Paste")
			(net "P1V0_STBY")
			(options
				(clearance outline)
				(anchor circle)
			)
			(primitives
				(gr_poly
					(pts
						(arc
							(start -0.254 0.1778)
							(mid -0.239121 0.213721)
							(end -0.2032 0.2286)
						)
						(arc
							(start 0.2032 0.2286)
							(mid 0.239121 0.213721)
							(end 0.254 0.1778)
						)
						(arc
							(start 0.254 -0.1778)
							(mid 0.239121 -0.213721)
							(end 0.2032 -0.2286)
						)
						(arc
							(start -0.2032 -0.2286)
							(mid -0.239121 -0.213721)
							(end -0.254 -0.1778)
						)
					)
					(width 0)
					(fill yes)
				)
			)
		)
		(pad "2" smd custom
			(at 0 0.4572 180)
			(size 0.1143 0.1143)
			(layers "B.Cu" "B.Mask" "B.Paste")
			(net "GND")
			(options
				(clearance outline)
				(anchor circle)
			)
			(primitives
				(gr_poly
					(pts
						(arc
							(start -0.254 0.1778)
							(mid -0.239121 0.213721)
							(end -0.2032 0.2286)
						)
						(arc
							(start 0.2032 0.2286)
							(mid 0.239121 0.213721)
							(end 0.254 0.1778)
						)
						(arc
							(start 0.254 -0.1778)
							(mid 0.239121 -0.213721)
							(end 0.2032 -0.2286)
						)
						(arc
							(start -0.2032 -0.2286)
							(mid -0.239121 -0.213721)
							(end -0.254 -0.1778)
						)
					)
					(width 0)
					(fill yes)
				)
			)
		)
	)
	(footprint ""
		(layer "B.Cu")
		(at 78.4098 -26.1112 180)
		(property "Reference" "R407"
			(at 0 0 0)
			(layer "B.SilkS")
			(hide yes)
			(effects
				(font
					(size 1.27 1.27)
				)
				(justify mirror)
			)
		)
		(property "Value" "0R2J-2-GP"
			(at -1.7907 -1.1176 180)
			(unlocked yes)
			(layer "B.Fab")
			(hide yes)
			(effects
				(font
					(size 1.016 1.016)
					(thickness 0.1524)
				)
				(justify mirror)
			)
		)
		(property "Device Type" "R402H16"
			(at -1.7907 -2.6416 180)
			(unlocked yes)
			(layer "B.Fab")
			(hide yes)
			(effects
				(font
					(size 1.016 1.016)
					(thickness 0.1524)
				)
				(justify mirror)
			)
		)
		(duplicate_pad_numbers_are_jumpers no)
		(fp_rect
			(start 0.381 0.8382)
			(end -0.381 -0.8382)
			(stroke
				(width 0)
				(type default)
			)
			(fill no)
			(layer "B.CrtYd")
		)
		(fp_rect
			(start 0.381 0.8382)
			(end -0.381 -0.8382)
			(stroke
				(width 0)
				(type default)
			)
			(fill no)
			(layer "B.Fab")
		)
		(pad "1" smd custom
			(at 0 -0.4318)
			(size 0.127 0.127)
			(layers "B.Cu" "B.Mask" "B.Paste")
			(net "NGFF_PRESENT_R#")
			(options
				(clearance outline)
				(anchor circle)
			)
			(primitives
				(gr_poly
					(pts
						(arc
							(start -0.2032 0.2794)
							(mid -0.239121 0.264521)
							(end -0.254 0.2286)
						)
						(arc
							(start -0.254 -0.2286)
							(mid -0.239121 -0.264521)
							(end -0.2032 -0.2794)
						)
						(arc
							(start 0.2032 -0.2794)
							(mid 0.239121 -0.264521)
							(end 0.254 -0.2286)
						)
						(arc
							(start 0.254 0.2286)
							(mid 0.239121 0.264521)
							(end 0.2032 0.2794)
						)
					)
					(width 0)
					(fill yes)
				)
			)
		)
		(pad "2" smd custom
			(at 0 0.4318)
			(size 0.127 0.127)
			(layers "B.Cu" "B.Mask" "B.Paste")
			(net "NGFF_PRESENT#")
			(options
				(clearance outline)
				(anchor circle)
			)
			(primitives
				(gr_poly
					(pts
						(arc
							(start -0.2032 0.2794)
							(mid -0.239121 0.264521)
							(end -0.254 0.2286)
						)
						(arc
							(start -0.254 -0.2286)
							(mid -0.239121 -0.264521)
							(end -0.2032 -0.2794)
						)
						(arc
							(start 0.2032 -0.2794)
							(mid 0.239121 -0.264521)
							(end 0.254 -0.2286)
						)
						(arc
							(start 0.254 0.2286)
							(mid 0.239121 0.264521)
							(end 0.2032 0.2794)
						)
					)
					(width 0)
					(fill yes)
				)
			)
		)
	)
	(footprint ""
		(layer "B.Cu")
		(at 142.748 -47.498 -90)
		(property "Reference" "R76"
			(at 0 0 90)
			(layer "B.SilkS")
			(hide yes)
			(effects
				(font
					(size 1.27 1.27)
				)
				(justify mirror)
			)
		)
		(property "Value" "10KR2F-2-GP"
			(at -0.064008 -3.993896 270)
			(unlocked yes)
			(layer "B.Fab")
			(hide yes)
			(effects
				(font
					(size 1.016 1.016)
					(thickness 0.1524)
				)
				(justify mirror)
			)
		)
		(property "Device Type" "R402H16"
			(at -0.064008 -5.517896 270)
			(unlocked yes)
			(layer "B.Fab")
			(hide yes)
			(effects
				(font
					(size 1.016 1.016)
					(thickness 0.1524)
				)
				(justify mirror)
			)
		)
		(duplicate_pad_numbers_are_jumpers no)
		(fp_rect
			(start 0.381 0.8382)
			(end -0.381 -0.8382)
			(stroke
				(width 0)
				(type default)
			)
			(fill no)
			(layer "B.CrtYd")
		)
		(fp_rect
			(start 0.381 0.8382)
			(end -0.381 -0.8382)
			(stroke
				(width 0)
				(type default)
			)
			(fill no)
			(layer "B.Fab")
		)
		(pad "1" smd custom
			(at 0 -0.4318 90)
			(size 0.127 0.127)
			(layers "B.Cu" "B.Mask" "B.Paste")
			(net "P3V3_STBY")
			(options
				(clearance outline)
				(anchor circle)
			)
			(primitives
				(gr_poly
					(pts
						(arc
							(start -0.2032 0.2794)
							(mid -0.239121 0.264521)
							(end -0.254 0.2286)
						)
						(arc
							(start -0.254 -0.2286)
							(mid -0.239121 -0.264521)
							(end -0.2032 -0.2794)
						)
						(arc
							(start 0.2032 -0.2794)
							(mid 0.239121 -0.264521)
							(end 0.254 -0.2286)
						)
						(arc
							(start 0.254 0.2286)
							(mid 0.239121 0.264521)
							(end 0.2032 0.2794)
						)
					)
					(width 0)
					(fill yes)
				)
			)
		)
		(pad "2" smd custom
			(at 0 0.4318 90)
			(size 0.127 0.127)
			(layers "B.Cu" "B.Mask" "B.Paste")
			(net "JTAG_PLD_TMS")
			(options
				(clearance outline)
				(anchor circle)
			)
			(primitives
				(gr_poly
					(pts
						(arc
							(start -0.2032 0.2794)
							(mid -0.239121 0.264521)
							(end -0.254 0.2286)
						)
						(arc
							(start -0.254 -0.2286)
							(mid -0.239121 -0.264521)
							(end -0.2032 -0.2794)
						)
						(arc
							(start 0.2032 -0.2794)
							(mid 0.239121 -0.264521)
							(end 0.254 -0.2286)
						)
						(arc
							(start 0.254 0.2286)
							(mid 0.239121 0.264521)
							(end 0.2032 0.2794)
						)
					)
					(width 0)
					(fill yes)
				)
			)
		)
	)
	(footprint ""
		(layer "B.Cu")
		(at 51.308 -49.53 90)
		(property "Reference" "R83"
			(at 0 0 90)
			(layer "B.SilkS")
			(hide yes)
			(effects
				(font
					(size 1.27 1.27)
				)
				(justify mirror)
			)
		)
		(property "Value" "1KR2F-3-GP"
			(at -0.064008 -3.993896 90)
			(unlocked yes)
			(layer "B.Fab")
			(hide yes)
			(effects
				(font
					(size 1.016 1.016)
					(thickness 0.1524)
				)
				(justify mirror)
			)
		)
		(property "Device Type" "R402H16"
			(at -0.064008 -5.517896 90)
			(unlocked yes)
			(layer "B.Fab")
			(hide yes)
			(effects
				(font
					(size 1.016 1.016)
					(thickness 0.1524)
				)
				(justify mirror)
			)
		)
		(duplicate_pad_numbers_are_jumpers no)
		(fp_rect
			(start 0.381 0.8382)
			(end -0.381 -0.8382)
			(stroke
				(width 0)
				(type default)
			)
			(fill no)
			(layer "B.CrtYd")
		)
		(fp_rect
			(start 0.381 0.8382)
			(end -0.381 -0.8382)
			(stroke
				(width 0)
				(type default)
			)
			(fill no)
			(layer "B.Fab")
		)
		(pad "1" smd custom
			(at 0 -0.4318 270)
			(size 0.127 0.127)
			(layers "B.Cu" "B.Mask" "B.Paste")
			(net "CLKGEN_PCI_STOP#")
			(options
				(clearance outline)
				(anchor circle)
			)
			(primitives
				(gr_poly
					(pts
						(arc
							(start -0.2032 0.2794)
							(mid -0.239121 0.264521)
							(end -0.254 0.2286)
						)
						(arc
							(start -0.254 -0.2286)
							(mid -0.239121 -0.264521)
							(end -0.2032 -0.2794)
						)
						(arc
							(start 0.2032 -0.2794)
							(mid 0.239121 -0.264521)
							(end 0.254 -0.2286)
						)
						(arc
							(start 0.254 0.2286)
							(mid 0.239121 0.264521)
							(end 0.2032 0.2794)
						)
					)
					(width 0)
					(fill yes)
				)
			)
		)
		(pad "2" smd custom
			(at 0 0.4318 270)
			(size 0.127 0.127)
			(layers "B.Cu" "B.Mask" "B.Paste")
			(net "GND")
			(options
				(clearance outline)
				(anchor circle)
			)
			(primitives
				(gr_poly
					(pts
						(arc
							(start -0.2032 0.2794)
							(mid -0.239121 0.264521)
							(end -0.254 0.2286)
						)
						(arc
							(start -0.254 -0.2286)
							(mid -0.239121 -0.264521)
							(end -0.2032 -0.2794)
						)
						(arc
							(start 0.2032 -0.2794)
							(mid 0.239121 -0.264521)
							(end 0.254 -0.2286)
						)
						(arc
							(start 0.254 0.2286)
							(mid 0.239121 0.264521)
							(end 0.2032 0.2794)
						)
					)
					(width 0)
					(fill yes)
				)
			)
		)
	)
	(footprint ""
		(layer "B.Cu")
		(at 71.2216 -62.0776 -90)
		(property "Reference" "R159"
			(at 0 0 90)
			(layer "B.SilkS")
			(hide yes)
			(effects
				(font
					(size 1.27 1.27)
				)
				(justify mirror)
			)
		)
		(property "Value" "10KR2F-2-GP"
			(at -1.7907 -1.1176 270)
			(unlocked yes)
			(layer "B.Fab")
			(hide yes)
			(effects
				(font
					(size 1.016 1.016)
					(thickness 0.1524)
				)
				(justify mirror)
			)
		)
		(property "Device Type" "R402H16"
			(at -1.7907 -2.6416 270)
			(unlocked yes)
			(layer "B.Fab")
			(hide yes)
			(effects
				(font
					(size 1.016 1.016)
					(thickness 0.1524)
				)
				(justify mirror)
			)
		)
		(duplicate_pad_numbers_are_jumpers no)
		(fp_rect
			(start 0.381 0.8382)
			(end -0.381 -0.8382)
			(stroke
				(width 0)
				(type default)
			)
			(fill no)
			(layer "B.CrtYd")
		)
		(fp_rect
			(start 0.381 0.8382)
			(end -0.381 -0.8382)
			(stroke
				(width 0)
				(type default)
			)
			(fill no)
			(layer "B.Fab")
		)
		(pad "1" smd custom
			(at 0 -0.4318 90)
			(size 0.127 0.127)
			(layers "B.Cu" "B.Mask" "B.Paste")
			(net "P3V3_STBY")
			(options
				(clearance outline)
				(anchor circle)
			)
			(primitives
				(gr_poly
					(pts
						(arc
							(start -0.2032 0.2794)
							(mid -0.239121 0.264521)
							(end -0.254 0.2286)
						)
						(arc
							(start -0.254 -0.2286)
							(mid -0.239121 -0.264521)
							(end -0.2032 -0.2794)
						)
						(arc
							(start 0.2032 -0.2794)
							(mid 0.239121 -0.264521)
							(end 0.254 -0.2286)
						)
						(arc
							(start 0.254 0.2286)
							(mid 0.239121 0.264521)
							(end 0.2032 0.2794)
						)
					)
					(width 0)
					(fill yes)
				)
			)
		)
		(pad "2" smd custom
			(at 0 0.4318 90)
			(size 0.127 0.127)
			(layers "B.Cu" "B.Mask" "B.Paste")
			(net "P3V3_STBY_SENSE")
			(options
				(clearance outline)
				(anchor circle)
			)
			(primitives
				(gr_poly
					(pts
						(arc
							(start -0.2032 0.2794)
							(mid -0.239121 0.264521)
							(end -0.254 0.2286)
						)
						(arc
							(start -0.254 -0.2286)
							(mid -0.239121 -0.264521)
							(end -0.2032 -0.2794)
						)
						(arc
							(start 0.2032 -0.2794)
							(mid 0.239121 -0.264521)
							(end 0.254 -0.2286)
						)
						(arc
							(start 0.254 0.2286)
							(mid 0.239121 0.264521)
							(end 0.2032 0.2794)
						)
					)
					(width 0)
					(fill yes)
				)
			)
		)
	)
	(footprint ""
		(layer "B.Cu")
		(at 18.6944 -61.3918 90)
		(property "Reference" "PC1"
			(at 0 0 90)
			(layer "B.SilkS")
			(hide yes)
			(effects
				(font
					(size 1.27 1.27)
				)
				(justify mirror)
			)
		)
		(property "Value" "SC100P50V2JN-3GP"
			(at -1.8923 -1.2065 90)
			(unlocked yes)
			(layer "B.Fab")
			(hide yes)
			(effects
				(font
					(size 1.016 1.016)
					(thickness 0.1524)
				)
				(justify mirror)
			)
		)
		(property "Device Type" "C402H22"
			(at -1.8923 -2.7305 90)
			(unlocked yes)
			(layer "B.Fab")
			(hide yes)
			(effects
				(font
					(size 1.016 1.016)
					(thickness 0.1524)
				)
				(justify mirror)
			)
		)
		(duplicate_pad_numbers_are_jumpers no)
		(fp_rect
			(start 0.381 0.7366)
			(end -0.381 -0.7366)
			(stroke
				(width 0)
				(type default)
			)
			(fill no)
			(layer "B.CrtYd")
		)
		(fp_rect
			(start 0.381 0.7366)
			(end -0.381 -0.7366)
			(stroke
				(width 0)
				(type default)
			)
			(fill no)
			(layer "B.Fab")
		)
		(pad "1" smd custom
			(at 0 -0.4572 270)
			(size 0.1143 0.1143)
			(layers "B.Cu" "B.Mask" "B.Paste")
			(net "VR_PVNN_COMP")
			(options
				(clearance outline)
				(anchor circle)
			)
			(primitives
				(gr_poly
					(pts
						(arc
							(start -0.254 0.1778)
							(mid -0.239121 0.213721)
							(end -0.2032 0.2286)
						)
						(arc
							(start 0.2032 0.2286)
							(mid 0.239121 0.213721)
							(end 0.254 0.1778)
						)
						(arc
							(start 0.254 -0.1778)
							(mid 0.239121 -0.213721)
							(end 0.2032 -0.2286)
						)
						(arc
							(start -0.2032 -0.2286)
							(mid -0.239121 -0.213721)
							(end -0.254 -0.1778)
						)
					)
					(width 0)
					(fill yes)
				)
			)
		)
		(pad "2" smd custom
			(at 0 0.4572 270)
			(size 0.1143 0.1143)
			(layers "B.Cu" "B.Mask" "B.Paste")
			(net "VR_PVNN_FB")
			(options
				(clearance outline)
				(anchor circle)
			)
			(primitives
				(gr_poly
					(pts
						(arc
							(start -0.254 0.1778)
							(mid -0.239121 0.213721)
							(end -0.2032 0.2286)
						)
						(arc
							(start 0.2032 0.2286)
							(mid 0.239121 0.213721)
							(end 0.254 0.1778)
						)
						(arc
							(start 0.254 -0.1778)
							(mid 0.239121 -0.213721)
							(end 0.2032 -0.2286)
						)
						(arc
							(start -0.2032 -0.2286)
							(mid -0.239121 -0.213721)
							(end -0.254 -0.1778)
						)
					)
					(width 0)
					(fill yes)
				)
			)
		)
	)
	(footprint ""
		(layer "B.Cu")
		(at 145.669 -44.958 180)
		(property "Reference" "R77"
			(at 0 0 0)
			(layer "B.SilkS")
			(hide yes)
			(effects
				(font
					(size 1.27 1.27)
				)
				(justify mirror)
			)
		)
		(property "Value" "10KR2F-2-GP"
			(at -0.064008 -3.993896 180)
			(unlocked yes)
			(layer "B.Fab")
			(hide yes)
			(effects
				(font
					(size 1.016 1.016)
					(thickness 0.1524)
				)
				(justify mirror)
			)
		)
		(property "Device Type" "R402H16"
			(at -0.064008 -5.517896 180)
			(unlocked yes)
			(layer "B.Fab")
			(hide yes)
			(effects
				(font
					(size 1.016 1.016)
					(thickness 0.1524)
				)
				(justify mirror)
			)
		)
		(duplicate_pad_numbers_are_jumpers no)
		(fp_rect
			(start 0.381 0.8382)
			(end -0.381 -0.8382)
			(stroke
				(width 0)
				(type default)
			)
			(fill no)
			(layer "B.CrtYd")
		)
		(fp_rect
			(start 0.381 0.8382)
			(end -0.381 -0.8382)
			(stroke
				(width 0)
				(type default)
			)
			(fill no)
			(layer "B.Fab")
		)
		(pad "1" smd custom
			(at 0 -0.4318)
			(size 0.127 0.127)
			(layers "B.Cu" "B.Mask" "B.Paste")
			(net "P3V3_STBY")
			(options
				(clearance outline)
				(anchor circle)
			)
			(primitives
				(gr_poly
					(pts
						(arc
							(start -0.2032 0.2794)
							(mid -0.239121 0.264521)
							(end -0.254 0.2286)
						)
						(arc
							(start -0.254 -0.2286)
							(mid -0.239121 -0.264521)
							(end -0.2032 -0.2794)
						)
						(arc
							(start 0.2032 -0.2794)
							(mid 0.239121 -0.264521)
							(end 0.254 -0.2286)
						)
						(arc
							(start 0.254 0.2286)
							(mid 0.239121 0.264521)
							(end 0.2032 0.2794)
						)
					)
					(width 0)
					(fill yes)
				)
			)
		)
		(pad "2" smd custom
			(at 0 0.4318)
			(size 0.127 0.127)
			(layers "B.Cu" "B.Mask" "B.Paste")
			(net "JTAG_PLD_TDI")
			(options
				(clearance outline)
				(anchor circle)
			)
			(primitives
				(gr_poly
					(pts
						(arc
							(start -0.2032 0.2794)
							(mid -0.239121 0.264521)
							(end -0.254 0.2286)
						)
						(arc
							(start -0.254 -0.2286)
							(mid -0.239121 -0.264521)
							(end -0.2032 -0.2794)
						)
						(arc
							(start 0.2032 -0.2794)
							(mid 0.239121 -0.264521)
							(end 0.254 -0.2286)
						)
						(arc
							(start 0.254 0.2286)
							(mid 0.239121 0.264521)
							(end 0.2032 0.2794)
						)
					)
					(width 0)
					(fill yes)
				)
			)
		)
	)
	(footprint ""
		(layer "B.Cu")
		(at 103.378 -27.321002)
		(property "Reference" "C243"
			(at 0 0 0)
			(layer "B.SilkS")
			(hide yes)
			(effects
				(font
					(size 1.27 1.27)
				)
				(justify mirror)
			)
		)
		(property "Value" "SC1U10V2KX-1GP"
			(at -1.1811 -2.7051 0)
			(unlocked yes)
			(layer "B.Fab")
			(hide yes)
			(effects
				(font
					(size 1.016 1.016)
					(thickness 0.1524)
				)
				(justify mirror)
			)
		)
		(property "Device Type" "C402H22"
			(at -1.1811 -4.2291 0)
			(unlocked yes)
			(layer "B.Fab")
			(hide yes)
			(effects
				(font
					(size 1.016 1.016)
					(thickness 0.1524)
				)
				(justify mirror)
			)
		)
		(duplicate_pad_numbers_are_jumpers no)
		(fp_rect
			(start 0.381 0.7366)
			(end -0.381 -0.7366)
			(stroke
				(width 0)
				(type default)
			)
			(fill no)
			(layer "B.CrtYd")
		)
		(fp_rect
			(start 0.381 0.7366)
			(end -0.381 -0.7366)
			(stroke
				(width 0)
				(type default)
			)
			(fill no)
			(layer "B.Fab")
		)
		(pad "1" smd custom
			(at 0 -0.4572 180)
			(size 0.1143 0.1143)
			(layers "B.Cu" "B.Mask" "B.Paste")
			(net "PV_VDDR")
			(options
				(clearance outline)
				(anchor circle)
			)
			(primitives
				(gr_poly
					(pts
						(arc
							(start -0.254 0.1778)
							(mid -0.239121 0.213721)
							(end -0.2032 0.2286)
						)
						(arc
							(start 0.2032 0.2286)
							(mid 0.239121 0.213721)
							(end 0.254 0.1778)
						)
						(arc
							(start 0.254 -0.1778)
							(mid 0.239121 -0.213721)
							(end 0.2032 -0.2286)
						)
						(arc
							(start -0.2032 -0.2286)
							(mid -0.239121 -0.213721)
							(end -0.254 -0.1778)
						)
					)
					(width 0)
					(fill yes)
				)
			)
		)
		(pad "2" smd custom
			(at 0 0.4572 180)
			(size 0.1143 0.1143)
			(layers "B.Cu" "B.Mask" "B.Paste")
			(net "GND")
			(options
				(clearance outline)
				(anchor circle)
			)
			(primitives
				(gr_poly
					(pts
						(arc
							(start -0.254 0.1778)
							(mid -0.239121 0.213721)
							(end -0.2032 0.2286)
						)
						(arc
							(start 0.2032 0.2286)
							(mid 0.239121 0.213721)
							(end 0.254 0.1778)
						)
						(arc
							(start 0.254 -0.1778)
							(mid 0.239121 -0.213721)
							(end 0.2032 -0.2286)
						)
						(arc
							(start -0.2032 -0.2286)
							(mid -0.239121 -0.213721)
							(end -0.254 -0.1778)
						)
					)
					(width 0)
					(fill yes)
				)
			)
		)
	)
	(footprint ""
		(layer "B.Cu")
		(at 27.813 -43.053)
		(property "Reference" "PC134"
			(at 0 0 0)
			(layer "B.SilkS")
			(hide yes)
			(effects
				(font
					(size 1.27 1.27)
				)
				(justify mirror)
			)
		)
		(property "Value" "SC10U6D3V5KX-4GP"
			(at 0 -4.9022 0)
			(unlocked yes)
			(layer "B.Fab")
			(hide yes)
			(effects
				(font
					(size 1.016 1.016)
					(thickness 0.1524)
				)
				(justify mirror)
			)
		)
		(property "Device Type" "C805H58"
			(at 0 -6.8072 0)
			(unlocked yes)
			(layer "B.Fab")
			(hide yes)
			(effects
				(font
					(size 1.016 1.016)
					(thickness 0.1524)
				)
				(justify mirror)
			)
		)
		(duplicate_pad_numbers_are_jumpers no)
		(fp_line
			(start -0.6096 0)
			(end 0.6096 0)
			(stroke
				(width 0.3048)
				(type default)
			)
			(layer "B.SilkS")
		)
		(fp_poly
			(pts
				(xy 0.9017 1.4351) (xy -0.9017 1.4351) (xy -0.9017 -1.4351) (xy 0.9017 -1.4351)
			)
			(stroke
				(width 0)
				(type default)
			)
			(fill no)
			(layer "B.CrtYd")
		)
		(fp_poly
			(pts
				(xy -0.9017 1.4351) (xy -0.9017 -1.4351) (xy 0.9017 -1.4351) (xy 0.9017 1.4351)
			)
			(stroke
				(width 0)
				(type default)
			)
			(fill no)
			(layer "B.Fab")
		)
		(pad "1" smd rect
			(at 0 -0.8382 180)
			(size 1.5494 0.9398)
			(layers "B.Cu" "B.Mask" "B.Paste")
			(net "P1V5_STBY_OUT")
		)
		(pad "2" smd rect
			(at 0 0.8382 180)
			(size 1.5494 0.9398)
			(layers "B.Cu" "B.Mask" "B.Paste")
			(net "GND")
		)
	)
	(footprint ""
		(layer "B.Cu")
		(at 92.71 -67.564)
		(property "Reference" "PC19"
			(at 0 0 0)
			(layer "B.SilkS")
			(hide yes)
			(effects
				(font
					(size 1.27 1.27)
				)
				(justify mirror)
			)
		)
		(property "Value" "SC22U10V6KX-GP"
			(at 0.0762 -5.1308 0)
			(unlocked yes)
			(layer "B.Fab")
			(hide yes)
			(effects
				(font
					(size 1.016 1.016)
					(thickness 0.1524)
				)
				(justify mirror)
			)
		)
		(property "Device Type" "C1206H71"
			(at 0.127 -6.6548 0)
			(unlocked yes)
			(layer "B.Fab")
			(hide yes)
			(effects
				(font
					(size 1.016 1.016)
					(thickness 0.1524)
				)
				(justify mirror)
			)
		)
		(duplicate_pad_numbers_are_jumpers no)
		(fp_rect
			(start 1.0541 1.9812)
			(end -1.0541 -1.9812)
			(stroke
				(width 0)
				(type default)
			)
			(fill no)
			(layer "B.CrtYd")
		)
		(fp_rect
			(start 1.0541 1.9812)
			(end -1.0541 -1.9812)
			(stroke
				(width 0)
				(type default)
			)
			(fill no)
			(layer "B.Fab")
		)
		(pad "1" smd rect
			(at 0 -1.3462 180)
			(size 1.8542 1.016)
			(layers "B.Cu" "B.Mask" "B.Paste")
			(net "VR_P1V1_PVIN")
		)
		(pad "2" smd rect
			(at 0 1.3462 180)
			(size 1.8542 1.016)
			(layers "B.Cu" "B.Mask" "B.Paste")
			(net "GND")
		)
	)
	(footprint ""
		(layer "B.Cu")
		(at 31.877 -33.6804)
		(property "Reference" "TP61"
			(at 0 0 0)
			(layer "B.SilkS")
			(hide yes)
			(effects
				(font
					(size 1.27 1.27)
				)
				(justify mirror)
			)
		)
		(property "Value" "TPAD32-GP"
			(at 0 -3.166364 0)
			(unlocked yes)
			(layer "B.Fab")
			(hide yes)
			(effects
				(font
					(size 1.016 1.016)
					(thickness 0.1524)
				)
				(justify mirror)
			)
		)
		(property "Device Type" "TPAD32"
			(at 0 -4.690618 0)
			(unlocked yes)
			(layer "B.Fab")
			(hide yes)
			(effects
				(font
					(size 1.016 1.016)
					(thickness 0.1524)
				)
				(justify mirror)
			)
		)
		(duplicate_pad_numbers_are_jumpers no)
		(fp_poly
			(pts
				(arc
					(start 0.7112 0)
					(mid -0.7112 0)
					(end 0.7112 0)
				)
			)
			(stroke
				(width 0)
				(type default)
			)
			(fill no)
			(layer "B.CrtYd")
		)
		(fp_poly
			(pts
				(arc
					(start 0.7112 0)
					(mid -0.7112 0)
					(end 0.7112 0)
				)
			)
			(stroke
				(width 0)
				(type default)
			)
			(fill no)
			(layer "B.Fab")
		)
		(pad "1" smd circle
			(at 0 0 180)
			(size 0.8128 0.8128)
			(layers "B.Cu" "B.Mask" "B.Paste")
			(net "XDP_SOC_CPU_TDO")
		)
	)
	(footprint ""
		(layer "B.Cu")
		(at 98.933 -40.071802)
		(property "Reference" "C180"
			(at 0 0 0)
			(layer "B.SilkS")
			(hide yes)
			(effects
				(font
					(size 1.27 1.27)
				)
				(justify mirror)
			)
		)
		(property "Value" "SC1U10V2KX-1GP"
			(at -1.1811 -2.7051 0)
			(unlocked yes)
			(layer "B.Fab")
			(hide yes)
			(effects
				(font
					(size 1.016 1.016)
					(thickness 0.1524)
				)
				(justify mirror)
			)
		)
		(property "Device Type" "C402H22"
			(at -1.1811 -4.2291 0)
			(unlocked yes)
			(layer "B.Fab")
			(hide yes)
			(effects
				(font
					(size 1.016 1.016)
					(thickness 0.1524)
				)
				(justify mirror)
			)
		)
		(duplicate_pad_numbers_are_jumpers no)
		(fp_rect
			(start 0.381 0.7366)
			(end -0.381 -0.7366)
			(stroke
				(width 0)
				(type default)
			)
			(fill no)
			(layer "B.CrtYd")
		)
		(fp_rect
			(start 0.381 0.7366)
			(end -0.381 -0.7366)
			(stroke
				(width 0)
				(type default)
			)
			(fill no)
			(layer "B.Fab")
		)
		(pad "1" smd custom
			(at 0 -0.4572 180)
			(size 0.1143 0.1143)
			(layers "B.Cu" "B.Mask" "B.Paste")
			(net "P1V0")
			(options
				(clearance outline)
				(anchor circle)
			)
			(primitives
				(gr_poly
					(pts
						(arc
							(start -0.254 0.1778)
							(mid -0.239121 0.213721)
							(end -0.2032 0.2286)
						)
						(arc
							(start 0.2032 0.2286)
							(mid 0.239121 0.213721)
							(end 0.254 0.1778)
						)
						(arc
							(start 0.254 -0.1778)
							(mid 0.239121 -0.213721)
							(end 0.2032 -0.2286)
						)
						(arc
							(start -0.2032 -0.2286)
							(mid -0.239121 -0.213721)
							(end -0.254 -0.1778)
						)
					)
					(width 0)
					(fill yes)
				)
			)
		)
		(pad "2" smd custom
			(at 0 0.4572 180)
			(size 0.1143 0.1143)
			(layers "B.Cu" "B.Mask" "B.Paste")
			(net "GND")
			(options
				(clearance outline)
				(anchor circle)
			)
			(primitives
				(gr_poly
					(pts
						(arc
							(start -0.254 0.1778)
							(mid -0.239121 0.213721)
							(end -0.2032 0.2286)
						)
						(arc
							(start 0.2032 0.2286)
							(mid 0.239121 0.213721)
							(end 0.254 0.1778)
						)
						(arc
							(start 0.254 -0.1778)
							(mid 0.239121 -0.213721)
							(end 0.2032 -0.2286)
						)
						(arc
							(start -0.2032 -0.2286)
							(mid -0.239121 -0.213721)
							(end -0.254 -0.1778)
						)
					)
					(width 0)
					(fill yes)
				)
			)
		)
	)
	(footprint ""
		(layer "B.Cu")
		(at 86.106 -19.939 -90)
		(property "Reference" "PC197"
			(at 0 0 90)
			(layer "B.SilkS")
			(hide yes)
			(effects
				(font
					(size 1.27 1.27)
				)
				(justify mirror)
			)
		)
		(property "Value" "SC1KP50V2KX-1GP"
			(at -1.1811 -2.7051 270)
			(unlocked yes)
			(layer "B.Fab")
			(hide yes)
			(effects
				(font
					(size 1.016 1.016)
					(thickness 0.1524)
				)
				(justify mirror)
			)
		)
		(property "Device Type" "C402H22"
			(at -1.1811 -4.2291 270)
			(unlocked yes)
			(layer "B.Fab")
			(hide yes)
			(effects
				(font
					(size 1.016 1.016)
					(thickness 0.1524)
				)
				(justify mirror)
			)
		)
		(duplicate_pad_numbers_are_jumpers no)
		(fp_rect
			(start 0.381 0.7366)
			(end -0.381 -0.7366)
			(stroke
				(width 0)
				(type default)
			)
			(fill no)
			(layer "B.CrtYd")
		)
		(fp_rect
			(start 0.381 0.7366)
			(end -0.381 -0.7366)
			(stroke
				(width 0)
				(type default)
			)
			(fill no)
			(layer "B.Fab")
		)
		(pad "1" smd custom
			(at 0 -0.4572 90)
			(size 0.1143 0.1143)
			(layers "B.Cu" "B.Mask" "B.Paste")
			(net "TPS74801_1V35_OUT")
			(options
				(clearance outline)
				(anchor circle)
			)
			(primitives
				(gr_poly
					(pts
						(arc
							(start -0.254 0.1778)
							(mid -0.239121 0.213721)
							(end -0.2032 0.2286)
						)
						(arc
							(start 0.2032 0.2286)
							(mid 0.239121 0.213721)
							(end 0.254 0.1778)
						)
						(arc
							(start 0.254 -0.1778)
							(mid 0.239121 -0.213721)
							(end 0.2032 -0.2286)
						)
						(arc
							(start -0.2032 -0.2286)
							(mid -0.239121 -0.213721)
							(end -0.254 -0.1778)
						)
					)
					(width 0)
					(fill yes)
				)
			)
		)
		(pad "2" smd custom
			(at 0 0.4572 90)
			(size 0.1143 0.1143)
			(layers "B.Cu" "B.Mask" "B.Paste")
			(net "TPS74801_1V35_FB")
			(options
				(clearance outline)
				(anchor circle)
			)
			(primitives
				(gr_poly
					(pts
						(arc
							(start -0.254 0.1778)
							(mid -0.239121 0.213721)
							(end -0.2032 0.2286)
						)
						(arc
							(start 0.2032 0.2286)
							(mid 0.239121 0.213721)
							(end 0.254 0.1778)
						)
						(arc
							(start 0.254 -0.1778)
							(mid 0.239121 -0.213721)
							(end 0.2032 -0.2286)
						)
						(arc
							(start -0.2032 -0.2286)
							(mid -0.239121 -0.213721)
							(end -0.254 -0.1778)
						)
					)
					(width 0)
					(fill yes)
				)
			)
		)
	)
	(footprint ""
		(layer "B.Cu")
		(at 85.852 -43.561 -90)
		(property "Reference" "TP25"
			(at 0 0 90)
			(layer "B.SilkS")
			(hide yes)
			(effects
				(font
					(size 1.27 1.27)
				)
				(justify mirror)
			)
		)
		(property "Value" "TPAD24"
			(at 0 -2.9972 270)
			(unlocked yes)
			(layer "B.Fab")
			(hide yes)
			(effects
				(font
					(size 1.016 1.016)
					(thickness 0.1524)
				)
				(justify mirror)
			)
		)
		(property "Device Type" "TPAD24"
			(at 0 -4.5212 270)
			(unlocked yes)
			(layer "B.Fab")
			(hide yes)
			(effects
				(font
					(size 1.016 1.016)
					(thickness 0.1524)
				)
				(justify mirror)
			)
		)
		(duplicate_pad_numbers_are_jumpers no)
		(fp_poly
			(pts
				(arc
					(start 0 -0.3048)
					(mid 0 0.3048)
					(end 0 -0.3048)
				)
			)
			(stroke
				(width 0)
				(type default)
			)
			(fill no)
			(layer "B.CrtYd")
		)
		(fp_poly
			(pts
				(arc
					(start 0 -0.6096)
					(mid 0 0.6096)
					(end 0 -0.6096)
				)
			)
			(stroke
				(width 0)
				(type default)
			)
			(fill no)
			(layer "B.Fab")
		)
		(pad "1" smd circle
			(at 0 0 90)
			(size 0.6096 0.6096)
			(layers "B.Cu" "B.Mask" "B.Paste")
			(net "TP_CPU_RSVD1")
		)
	)
	(footprint ""
		(layer "B.Cu")
		(at 186.6138 -28.4226 90)
		(property "Reference" "PC189"
			(at 0 0 90)
			(layer "B.SilkS")
			(hide yes)
			(effects
				(font
					(size 1.27 1.27)
				)
				(justify mirror)
			)
		)
		(property "Value" "SCD33U6D3V2KX-1-GP"
			(at -1.8923 -1.2065 90)
			(unlocked yes)
			(layer "B.Fab")
			(hide yes)
			(effects
				(font
					(size 1.016 1.016)
					(thickness 0.1524)
				)
				(justify mirror)
			)
		)
		(property "Device Type" "C402H22"
			(at -1.8923 -2.7305 90)
			(unlocked yes)
			(layer "B.Fab")
			(hide yes)
			(effects
				(font
					(size 1.016 1.016)
					(thickness 0.1524)
				)
				(justify mirror)
			)
		)
		(duplicate_pad_numbers_are_jumpers no)
		(fp_rect
			(start 0.381 0.7366)
			(end -0.381 -0.7366)
			(stroke
				(width 0)
				(type default)
			)
			(fill no)
			(layer "B.CrtYd")
		)
		(fp_rect
			(start 0.381 0.7366)
			(end -0.381 -0.7366)
			(stroke
				(width 0)
				(type default)
			)
			(fill no)
			(layer "B.Fab")
		)
		(pad "1" smd custom
			(at 0 -0.4572 270)
			(size 0.1143 0.1143)
			(layers "B.Cu" "B.Mask" "B.Paste")
			(net "VR_PVDDRA_ISUMP1")
			(options
				(clearance outline)
				(anchor circle)
			)
			(primitives
				(gr_poly
					(pts
						(arc
							(start -0.254 0.1778)
							(mid -0.239121 0.213721)
							(end -0.2032 0.2286)
						)
						(arc
							(start 0.2032 0.2286)
							(mid 0.239121 0.213721)
							(end 0.254 0.1778)
						)
						(arc
							(start 0.254 -0.1778)
							(mid 0.239121 -0.213721)
							(end 0.2032 -0.2286)
						)
						(arc
							(start -0.2032 -0.2286)
							(mid -0.239121 -0.213721)
							(end -0.254 -0.1778)
						)
					)
					(width 0)
					(fill yes)
				)
			)
		)
		(pad "2" smd custom
			(at 0 0.4572 270)
			(size 0.1143 0.1143)
			(layers "B.Cu" "B.Mask" "B.Paste")
			(net "VR_PVDDRA_ISUMN1")
			(options
				(clearance outline)
				(anchor circle)
			)
			(primitives
				(gr_poly
					(pts
						(arc
							(start -0.254 0.1778)
							(mid -0.239121 0.213721)
							(end -0.2032 0.2286)
						)
						(arc
							(start 0.2032 0.2286)
							(mid 0.239121 0.213721)
							(end 0.254 0.1778)
						)
						(arc
							(start 0.254 -0.1778)
							(mid 0.239121 -0.213721)
							(end 0.2032 -0.2286)
						)
						(arc
							(start -0.2032 -0.2286)
							(mid -0.239121 -0.213721)
							(end -0.254 -0.1778)
						)
					)
					(width 0)
					(fill yes)
				)
			)
		)
	)
	(footprint ""
		(layer "B.Cu")
		(at 133.731 -31.877 90)
		(property "Reference" "C137"
			(at 0 0 90)
			(layer "B.SilkS")
			(hide yes)
			(effects
				(font
					(size 1.27 1.27)
				)
				(justify mirror)
			)
		)
		(property "Value" "SC1U6D3V2KX-GP"
			(at -1.1811 -2.7051 90)
			(unlocked yes)
			(layer "B.Fab")
			(hide yes)
			(effects
				(font
					(size 1.016 1.016)
					(thickness 0.1524)
				)
				(justify mirror)
			)
		)
		(property "Device Type" "C402H22"
			(at -1.1811 -4.2291 90)
			(unlocked yes)
			(layer "B.Fab")
			(hide yes)
			(effects
				(font
					(size 1.016 1.016)
					(thickness 0.1524)
				)
				(justify mirror)
			)
		)
		(duplicate_pad_numbers_are_jumpers no)
		(fp_rect
			(start 0.381 0.7366)
			(end -0.381 -0.7366)
			(stroke
				(width 0)
				(type default)
			)
			(fill no)
			(layer "B.CrtYd")
		)
		(fp_rect
			(start 0.381 0.7366)
			(end -0.381 -0.7366)
			(stroke
				(width 0)
				(type default)
			)
			(fill no)
			(layer "B.Fab")
		)
		(pad "1" smd custom
			(at 0 -0.4572 270)
			(size 0.1143 0.1143)
			(layers "B.Cu" "B.Mask" "B.Paste")
			(net "GND")
			(options
				(clearance outline)
				(anchor circle)
			)
			(primitives
				(gr_poly
					(pts
						(arc
							(start -0.254 0.1778)
							(mid -0.239121 0.213721)
							(end -0.2032 0.2286)
						)
						(arc
							(start 0.2032 0.2286)
							(mid 0.239121 0.213721)
							(end 0.254 0.1778)
						)
						(arc
							(start 0.254 -0.1778)
							(mid 0.239121 -0.213721)
							(end 0.2032 -0.2286)
						)
						(arc
							(start -0.2032 -0.2286)
							(mid -0.239121 -0.213721)
							(end -0.254 -0.1778)
						)
					)
					(width 0)
					(fill yes)
				)
			)
		)
		(pad "2" smd custom
			(at 0 0.4572 270)
			(size 0.1143 0.1143)
			(layers "B.Cu" "B.Mask" "B.Paste")
			(net "P3V3_STBY")
			(options
				(clearance outline)
				(anchor circle)
			)
			(primitives
				(gr_poly
					(pts
						(arc
							(start -0.254 0.1778)
							(mid -0.239121 0.213721)
							(end -0.2032 0.2286)
						)
						(arc
							(start 0.2032 0.2286)
							(mid 0.239121 0.213721)
							(end 0.254 0.1778)
						)
						(arc
							(start 0.254 -0.1778)
							(mid 0.239121 -0.213721)
							(end 0.2032 -0.2286)
						)
						(arc
							(start -0.2032 -0.2286)
							(mid -0.239121 -0.213721)
							(end -0.254 -0.1778)
						)
					)
					(width 0)
					(fill yes)
				)
			)
		)
	)
	(footprint ""
		(layer "B.Cu")
		(at 15.494 -34.798 180)
		(property "Reference" "PR195"
			(at 0 0 0)
			(layer "B.SilkS")
			(hide yes)
			(effects
				(font
					(size 1.27 1.27)
				)
				(justify mirror)
			)
		)
		(property "Value" "15KR2F-GP"
			(at -1.7907 -1.1176 180)
			(unlocked yes)
			(layer "B.Fab")
			(hide yes)
			(effects
				(font
					(size 1.016 1.016)
					(thickness 0.1524)
				)
				(justify mirror)
			)
		)
		(property "Device Type" "R402H16"
			(at -1.7907 -2.6416 180)
			(unlocked yes)
			(layer "B.Fab")
			(hide yes)
			(effects
				(font
					(size 1.016 1.016)
					(thickness 0.1524)
				)
				(justify mirror)
			)
		)
		(duplicate_pad_numbers_are_jumpers no)
		(fp_rect
			(start 0.381 0.8382)
			(end -0.381 -0.8382)
			(stroke
				(width 0)
				(type default)
			)
			(fill no)
			(layer "B.CrtYd")
		)
		(fp_rect
			(start 0.381 0.8382)
			(end -0.381 -0.8382)
			(stroke
				(width 0)
				(type default)
			)
			(fill no)
			(layer "B.Fab")
		)
		(pad "1" smd custom
			(at 0 -0.4318)
			(size 0.127 0.127)
			(layers "B.Cu" "B.Mask" "B.Paste")
			(net "P3V3_STBY_PG")
			(options
				(clearance outline)
				(anchor circle)
			)
			(primitives
				(gr_poly
					(pts
						(arc
							(start -0.2032 0.2794)
							(mid -0.239121 0.264521)
							(end -0.254 0.2286)
						)
						(arc
							(start -0.254 -0.2286)
							(mid -0.239121 -0.264521)
							(end -0.2032 -0.2794)
						)
						(arc
							(start 0.2032 -0.2794)
							(mid 0.239121 -0.264521)
							(end 0.254 -0.2286)
						)
						(arc
							(start 0.254 0.2286)
							(mid 0.239121 0.264521)
							(end 0.2032 0.2794)
						)
					)
					(width 0)
					(fill yes)
				)
			)
		)
		(pad "2" smd custom
			(at 0 0.4318)
			(size 0.127 0.127)
			(layers "B.Cu" "B.Mask" "B.Paste")
			(net "GND")
			(options
				(clearance outline)
				(anchor circle)
			)
			(primitives
				(gr_poly
					(pts
						(arc
							(start -0.2032 0.2794)
							(mid -0.239121 0.264521)
							(end -0.254 0.2286)
						)
						(arc
							(start -0.254 -0.2286)
							(mid -0.239121 -0.264521)
							(end -0.2032 -0.2794)
						)
						(arc
							(start 0.2032 -0.2794)
							(mid 0.239121 -0.264521)
							(end 0.254 -0.2286)
						)
						(arc
							(start 0.254 0.2286)
							(mid 0.239121 0.264521)
							(end 0.2032 0.2794)
						)
					)
					(width 0)
					(fill yes)
				)
			)
		)
	)
	(footprint ""
		(layer "B.Cu")
		(at 89.662 -37.592 180)
		(property "Reference" "C190"
			(at 0 0 0)
			(layer "B.SilkS")
			(hide yes)
			(effects
				(font
					(size 1.27 1.27)
				)
				(justify mirror)
			)
		)
		(property "Value" "SC1U10V2KX-1GP"
			(at -1.1811 -2.7051 180)
			(unlocked yes)
			(layer "B.Fab")
			(hide yes)
			(effects
				(font
					(size 1.016 1.016)
					(thickness 0.1524)
				)
				(justify mirror)
			)
		)
		(property "Device Type" "C402H22"
			(at -1.1811 -4.2291 180)
			(unlocked yes)
			(layer "B.Fab")
			(hide yes)
			(effects
				(font
					(size 1.016 1.016)
					(thickness 0.1524)
				)
				(justify mirror)
			)
		)
		(duplicate_pad_numbers_are_jumpers no)
		(fp_rect
			(start 0.381 0.7366)
			(end -0.381 -0.7366)
			(stroke
				(width 0)
				(type default)
			)
			(fill no)
			(layer "B.CrtYd")
		)
		(fp_rect
			(start 0.381 0.7366)
			(end -0.381 -0.7366)
			(stroke
				(width 0)
				(type default)
			)
			(fill no)
			(layer "B.Fab")
		)
		(pad "1" smd custom
			(at 0 -0.4572)
			(size 0.1143 0.1143)
			(layers "B.Cu" "B.Mask" "B.Paste")
			(net "P3V3_CPU")
			(options
				(clearance outline)
				(anchor circle)
			)
			(primitives
				(gr_poly
					(pts
						(arc
							(start -0.254 0.1778)
							(mid -0.239121 0.213721)
							(end -0.2032 0.2286)
						)
						(arc
							(start 0.2032 0.2286)
							(mid 0.239121 0.213721)
							(end 0.254 0.1778)
						)
						(arc
							(start 0.254 -0.1778)
							(mid 0.239121 -0.213721)
							(end 0.2032 -0.2286)
						)
						(arc
							(start -0.2032 -0.2286)
							(mid -0.239121 -0.213721)
							(end -0.254 -0.1778)
						)
					)
					(width 0)
					(fill yes)
				)
			)
		)
		(pad "2" smd custom
			(at 0 0.4572)
			(size 0.1143 0.1143)
			(layers "B.Cu" "B.Mask" "B.Paste")
			(net "GND")
			(options
				(clearance outline)
				(anchor circle)
			)
			(primitives
				(gr_poly
					(pts
						(arc
							(start -0.254 0.1778)
							(mid -0.239121 0.213721)
							(end -0.2032 0.2286)
						)
						(arc
							(start 0.2032 0.2286)
							(mid 0.239121 0.213721)
							(end 0.254 0.1778)
						)
						(arc
							(start 0.254 -0.1778)
							(mid 0.239121 -0.213721)
							(end 0.2032 -0.2286)
						)
						(arc
							(start -0.2032 -0.2286)
							(mid -0.239121 -0.213721)
							(end -0.254 -0.1778)
						)
					)
					(width 0)
					(fill yes)
				)
			)
		)
	)
	(footprint ""
		(layer "B.Cu")
		(at 91.186 -44.577)
		(property "Reference" "C154"
			(at 0 0 0)
			(layer "B.SilkS")
			(hide yes)
			(effects
				(font
					(size 1.27 1.27)
				)
				(justify mirror)
			)
		)
		(property "Value" "SCD1U16V2JX-1-GP"
			(at -1.1811 -2.7051 0)
			(unlocked yes)
			(layer "B.Fab")
			(hide yes)
			(effects
				(font
					(size 1.016 1.016)
					(thickness 0.1524)
				)
				(justify mirror)
			)
		)
		(property "Device Type" "C402H22"
			(at -1.1811 -4.2291 0)
			(unlocked yes)
			(layer "B.Fab")
			(hide yes)
			(effects
				(font
					(size 1.016 1.016)
					(thickness 0.1524)
				)
				(justify mirror)
			)
		)
		(duplicate_pad_numbers_are_jumpers no)
		(fp_rect
			(start 0.381 0.7366)
			(end -0.381 -0.7366)
			(stroke
				(width 0)
				(type default)
			)
			(fill no)
			(layer "B.CrtYd")
		)
		(fp_rect
			(start 0.381 0.7366)
			(end -0.381 -0.7366)
			(stroke
				(width 0)
				(type default)
			)
			(fill no)
			(layer "B.Fab")
		)
		(pad "1" smd custom
			(at 0 -0.4572 180)
			(size 0.1143 0.1143)
			(layers "B.Cu" "B.Mask" "B.Paste")
			(net "P3V3_CPU")
			(options
				(clearance outline)
				(anchor circle)
			)
			(primitives
				(gr_poly
					(pts
						(arc
							(start -0.254 0.1778)
							(mid -0.239121 0.213721)
							(end -0.2032 0.2286)
						)
						(arc
							(start 0.2032 0.2286)
							(mid 0.239121 0.213721)
							(end 0.254 0.1778)
						)
						(arc
							(start 0.254 -0.1778)
							(mid 0.239121 -0.213721)
							(end 0.2032 -0.2286)
						)
						(arc
							(start -0.2032 -0.2286)
							(mid -0.239121 -0.213721)
							(end -0.254 -0.1778)
						)
					)
					(width 0)
					(fill yes)
				)
			)
		)
		(pad "2" smd custom
			(at 0 0.4572 180)
			(size 0.1143 0.1143)
			(layers "B.Cu" "B.Mask" "B.Paste")
			(net "GND")
			(options
				(clearance outline)
				(anchor circle)
			)
			(primitives
				(gr_poly
					(pts
						(arc
							(start -0.254 0.1778)
							(mid -0.239121 0.213721)
							(end -0.2032 0.2286)
						)
						(arc
							(start 0.2032 0.2286)
							(mid 0.239121 0.213721)
							(end 0.254 0.1778)
						)
						(arc
							(start 0.254 -0.1778)
							(mid 0.239121 -0.213721)
							(end 0.2032 -0.2286)
						)
						(arc
							(start -0.2032 -0.2286)
							(mid -0.239121 -0.213721)
							(end -0.254 -0.1778)
						)
					)
					(width 0)
					(fill yes)
				)
			)
		)
	)
	(footprint ""
		(layer "B.Cu")
		(at 110.617 -4.445 -90)
		(property "Reference" "C337"
			(at 0 0 90)
			(layer "B.SilkS")
			(hide yes)
			(effects
				(font
					(size 1.27 1.27)
				)
				(justify mirror)
			)
		)
		(property "Value" "SCD1U10V2KX-5GP"
			(at -1.8923 -1.2065 270)
			(unlocked yes)
			(layer "B.Fab")
			(hide yes)
			(effects
				(font
					(size 1.016 1.016)
					(thickness 0.1524)
				)
				(justify mirror)
			)
		)
		(property "Device Type" "C402H22"
			(at -1.8923 -2.7305 270)
			(unlocked yes)
			(layer "B.Fab")
			(hide yes)
			(effects
				(font
					(size 1.016 1.016)
					(thickness 0.1524)
				)
				(justify mirror)
			)
		)
		(duplicate_pad_numbers_are_jumpers no)
		(fp_rect
			(start 0.381 0.7366)
			(end -0.381 -0.7366)
			(stroke
				(width 0)
				(type default)
			)
			(fill no)
			(layer "B.CrtYd")
		)
		(fp_rect
			(start 0.381 0.7366)
			(end -0.381 -0.7366)
			(stroke
				(width 0)
				(type default)
			)
			(fill no)
			(layer "B.Fab")
		)
		(pad "1" smd custom
			(at 0 -0.4572 90)
			(size 0.1143 0.1143)
			(layers "B.Cu" "B.Mask" "B.Paste")
			(net "P3V3")
			(options
				(clearance outline)
				(anchor circle)
			)
			(primitives
				(gr_poly
					(pts
						(arc
							(start -0.254 0.1778)
							(mid -0.239121 0.213721)
							(end -0.2032 0.2286)
						)
						(arc
							(start 0.2032 0.2286)
							(mid 0.239121 0.213721)
							(end 0.254 0.1778)
						)
						(arc
							(start 0.254 -0.1778)
							(mid 0.239121 -0.213721)
							(end 0.2032 -0.2286)
						)
						(arc
							(start -0.2032 -0.2286)
							(mid -0.239121 -0.213721)
							(end -0.254 -0.1778)
						)
					)
					(width 0)
					(fill yes)
				)
			)
		)
		(pad "2" smd custom
			(at 0 0.4572 90)
			(size 0.1143 0.1143)
			(layers "B.Cu" "B.Mask" "B.Paste")
			(net "GND")
			(options
				(clearance outline)
				(anchor circle)
			)
			(primitives
				(gr_poly
					(pts
						(arc
							(start -0.254 0.1778)
							(mid -0.239121 0.213721)
							(end -0.2032 0.2286)
						)
						(arc
							(start 0.2032 0.2286)
							(mid 0.239121 0.213721)
							(end 0.254 0.1778)
						)
						(arc
							(start 0.254 -0.1778)
							(mid 0.239121 -0.213721)
							(end 0.2032 -0.2286)
						)
						(arc
							(start -0.2032 -0.2286)
							(mid -0.239121 -0.213721)
							(end -0.254 -0.1778)
						)
					)
					(width 0)
					(fill yes)
				)
			)
		)
	)
	(footprint ""
		(layer "B.Cu")
		(at 69.3928 -35.9156 -90)
		(property "Reference" "R405"
			(at 0 0 90)
			(layer "B.SilkS")
			(hide yes)
			(effects
				(font
					(size 1.27 1.27)
				)
				(justify mirror)
			)
		)
		(property "Value" "220KR2F-GP"
			(at -1.7907 -1.1176 270)
			(unlocked yes)
			(layer "B.Fab")
			(hide yes)
			(effects
				(font
					(size 1.016 1.016)
					(thickness 0.1524)
				)
				(justify mirror)
			)
		)
		(property "Device Type" "R402H16"
			(at -1.7907 -2.6416 270)
			(unlocked yes)
			(layer "B.Fab")
			(hide yes)
			(effects
				(font
					(size 1.016 1.016)
					(thickness 0.1524)
				)
				(justify mirror)
			)
		)
		(duplicate_pad_numbers_are_jumpers no)
		(fp_rect
			(start 0.381 0.8382)
			(end -0.381 -0.8382)
			(stroke
				(width 0)
				(type default)
			)
			(fill no)
			(layer "B.CrtYd")
		)
		(fp_rect
			(start 0.381 0.8382)
			(end -0.381 -0.8382)
			(stroke
				(width 0)
				(type default)
			)
			(fill no)
			(layer "B.Fab")
		)
		(pad "1" smd custom
			(at 0 -0.4318 90)
			(size 0.127 0.127)
			(layers "B.Cu" "B.Mask" "B.Paste")
			(net "SRTCRST_BUF_IN#")
			(options
				(clearance outline)
				(anchor circle)
			)
			(primitives
				(gr_poly
					(pts
						(arc
							(start -0.2032 0.2794)
							(mid -0.239121 0.264521)
							(end -0.254 0.2286)
						)
						(arc
							(start -0.254 -0.2286)
							(mid -0.239121 -0.264521)
							(end -0.2032 -0.2794)
						)
						(arc
							(start 0.2032 -0.2794)
							(mid 0.239121 -0.264521)
							(end 0.254 -0.2286)
						)
						(arc
							(start 0.254 0.2286)
							(mid 0.239121 0.264521)
							(end 0.2032 0.2794)
						)
					)
					(width 0)
					(fill yes)
				)
			)
		)
		(pad "2" smd custom
			(at 0 0.4318 90)
			(size 0.127 0.127)
			(layers "B.Cu" "B.Mask" "B.Paste")
			(net "GND")
			(options
				(clearance outline)
				(anchor circle)
			)
			(primitives
				(gr_poly
					(pts
						(arc
							(start -0.2032 0.2794)
							(mid -0.239121 0.264521)
							(end -0.254 0.2286)
						)
						(arc
							(start -0.254 -0.2286)
							(mid -0.239121 -0.264521)
							(end -0.2032 -0.2794)
						)
						(arc
							(start 0.2032 -0.2794)
							(mid 0.239121 -0.264521)
							(end 0.254 -0.2286)
						)
						(arc
							(start 0.254 0.2286)
							(mid 0.239121 0.264521)
							(end 0.2032 0.2794)
						)
					)
					(width 0)
					(fill yes)
				)
			)
		)
	)
	(footprint ""
		(layer "B.Cu")
		(at 112.268 -9.144 -90)
		(property "Reference" "R478"
			(at 0 0 90)
			(layer "B.SilkS")
			(hide yes)
			(effects
				(font
					(size 1.27 1.27)
				)
				(justify mirror)
			)
		)
		(property "Value" "10KR2F-2-GP"
			(at -1.7907 -1.1176 270)
			(unlocked yes)
			(layer "B.Fab")
			(hide yes)
			(effects
				(font
					(size 1.016 1.016)
					(thickness 0.1524)
				)
				(justify mirror)
			)
		)
		(property "Device Type" "R402H16"
			(at -1.7907 -2.6416 270)
			(unlocked yes)
			(layer "B.Fab")
			(hide yes)
			(effects
				(font
					(size 1.016 1.016)
					(thickness 0.1524)
				)
				(justify mirror)
			)
		)
		(duplicate_pad_numbers_are_jumpers no)
		(fp_rect
			(start 0.381 0.8382)
			(end -0.381 -0.8382)
			(stroke
				(width 0)
				(type default)
			)
			(fill no)
			(layer "B.CrtYd")
		)
		(fp_rect
			(start 0.381 0.8382)
			(end -0.381 -0.8382)
			(stroke
				(width 0)
				(type default)
			)
			(fill no)
			(layer "B.Fab")
		)
		(pad "1" smd custom
			(at 0 -0.4318 90)
			(size 0.127 0.127)
			(layers "B.Cu" "B.Mask" "B.Paste")
			(net "P3V3")
			(options
				(clearance outline)
				(anchor circle)
			)
			(primitives
				(gr_poly
					(pts
						(arc
							(start -0.2032 0.2794)
							(mid -0.239121 0.264521)
							(end -0.254 0.2286)
						)
						(arc
							(start -0.254 -0.2286)
							(mid -0.239121 -0.264521)
							(end -0.2032 -0.2794)
						)
						(arc
							(start 0.2032 -0.2794)
							(mid 0.239121 -0.264521)
							(end 0.254 -0.2286)
						)
						(arc
							(start 0.254 0.2286)
							(mid 0.239121 0.264521)
							(end 0.2032 0.2794)
						)
					)
					(width 0)
					(fill yes)
				)
			)
		)
		(pad "2" smd custom
			(at 0 0.4318 90)
			(size 0.127 0.127)
			(layers "B.Cu" "B.Mask" "B.Paste")
			(net "IRQ_MCERR#")
			(options
				(clearance outline)
				(anchor circle)
			)
			(primitives
				(gr_poly
					(pts
						(arc
							(start -0.2032 0.2794)
							(mid -0.239121 0.264521)
							(end -0.254 0.2286)
						)
						(arc
							(start -0.254 -0.2286)
							(mid -0.239121 -0.264521)
							(end -0.2032 -0.2794)
						)
						(arc
							(start 0.2032 -0.2794)
							(mid 0.239121 -0.264521)
							(end 0.254 -0.2286)
						)
						(arc
							(start 0.254 0.2286)
							(mid 0.239121 0.264521)
							(end 0.2032 0.2794)
						)
					)
					(width 0)
					(fill yes)
				)
			)
		)
	)
	(footprint ""
		(layer "B.Cu")
		(at 100.33 -63.881 180)
		(property "Reference" "PR4"
			(at 0 0 0)
			(layer "B.SilkS")
			(hide yes)
			(effects
				(font
					(size 1.27 1.27)
				)
				(justify mirror)
			)
		)
		(property "Value" "0R2J-2-GP"
			(at -0.064008 -3.993896 180)
			(unlocked yes)
			(layer "B.Fab")
			(hide yes)
			(effects
				(font
					(size 1.016 1.016)
					(thickness 0.1524)
				)
				(justify mirror)
			)
		)
		(property "Device Type" "R402H16"
			(at -0.064008 -5.517896 180)
			(unlocked yes)
			(layer "B.Fab")
			(hide yes)
			(effects
				(font
					(size 1.016 1.016)
					(thickness 0.1524)
				)
				(justify mirror)
			)
		)
		(duplicate_pad_numbers_are_jumpers no)
		(fp_rect
			(start 0.381 0.8382)
			(end -0.381 -0.8382)
			(stroke
				(width 0)
				(type default)
			)
			(fill no)
			(layer "B.CrtYd")
		)
		(fp_rect
			(start 0.381 0.8382)
			(end -0.381 -0.8382)
			(stroke
				(width 0)
				(type default)
			)
			(fill no)
			(layer "B.Fab")
		)
		(pad "1" smd custom
			(at 0 -0.4318)
			(size 0.127 0.127)
			(layers "B.Cu" "B.Mask" "B.Paste")
			(net "P3V3_STBY")
			(options
				(clearance outline)
				(anchor circle)
			)
			(primitives
				(gr_poly
					(pts
						(arc
							(start -0.2032 0.2794)
							(mid -0.239121 0.264521)
							(end -0.254 0.2286)
						)
						(arc
							(start -0.254 -0.2286)
							(mid -0.239121 -0.264521)
							(end -0.2032 -0.2794)
						)
						(arc
							(start 0.2032 -0.2794)
							(mid 0.239121 -0.264521)
							(end 0.254 -0.2286)
						)
						(arc
							(start 0.254 0.2286)
							(mid 0.239121 0.264521)
							(end 0.2032 0.2794)
						)
					)
					(width 0)
					(fill yes)
				)
			)
		)
		(pad "2" smd custom
			(at 0 0.4318)
			(size 0.127 0.127)
			(layers "B.Cu" "B.Mask" "B.Paste")
			(net "VR_P1V1_AVIN")
			(options
				(clearance outline)
				(anchor circle)
			)
			(primitives
				(gr_poly
					(pts
						(arc
							(start -0.2032 0.2794)
							(mid -0.239121 0.264521)
							(end -0.254 0.2286)
						)
						(arc
							(start -0.254 -0.2286)
							(mid -0.239121 -0.264521)
							(end -0.2032 -0.2794)
						)
						(arc
							(start 0.2032 -0.2794)
							(mid 0.239121 -0.264521)
							(end 0.254 -0.2286)
						)
						(arc
							(start 0.254 0.2286)
							(mid 0.239121 0.264521)
							(end 0.2032 0.2794)
						)
					)
					(width 0)
					(fill yes)
				)
			)
		)
	)
	(footprint ""
		(layer "B.Cu")
		(at 26.2255 -12.7)
		(property "Reference" "C272"
			(at 0 0 0)
			(layer "B.SilkS")
			(hide yes)
			(effects
				(font
					(size 1.27 1.27)
				)
				(justify mirror)
			)
		)
		(property "Value" "SCD1U16V2KX-3GP"
			(at -1.1811 -2.7051 0)
			(unlocked yes)
			(layer "B.Fab")
			(hide yes)
			(effects
				(font
					(size 1.016 1.016)
					(thickness 0.1524)
				)
				(justify mirror)
			)
		)
		(property "Device Type" "C402H22"
			(at -1.1811 -4.2291 0)
			(unlocked yes)
			(layer "B.Fab")
			(hide yes)
			(effects
				(font
					(size 1.016 1.016)
					(thickness 0.1524)
				)
				(justify mirror)
			)
		)
		(duplicate_pad_numbers_are_jumpers no)
		(fp_rect
			(start 0.381 0.7366)
			(end -0.381 -0.7366)
			(stroke
				(width 0)
				(type default)
			)
			(fill no)
			(layer "B.CrtYd")
		)
		(fp_rect
			(start 0.381 0.7366)
			(end -0.381 -0.7366)
			(stroke
				(width 0)
				(type default)
			)
			(fill no)
			(layer "B.Fab")
		)
		(pad "1" smd custom
			(at 0 -0.4572 180)
			(size 0.1143 0.1143)
			(layers "B.Cu" "B.Mask" "B.Paste")
			(net "P2E_CPU_ETH10G_C_TX_DP9")
			(options
				(clearance outline)
				(anchor circle)
			)
			(primitives
				(gr_poly
					(pts
						(arc
							(start -0.254 0.1778)
							(mid -0.239121 0.213721)
							(end -0.2032 0.2286)
						)
						(arc
							(start 0.2032 0.2286)
							(mid 0.239121 0.213721)
							(end 0.254 0.1778)
						)
						(arc
							(start 0.254 -0.1778)
							(mid 0.239121 -0.213721)
							(end 0.2032 -0.2286)
						)
						(arc
							(start -0.2032 -0.2286)
							(mid -0.239121 -0.213721)
							(end -0.254 -0.1778)
						)
					)
					(width 0)
					(fill yes)
				)
			)
		)
		(pad "2" smd custom
			(at 0 0.4572 180)
			(size 0.1143 0.1143)
			(layers "B.Cu" "B.Mask" "B.Paste")
			(net "P2E_CPU_ETH10G_TX_DP9")
			(options
				(clearance outline)
				(anchor circle)
			)
			(primitives
				(gr_poly
					(pts
						(arc
							(start -0.254 0.1778)
							(mid -0.239121 0.213721)
							(end -0.2032 0.2286)
						)
						(arc
							(start 0.2032 0.2286)
							(mid 0.239121 0.213721)
							(end 0.254 0.1778)
						)
						(arc
							(start 0.254 -0.1778)
							(mid 0.239121 -0.213721)
							(end 0.2032 -0.2286)
						)
						(arc
							(start -0.2032 -0.2286)
							(mid -0.239121 -0.213721)
							(end -0.254 -0.1778)
						)
					)
					(width 0)
					(fill yes)
				)
			)
		)
	)
	(footprint ""
		(layer "B.Cu")
		(at 51.181 -17.018)
		(property "Reference" "C201"
			(at 0 0 0)
			(layer "B.SilkS")
			(hide yes)
			(effects
				(font
					(size 1.27 1.27)
				)
				(justify mirror)
			)
		)
		(property "Value" "SCD1U10V2KX-5GP"
			(at -1.1811 -2.7051 0)
			(unlocked yes)
			(layer "B.Fab")
			(hide yes)
			(effects
				(font
					(size 1.016 1.016)
					(thickness 0.1524)
				)
				(justify mirror)
			)
		)
		(property "Device Type" "C402H22"
			(at -1.1811 -4.2291 0)
			(unlocked yes)
			(layer "B.Fab")
			(hide yes)
			(effects
				(font
					(size 1.016 1.016)
					(thickness 0.1524)
				)
				(justify mirror)
			)
		)
		(duplicate_pad_numbers_are_jumpers no)
		(fp_rect
			(start 0.381 0.7366)
			(end -0.381 -0.7366)
			(stroke
				(width 0)
				(type default)
			)
			(fill no)
			(layer "B.CrtYd")
		)
		(fp_rect
			(start 0.381 0.7366)
			(end -0.381 -0.7366)
			(stroke
				(width 0)
				(type default)
			)
			(fill no)
			(layer "B.Fab")
		)
		(pad "1" smd custom
			(at 0 -0.4572 180)
			(size 0.1143 0.1143)
			(layers "B.Cu" "B.Mask" "B.Paste")
			(net "P3V3_VDDA_CLKBUFF")
			(options
				(clearance outline)
				(anchor circle)
			)
			(primitives
				(gr_poly
					(pts
						(arc
							(start -0.254 0.1778)
							(mid -0.239121 0.213721)
							(end -0.2032 0.2286)
						)
						(arc
							(start 0.2032 0.2286)
							(mid 0.239121 0.213721)
							(end 0.254 0.1778)
						)
						(arc
							(start 0.254 -0.1778)
							(mid 0.239121 -0.213721)
							(end 0.2032 -0.2286)
						)
						(arc
							(start -0.2032 -0.2286)
							(mid -0.239121 -0.213721)
							(end -0.254 -0.1778)
						)
					)
					(width 0)
					(fill yes)
				)
			)
		)
		(pad "2" smd custom
			(at 0 0.4572 180)
			(size 0.1143 0.1143)
			(layers "B.Cu" "B.Mask" "B.Paste")
			(net "GND")
			(options
				(clearance outline)
				(anchor circle)
			)
			(primitives
				(gr_poly
					(pts
						(arc
							(start -0.254 0.1778)
							(mid -0.239121 0.213721)
							(end -0.2032 0.2286)
						)
						(arc
							(start 0.2032 0.2286)
							(mid 0.239121 0.213721)
							(end 0.254 0.1778)
						)
						(arc
							(start 0.254 -0.1778)
							(mid 0.239121 -0.213721)
							(end 0.2032 -0.2286)
						)
						(arc
							(start -0.2032 -0.2286)
							(mid -0.239121 -0.213721)
							(end -0.254 -0.1778)
						)
					)
					(width 0)
					(fill yes)
				)
			)
		)
	)
	(footprint ""
		(layer "B.Cu")
		(at 58.2168 -13.335 180)
		(property "Reference" "U31"
			(at 0 0 0)
			(layer "B.SilkS")
			(hide yes)
			(effects
				(font
					(size 1.27 1.27)
				)
				(justify mirror)
			)
		)
		(property "Value" "SN74LVC1G07DCKRG4-2-GP"
			(at 0 -8.0772 180)
			(unlocked yes)
			(layer "B.Fab")
			(hide yes)
			(effects
				(font
					(size 1.016 1.016)
					(thickness 0.1524)
				)
				(justify mirror)
			)
		)
		(property "Device Type" "SC70-5H44"
			(at 0 -9.6012 180)
			(unlocked yes)
			(layer "B.Fab")
			(hide yes)
			(effects
				(font
					(size 1.016 1.016)
					(thickness 0.1524)
				)
				(justify mirror)
			)
		)
		(duplicate_pad_numbers_are_jumpers no)
		(fp_line
			(start 1.0033 0.3302)
			(end 1.0033 -0.3302)
			(stroke
				(width 0.1524)
				(type default)
			)
			(layer "B.SilkS")
		)
		(fp_line
			(start 1.0033 -0.3302)
			(end -1.0033 -0.3302)
			(stroke
				(width 0.1524)
				(type default)
			)
			(layer "B.SilkS")
		)
		(fp_line
			(start -1.0033 0.3302)
			(end 1.0033 0.3302)
			(stroke
				(width 0.1524)
				(type default)
			)
			(layer "B.SilkS")
		)
		(fp_line
			(start -1.0033 -0.3302)
			(end -1.0033 0.3302)
			(stroke
				(width 0.1524)
				(type default)
			)
			(layer "B.SilkS")
		)
		(fp_poly
			(pts
				(xy 1.0033 1.4859) (xy 1.0033 0.8001) (xy 1.1811 0.8001) (xy 1.1811 -0.8001) (xy 1.0033 -0.8001)
				(xy 1.0033 -1.4859) (xy -1.0033 -1.4859) (xy -1.0033 -0.8001) (xy -1.1811 -0.8001) (xy -1.1811 0.8001)
				(xy -1.0033 0.8001) (xy -1.0033 1.4859) (xy -0.2921 1.4859) (xy -0.2921 0.8001) (xy 0.2921 0.8001)
				(xy 0.2921 1.4859)
			)
			(stroke
				(width 0)
				(type default)
			)
			(fill no)
			(layer "B.CrtYd")
		)
		(fp_poly
			(pts
				(xy 1.0033 1.4859) (xy 1.0033 0.8001) (xy 1.1811 0.8001) (xy 1.1811 -0.8001) (xy 1.0033 -0.8001)
				(xy 1.0033 -1.4859) (xy -1.0033 -1.4859) (xy -1.0033 -0.8001) (xy -1.1811 -0.8001) (xy -1.1811 0.8001)
				(xy -1.0033 0.8001) (xy -1.0033 1.4859) (xy -0.2921 1.4859) (xy -0.2921 0.8001) (xy 0.2921 0.8001)
				(xy 0.2921 1.4859)
			)
			(stroke
				(width 0)
				(type default)
			)
			(fill no)
			(layer "B.Fab")
		)
		(pad "1" smd rect
			(at -0.65024 -0.93472)
			(size 0.3556 0.762)
			(layers "B.Cu" "B.Mask" "B.Paste")
			(net "Net_144")
		)
		(pad "2" smd rect
			(at 0 -0.93472)
			(size 0.3556 0.762)
			(layers "B.Cu" "B.Mask" "B.Paste")
			(net "PMU_PLTRST#")
		)
		(pad "3" smd rect
			(at 0.65024 -0.93472)
			(size 0.3556 0.762)
			(layers "B.Cu" "B.Mask" "B.Paste")
			(net "GND")
		)
		(pad "4" smd rect
			(at 0.65024 0.93472)
			(size 0.3556 0.762)
			(layers "B.Cu" "B.Mask" "B.Paste")
			(net "PMU_BUF_PLTRST#")
		)
		(pad "5" smd rect
			(at -0.65024 0.93472)
			(size 0.3556 0.762)
			(layers "B.Cu" "B.Mask" "B.Paste")
			(net "P3V3_STBY")
		)
	)
	(footprint ""
		(layer "B.Cu")
		(at 88.773 -44.069 180)
		(property "Reference" "R299"
			(at 0 0 0)
			(layer "B.SilkS")
			(hide yes)
			(effects
				(font
					(size 1.27 1.27)
				)
				(justify mirror)
			)
		)
		(property "Value" "45D3R2F-L-GP"
			(at -0.064008 -3.993896 180)
			(unlocked yes)
			(layer "B.Fab")
			(hide yes)
			(effects
				(font
					(size 1.016 1.016)
					(thickness 0.1524)
				)
				(justify mirror)
			)
		)
		(property "Device Type" "R402H16"
			(at -0.064008 -5.517896 180)
			(unlocked yes)
			(layer "B.Fab")
			(hide yes)
			(effects
				(font
					(size 1.016 1.016)
					(thickness 0.1524)
				)
				(justify mirror)
			)
		)
		(duplicate_pad_numbers_are_jumpers no)
		(fp_rect
			(start 0.381 0.8382)
			(end -0.381 -0.8382)
			(stroke
				(width 0)
				(type default)
			)
			(fill no)
			(layer "B.CrtYd")
		)
		(fp_rect
			(start 0.381 0.8382)
			(end -0.381 -0.8382)
			(stroke
				(width 0)
				(type default)
			)
			(fill no)
			(layer "B.Fab")
		)
		(pad "1" smd custom
			(at 0 -0.4318)
			(size 0.127 0.127)
			(layers "B.Cu" "B.Mask" "B.Paste")
			(net "PD_USB_RCOMP")
			(options
				(clearance outline)
				(anchor circle)
			)
			(primitives
				(gr_poly
					(pts
						(arc
							(start -0.2032 0.2794)
							(mid -0.239121 0.264521)
							(end -0.254 0.2286)
						)
						(arc
							(start -0.254 -0.2286)
							(mid -0.239121 -0.264521)
							(end -0.2032 -0.2794)
						)
						(arc
							(start 0.2032 -0.2794)
							(mid 0.239121 -0.264521)
							(end 0.254 -0.2286)
						)
						(arc
							(start 0.254 0.2286)
							(mid 0.239121 0.264521)
							(end 0.2032 0.2794)
						)
					)
					(width 0)
					(fill yes)
				)
			)
		)
		(pad "2" smd custom
			(at 0 0.4318)
			(size 0.127 0.127)
			(layers "B.Cu" "B.Mask" "B.Paste")
			(net "GND")
			(options
				(clearance outline)
				(anchor circle)
			)
			(primitives
				(gr_poly
					(pts
						(arc
							(start -0.2032 0.2794)
							(mid -0.239121 0.264521)
							(end -0.254 0.2286)
						)
						(arc
							(start -0.254 -0.2286)
							(mid -0.239121 -0.264521)
							(end -0.2032 -0.2794)
						)
						(arc
							(start 0.2032 -0.2794)
							(mid 0.239121 -0.264521)
							(end 0.254 -0.2286)
						)
						(arc
							(start 0.254 0.2286)
							(mid 0.239121 0.264521)
							(end 0.2032 0.2794)
						)
					)
					(width 0)
					(fill yes)
				)
			)
		)
	)
	(footprint ""
		(layer "B.Cu")
		(at 18.796 -24.765 -90)
		(property "Reference" "PR87"
			(at 0 0 90)
			(layer "B.SilkS")
			(hide yes)
			(effects
				(font
					(size 1.27 1.27)
				)
				(justify mirror)
			)
		)
		(property "Value" "0R2J-2-GP"
			(at -1.7907 -1.1176 270)
			(unlocked yes)
			(layer "B.Fab")
			(hide yes)
			(effects
				(font
					(size 1.016 1.016)
					(thickness 0.1524)
				)
				(justify mirror)
			)
		)
		(property "Device Type" "R402H16"
			(at -1.7907 -2.6416 270)
			(unlocked yes)
			(layer "B.Fab")
			(hide yes)
			(effects
				(font
					(size 1.016 1.016)
					(thickness 0.1524)
				)
				(justify mirror)
			)
		)
		(duplicate_pad_numbers_are_jumpers no)
		(fp_rect
			(start 0.381 0.8382)
			(end -0.381 -0.8382)
			(stroke
				(width 0)
				(type default)
			)
			(fill no)
			(layer "B.CrtYd")
		)
		(fp_rect
			(start 0.381 0.8382)
			(end -0.381 -0.8382)
			(stroke
				(width 0)
				(type default)
			)
			(fill no)
			(layer "B.Fab")
		)
		(pad "1" smd custom
			(at 0 -0.4318 90)
			(size 0.127 0.127)
			(layers "B.Cu" "B.Mask" "B.Paste")
			(net "P1V0")
			(options
				(clearance outline)
				(anchor circle)
			)
			(primitives
				(gr_poly
					(pts
						(arc
							(start -0.2032 0.2794)
							(mid -0.239121 0.264521)
							(end -0.254 0.2286)
						)
						(arc
							(start -0.254 -0.2286)
							(mid -0.239121 -0.264521)
							(end -0.2032 -0.2794)
						)
						(arc
							(start 0.2032 -0.2794)
							(mid 0.239121 -0.264521)
							(end 0.254 -0.2286)
						)
						(arc
							(start 0.254 0.2286)
							(mid 0.239121 0.264521)
							(end 0.2032 0.2794)
						)
					)
					(width 0)
					(fill yes)
				)
			)
		)
		(pad "2" smd custom
			(at 0 0.4318 90)
			(size 0.127 0.127)
			(layers "B.Cu" "B.Mask" "B.Paste")
			(net "P1V0_ROVP")
			(options
				(clearance outline)
				(anchor circle)
			)
			(primitives
				(gr_poly
					(pts
						(arc
							(start -0.2032 0.2794)
							(mid -0.239121 0.264521)
							(end -0.254 0.2286)
						)
						(arc
							(start -0.254 -0.2286)
							(mid -0.239121 -0.264521)
							(end -0.2032 -0.2794)
						)
						(arc
							(start 0.2032 -0.2794)
							(mid 0.239121 -0.264521)
							(end 0.254 -0.2286)
						)
						(arc
							(start 0.254 0.2286)
							(mid 0.239121 0.264521)
							(end 0.2032 0.2794)
						)
					)
					(width 0)
					(fill yes)
				)
			)
		)
	)
	(footprint ""
		(layer "B.Cu")
		(at 80.137 -65.786)
		(property "Reference" "R293"
			(at 0 0 0)
			(layer "B.SilkS")
			(hide yes)
			(effects
				(font
					(size 1.27 1.27)
				)
				(justify mirror)
			)
		)
		(property "Value" "56D2R2F-GP"
			(at -0.064008 -3.993896 0)
			(unlocked yes)
			(layer "B.Fab")
			(hide yes)
			(effects
				(font
					(size 1.016 1.016)
					(thickness 0.1524)
				)
				(justify mirror)
			)
		)
		(property "Device Type" "R402H16"
			(at -0.064008 -5.517896 0)
			(unlocked yes)
			(layer "B.Fab")
			(hide yes)
			(effects
				(font
					(size 1.016 1.016)
					(thickness 0.1524)
				)
				(justify mirror)
			)
		)
		(duplicate_pad_numbers_are_jumpers no)
		(fp_rect
			(start 0.381 0.8382)
			(end -0.381 -0.8382)
			(stroke
				(width 0)
				(type default)
			)
			(fill no)
			(layer "B.CrtYd")
		)
		(fp_rect
			(start 0.381 0.8382)
			(end -0.381 -0.8382)
			(stroke
				(width 0)
				(type default)
			)
			(fill no)
			(layer "B.Fab")
		)
		(pad "1" smd custom
			(at 0 -0.4318 180)
			(size 0.127 0.127)
			(layers "B.Cu" "B.Mask" "B.Paste")
			(net "P1V0")
			(options
				(clearance outline)
				(anchor circle)
			)
			(primitives
				(gr_poly
					(pts
						(arc
							(start -0.2032 0.2794)
							(mid -0.239121 0.264521)
							(end -0.254 0.2286)
						)
						(arc
							(start -0.254 -0.2286)
							(mid -0.239121 -0.264521)
							(end -0.2032 -0.2794)
						)
						(arc
							(start 0.2032 -0.2794)
							(mid 0.239121 -0.264521)
							(end 0.254 -0.2286)
						)
						(arc
							(start 0.254 0.2286)
							(mid 0.239121 0.264521)
							(end 0.2032 0.2794)
						)
					)
					(width 0)
					(fill yes)
				)
			)
		)
		(pad "2" smd custom
			(at 0 0.4318 180)
			(size 0.127 0.127)
			(layers "B.Cu" "B.Mask" "B.Paste")
			(net "SVID_CPU_ALERT#")
			(options
				(clearance outline)
				(anchor circle)
			)
			(primitives
				(gr_poly
					(pts
						(arc
							(start -0.2032 0.2794)
							(mid -0.239121 0.264521)
							(end -0.254 0.2286)
						)
						(arc
							(start -0.254 -0.2286)
							(mid -0.239121 -0.264521)
							(end -0.2032 -0.2794)
						)
						(arc
							(start 0.2032 -0.2794)
							(mid 0.239121 -0.264521)
							(end 0.254 -0.2286)
						)
						(arc
							(start 0.254 0.2286)
							(mid 0.239121 0.264521)
							(end 0.2032 0.2794)
						)
					)
					(width 0)
					(fill yes)
				)
			)
		)
	)
	(footprint ""
		(layer "B.Cu")
		(at 136.779 -60.198 180)
		(property "Reference" "R232"
			(at 0 0 0)
			(layer "B.SilkS")
			(hide yes)
			(effects
				(font
					(size 1.27 1.27)
				)
				(justify mirror)
			)
		)
		(property "Value" "4K7R2F-GP"
			(at -0.064008 -3.993896 180)
			(unlocked yes)
			(layer "B.Fab")
			(hide yes)
			(effects
				(font
					(size 1.016 1.016)
					(thickness 0.1524)
				)
				(justify mirror)
			)
		)
		(property "Device Type" "R402H16"
			(at -0.064008 -5.517896 180)
			(unlocked yes)
			(layer "B.Fab")
			(hide yes)
			(effects
				(font
					(size 1.016 1.016)
					(thickness 0.1524)
				)
				(justify mirror)
			)
		)
		(duplicate_pad_numbers_are_jumpers no)
		(fp_rect
			(start 0.381 0.8382)
			(end -0.381 -0.8382)
			(stroke
				(width 0)
				(type default)
			)
			(fill no)
			(layer "B.CrtYd")
		)
		(fp_rect
			(start 0.381 0.8382)
			(end -0.381 -0.8382)
			(stroke
				(width 0)
				(type default)
			)
			(fill no)
			(layer "B.Fab")
		)
		(pad "1" smd custom
			(at 0 -0.4318)
			(size 0.127 0.127)
			(layers "B.Cu" "B.Mask" "B.Paste")
			(net "CHA_0_SA0")
			(options
				(clearance outline)
				(anchor circle)
			)
			(primitives
				(gr_poly
					(pts
						(arc
							(start -0.2032 0.2794)
							(mid -0.239121 0.264521)
							(end -0.254 0.2286)
						)
						(arc
							(start -0.254 -0.2286)
							(mid -0.239121 -0.264521)
							(end -0.2032 -0.2794)
						)
						(arc
							(start 0.2032 -0.2794)
							(mid 0.239121 -0.264521)
							(end 0.254 -0.2286)
						)
						(arc
							(start 0.254 0.2286)
							(mid 0.239121 0.264521)
							(end 0.2032 0.2794)
						)
					)
					(width 0)
					(fill yes)
				)
			)
		)
		(pad "2" smd custom
			(at 0 0.4318)
			(size 0.127 0.127)
			(layers "B.Cu" "B.Mask" "B.Paste")
			(net "GND")
			(options
				(clearance outline)
				(anchor circle)
			)
			(primitives
				(gr_poly
					(pts
						(arc
							(start -0.2032 0.2794)
							(mid -0.239121 0.264521)
							(end -0.254 0.2286)
						)
						(arc
							(start -0.254 -0.2286)
							(mid -0.239121 -0.264521)
							(end -0.2032 -0.2794)
						)
						(arc
							(start 0.2032 -0.2794)
							(mid 0.239121 -0.264521)
							(end 0.254 -0.2286)
						)
						(arc
							(start 0.254 0.2286)
							(mid 0.239121 0.264521)
							(end 0.2032 0.2794)
						)
					)
					(width 0)
					(fill yes)
				)
			)
		)
	)
	(footprint ""
		(layer "B.Cu")
		(at 92.226384 -50.689002 -90)
		(property "Reference" "R282"
			(at 0 0 90)
			(layer "B.SilkS")
			(hide yes)
			(effects
				(font
					(size 1.27 1.27)
				)
				(justify mirror)
			)
		)
		(property "Value" "402R2F-GP"
			(at -0.064008 -3.993896 270)
			(unlocked yes)
			(layer "B.Fab")
			(hide yes)
			(effects
				(font
					(size 1.016 1.016)
					(thickness 0.1524)
				)
				(justify mirror)
			)
		)
		(property "Device Type" "R402H16"
			(at -0.064008 -5.517896 270)
			(unlocked yes)
			(layer "B.Fab")
			(hide yes)
			(effects
				(font
					(size 1.016 1.016)
					(thickness 0.1524)
				)
				(justify mirror)
			)
		)
		(duplicate_pad_numbers_are_jumpers no)
		(fp_rect
			(start 0.381 0.8382)
			(end -0.381 -0.8382)
			(stroke
				(width 0)
				(type default)
			)
			(fill no)
			(layer "B.CrtYd")
		)
		(fp_rect
			(start 0.381 0.8382)
			(end -0.381 -0.8382)
			(stroke
				(width 0)
				(type default)
			)
			(fill no)
			(layer "B.Fab")
		)
		(pad "1" smd custom
			(at 0 -0.4318 90)
			(size 0.127 0.127)
			(layers "B.Cu" "B.Mask" "B.Paste")
			(net "PCIE_OBS_P")
			(options
				(clearance outline)
				(anchor circle)
			)
			(primitives
				(gr_poly
					(pts
						(arc
							(start -0.2032 0.2794)
							(mid -0.239121 0.264521)
							(end -0.254 0.2286)
						)
						(arc
							(start -0.254 -0.2286)
							(mid -0.239121 -0.264521)
							(end -0.2032 -0.2794)
						)
						(arc
							(start 0.2032 -0.2794)
							(mid 0.239121 -0.264521)
							(end 0.254 -0.2286)
						)
						(arc
							(start 0.254 0.2286)
							(mid 0.239121 0.264521)
							(end 0.2032 0.2794)
						)
					)
					(width 0)
					(fill yes)
				)
			)
		)
		(pad "2" smd custom
			(at 0 0.4318 90)
			(size 0.127 0.127)
			(layers "B.Cu" "B.Mask" "B.Paste")
			(net "PCIE_OBS_N")
			(options
				(clearance outline)
				(anchor circle)
			)
			(primitives
				(gr_poly
					(pts
						(arc
							(start -0.2032 0.2794)
							(mid -0.239121 0.264521)
							(end -0.254 0.2286)
						)
						(arc
							(start -0.254 -0.2286)
							(mid -0.239121 -0.264521)
							(end -0.2032 -0.2794)
						)
						(arc
							(start 0.2032 -0.2794)
							(mid 0.239121 -0.264521)
							(end 0.254 -0.2286)
						)
						(arc
							(start 0.254 0.2286)
							(mid 0.239121 0.264521)
							(end 0.2032 0.2794)
						)
					)
					(width 0)
					(fill yes)
				)
			)
		)
	)
	(footprint ""
		(layer "B.Cu")
		(at 197.231 -67.564 90)
		(property "Reference" "R410"
			(at 0 0 90)
			(layer "B.SilkS")
			(hide yes)
			(effects
				(font
					(size 1.27 1.27)
				)
				(justify mirror)
			)
		)
		(property "Value" "10KR2F-2-GP"
			(at -1.7907 -1.1176 90)
			(unlocked yes)
			(layer "B.Fab")
			(hide yes)
			(effects
				(font
					(size 1.016 1.016)
					(thickness 0.1524)
				)
				(justify mirror)
			)
		)
		(property "Device Type" "R402H16"
			(at -1.7907 -2.6416 90)
			(unlocked yes)
			(layer "B.Fab")
			(hide yes)
			(effects
				(font
					(size 1.016 1.016)
					(thickness 0.1524)
				)
				(justify mirror)
			)
		)
		(duplicate_pad_numbers_are_jumpers no)
		(fp_rect
			(start 0.381 0.8382)
			(end -0.381 -0.8382)
			(stroke
				(width 0)
				(type default)
			)
			(fill no)
			(layer "B.CrtYd")
		)
		(fp_rect
			(start 0.381 0.8382)
			(end -0.381 -0.8382)
			(stroke
				(width 0)
				(type default)
			)
			(fill no)
			(layer "B.Fab")
		)
		(pad "1" smd custom
			(at 0 -0.4318 270)
			(size 0.127 0.127)
			(layers "B.Cu" "B.Mask" "B.Paste")
			(net "P3V3")
			(options
				(clearance outline)
				(anchor circle)
			)
			(primitives
				(gr_poly
					(pts
						(arc
							(start -0.2032 0.2794)
							(mid -0.239121 0.264521)
							(end -0.254 0.2286)
						)
						(arc
							(start -0.254 -0.2286)
							(mid -0.239121 -0.264521)
							(end -0.2032 -0.2794)
						)
						(arc
							(start 0.2032 -0.2794)
							(mid 0.239121 -0.264521)
							(end 0.254 -0.2286)
						)
						(arc
							(start 0.254 0.2286)
							(mid 0.239121 0.264521)
							(end 0.2032 0.2794)
						)
					)
					(width 0)
					(fill yes)
				)
			)
		)
		(pad "2" smd custom
			(at 0 0.4318 270)
			(size 0.127 0.127)
			(layers "B.Cu" "B.Mask" "B.Paste")
			(net "PWR_STATUS_LED_EN")
			(options
				(clearance outline)
				(anchor circle)
			)
			(primitives
				(gr_poly
					(pts
						(arc
							(start -0.2032 0.2794)
							(mid -0.239121 0.264521)
							(end -0.254 0.2286)
						)
						(arc
							(start -0.254 -0.2286)
							(mid -0.239121 -0.264521)
							(end -0.2032 -0.2794)
						)
						(arc
							(start 0.2032 -0.2794)
							(mid 0.239121 -0.264521)
							(end 0.254 -0.2286)
						)
						(arc
							(start 0.254 0.2286)
							(mid 0.239121 0.264521)
							(end 0.2032 0.2794)
						)
					)
					(width 0)
					(fill yes)
				)
			)
		)
	)
	(footprint ""
		(layer "B.Cu")
		(at 18.796 -24.003 -90)
		(property "Reference" "PR84"
			(at 0 0 90)
			(layer "B.SilkS")
			(hide yes)
			(effects
				(font
					(size 1.27 1.27)
				)
				(justify mirror)
			)
		)
		(property "Value" "0R2J-2-GP"
			(at -1.7907 -1.1176 270)
			(unlocked yes)
			(layer "B.Fab")
			(hide yes)
			(effects
				(font
					(size 1.016 1.016)
					(thickness 0.1524)
				)
				(justify mirror)
			)
		)
		(property "Device Type" "R402H16"
			(at -1.7907 -2.6416 270)
			(unlocked yes)
			(layer "B.Fab")
			(hide yes)
			(effects
				(font
					(size 1.016 1.016)
					(thickness 0.1524)
				)
				(justify mirror)
			)
		)
		(duplicate_pad_numbers_are_jumpers no)
		(fp_rect
			(start 0.381 0.8382)
			(end -0.381 -0.8382)
			(stroke
				(width 0)
				(type default)
			)
			(fill no)
			(layer "B.CrtYd")
		)
		(fp_rect
			(start 0.381 0.8382)
			(end -0.381 -0.8382)
			(stroke
				(width 0)
				(type default)
			)
			(fill no)
			(layer "B.Fab")
		)
		(pad "1" smd custom
			(at 0 -0.4318 90)
			(size 0.127 0.127)
			(layers "B.Cu" "B.Mask" "B.Paste")
			(net "AGND_P1V0")
			(options
				(clearance outline)
				(anchor circle)
			)
			(primitives
				(gr_poly
					(pts
						(arc
							(start -0.2032 0.2794)
							(mid -0.239121 0.264521)
							(end -0.254 0.2286)
						)
						(arc
							(start -0.254 -0.2286)
							(mid -0.239121 -0.264521)
							(end -0.2032 -0.2794)
						)
						(arc
							(start 0.2032 -0.2794)
							(mid 0.239121 -0.264521)
							(end 0.254 -0.2286)
						)
						(arc
							(start 0.254 0.2286)
							(mid 0.239121 0.264521)
							(end 0.2032 0.2794)
						)
					)
					(width 0)
					(fill yes)
				)
			)
		)
		(pad "2" smd custom
			(at 0 0.4318 90)
			(size 0.127 0.127)
			(layers "B.Cu" "B.Mask" "B.Paste")
			(net "P1V0_ROVP")
			(options
				(clearance outline)
				(anchor circle)
			)
			(primitives
				(gr_poly
					(pts
						(arc
							(start -0.2032 0.2794)
							(mid -0.239121 0.264521)
							(end -0.254 0.2286)
						)
						(arc
							(start -0.254 -0.2286)
							(mid -0.239121 -0.264521)
							(end -0.2032 -0.2794)
						)
						(arc
							(start 0.2032 -0.2794)
							(mid 0.239121 -0.264521)
							(end 0.254 -0.2286)
						)
						(arc
							(start 0.254 0.2286)
							(mid 0.239121 0.264521)
							(end 0.2032 0.2794)
						)
					)
					(width 0)
					(fill yes)
				)
			)
		)
	)
	(footprint ""
		(layer "B.Cu")
		(at 19.177 -64.77)
		(property "Reference" "PR22"
			(at 0 0 0)
			(layer "B.SilkS")
			(hide yes)
			(effects
				(font
					(size 1.27 1.27)
				)
				(justify mirror)
			)
		)
		(property "Value" "0R2J-2-GP"
			(at -1.7907 -1.1176 0)
			(unlocked yes)
			(layer "B.Fab")
			(hide yes)
			(effects
				(font
					(size 1.016 1.016)
					(thickness 0.1524)
				)
				(justify mirror)
			)
		)
		(property "Device Type" "R402H16"
			(at -1.7907 -2.6416 0)
			(unlocked yes)
			(layer "B.Fab")
			(hide yes)
			(effects
				(font
					(size 1.016 1.016)
					(thickness 0.1524)
				)
				(justify mirror)
			)
		)
		(duplicate_pad_numbers_are_jumpers no)
		(fp_rect
			(start 0.381 0.8382)
			(end -0.381 -0.8382)
			(stroke
				(width 0)
				(type default)
			)
			(fill no)
			(layer "B.CrtYd")
		)
		(fp_rect
			(start 0.381 0.8382)
			(end -0.381 -0.8382)
			(stroke
				(width 0)
				(type default)
			)
			(fill no)
			(layer "B.Fab")
		)
		(pad "1" smd custom
			(at 0 -0.4318 180)
			(size 0.127 0.127)
			(layers "B.Cu" "B.Mask" "B.Paste")
			(net "PVNN")
			(options
				(clearance outline)
				(anchor circle)
			)
			(primitives
				(gr_poly
					(pts
						(arc
							(start -0.2032 0.2794)
							(mid -0.239121 0.264521)
							(end -0.254 0.2286)
						)
						(arc
							(start -0.254 -0.2286)
							(mid -0.239121 -0.264521)
							(end -0.2032 -0.2794)
						)
						(arc
							(start 0.2032 -0.2794)
							(mid 0.239121 -0.264521)
							(end 0.254 -0.2286)
						)
						(arc
							(start 0.254 0.2286)
							(mid 0.239121 0.264521)
							(end 0.2032 0.2794)
						)
					)
					(width 0)
					(fill yes)
				)
			)
		)
		(pad "2" smd custom
			(at 0 0.4318 180)
			(size 0.127 0.127)
			(layers "B.Cu" "B.Mask" "B.Paste")
			(net "VR_PVNN_VSEN")
			(options
				(clearance outline)
				(anchor circle)
			)
			(primitives
				(gr_poly
					(pts
						(arc
							(start -0.2032 0.2794)
							(mid -0.239121 0.264521)
							(end -0.254 0.2286)
						)
						(arc
							(start -0.254 -0.2286)
							(mid -0.239121 -0.264521)
							(end -0.2032 -0.2794)
						)
						(arc
							(start 0.2032 -0.2794)
							(mid 0.239121 -0.264521)
							(end 0.254 -0.2286)
						)
						(arc
							(start 0.254 0.2286)
							(mid 0.239121 0.264521)
							(end 0.2032 0.2794)
						)
					)
					(width 0)
					(fill yes)
				)
			)
		)
	)
	(footprint ""
		(layer "B.Cu")
		(at 37.46881 -12.7)
		(property "Reference" "C267"
			(at 0 0 0)
			(layer "B.SilkS")
			(hide yes)
			(effects
				(font
					(size 1.27 1.27)
				)
				(justify mirror)
			)
		)
		(property "Value" "SCD1U16V2KX-3GP"
			(at -1.1811 -2.7051 0)
			(unlocked yes)
			(layer "B.Fab")
			(hide yes)
			(effects
				(font
					(size 1.016 1.016)
					(thickness 0.1524)
				)
				(justify mirror)
			)
		)
		(property "Device Type" "C402H22"
			(at -1.1811 -4.2291 0)
			(unlocked yes)
			(layer "B.Fab")
			(hide yes)
			(effects
				(font
					(size 1.016 1.016)
					(thickness 0.1524)
				)
				(justify mirror)
			)
		)
		(duplicate_pad_numbers_are_jumpers no)
		(fp_rect
			(start 0.381 0.7366)
			(end -0.381 -0.7366)
			(stroke
				(width 0)
				(type default)
			)
			(fill no)
			(layer "B.CrtYd")
		)
		(fp_rect
			(start 0.381 0.7366)
			(end -0.381 -0.7366)
			(stroke
				(width 0)
				(type default)
			)
			(fill no)
			(layer "B.Fab")
		)
		(pad "1" smd custom
			(at 0 -0.4572 180)
			(size 0.1143 0.1143)
			(layers "B.Cu" "B.Mask" "B.Paste")
			(net "P2E_CPU_SAS_C_TX_DN6")
			(options
				(clearance outline)
				(anchor circle)
			)
			(primitives
				(gr_poly
					(pts
						(arc
							(start -0.254 0.1778)
							(mid -0.239121 0.213721)
							(end -0.2032 0.2286)
						)
						(arc
							(start 0.2032 0.2286)
							(mid 0.239121 0.213721)
							(end 0.254 0.1778)
						)
						(arc
							(start 0.254 -0.1778)
							(mid 0.239121 -0.213721)
							(end 0.2032 -0.2286)
						)
						(arc
							(start -0.2032 -0.2286)
							(mid -0.239121 -0.213721)
							(end -0.254 -0.1778)
						)
					)
					(width 0)
					(fill yes)
				)
			)
		)
		(pad "2" smd custom
			(at 0 0.4572 180)
			(size 0.1143 0.1143)
			(layers "B.Cu" "B.Mask" "B.Paste")
			(net "P2E_CPU_SAS_TX_DN6")
			(options
				(clearance outline)
				(anchor circle)
			)
			(primitives
				(gr_poly
					(pts
						(arc
							(start -0.254 0.1778)
							(mid -0.239121 0.213721)
							(end -0.2032 0.2286)
						)
						(arc
							(start 0.2032 0.2286)
							(mid 0.239121 0.213721)
							(end 0.254 0.1778)
						)
						(arc
							(start 0.254 -0.1778)
							(mid 0.239121 -0.213721)
							(end 0.2032 -0.2286)
						)
						(arc
							(start -0.2032 -0.2286)
							(mid -0.239121 -0.213721)
							(end -0.254 -0.1778)
						)
					)
					(width 0)
					(fill yes)
				)
			)
		)
	)
	(footprint ""
		(layer "B.Cu")
		(at 6.096 -33.401 90)
		(property "Reference" "PR207"
			(at 0 0 90)
			(layer "B.SilkS")
			(hide yes)
			(effects
				(font
					(size 1.27 1.27)
				)
				(justify mirror)
			)
		)
		(property "Value" "10KR2F-2-GP"
			(at -1.7907 -1.1176 90)
			(unlocked yes)
			(layer "B.Fab")
			(hide yes)
			(effects
				(font
					(size 1.016 1.016)
					(thickness 0.1524)
				)
				(justify mirror)
			)
		)
		(property "Device Type" "R402H16"
			(at -1.7907 -2.6416 90)
			(unlocked yes)
			(layer "B.Fab")
			(hide yes)
			(effects
				(font
					(size 1.016 1.016)
					(thickness 0.1524)
				)
				(justify mirror)
			)
		)
		(duplicate_pad_numbers_are_jumpers no)
		(fp_rect
			(start 0.381 0.8382)
			(end -0.381 -0.8382)
			(stroke
				(width 0)
				(type default)
			)
			(fill no)
			(layer "B.CrtYd")
		)
		(fp_rect
			(start 0.381 0.8382)
			(end -0.381 -0.8382)
			(stroke
				(width 0)
				(type default)
			)
			(fill no)
			(layer "B.Fab")
		)
		(pad "1" smd custom
			(at 0 -0.4318 270)
			(size 0.127 0.127)
			(layers "B.Cu" "B.Mask" "B.Paste")
			(net "P3V3_STBY_PG")
			(options
				(clearance outline)
				(anchor circle)
			)
			(primitives
				(gr_poly
					(pts
						(arc
							(start -0.2032 0.2794)
							(mid -0.239121 0.264521)
							(end -0.254 0.2286)
						)
						(arc
							(start -0.254 -0.2286)
							(mid -0.239121 -0.264521)
							(end -0.2032 -0.2794)
						)
						(arc
							(start 0.2032 -0.2794)
							(mid 0.239121 -0.264521)
							(end 0.254 -0.2286)
						)
						(arc
							(start 0.254 0.2286)
							(mid 0.239121 0.264521)
							(end 0.2032 0.2794)
						)
					)
					(width 0)
					(fill yes)
				)
			)
		)
		(pad "2" smd custom
			(at 0 0.4318 270)
			(size 0.127 0.127)
			(layers "B.Cu" "B.Mask" "B.Paste")
			(net "P3V3_STBY_VREG")
			(options
				(clearance outline)
				(anchor circle)
			)
			(primitives
				(gr_poly
					(pts
						(arc
							(start -0.2032 0.2794)
							(mid -0.239121 0.264521)
							(end -0.254 0.2286)
						)
						(arc
							(start -0.254 -0.2286)
							(mid -0.239121 -0.264521)
							(end -0.2032 -0.2794)
						)
						(arc
							(start 0.2032 -0.2794)
							(mid 0.239121 -0.264521)
							(end 0.254 -0.2286)
						)
						(arc
							(start 0.254 0.2286)
							(mid 0.239121 0.264521)
							(end 0.2032 0.2794)
						)
					)
					(width 0)
					(fill yes)
				)
			)
		)
	)
	(footprint ""
		(layer "B.Cu")
		(at 159.512 -59.309)
		(property "Reference" "C108"
			(at 0 0 0)
			(layer "B.SilkS")
			(hide yes)
			(effects
				(font
					(size 1.27 1.27)
				)
				(justify mirror)
			)
		)
		(property "Value" "SC10U6D3V3MX-GP"
			(at 0.0254 -2.0193 0)
			(unlocked yes)
			(layer "B.Fab")
			(hide yes)
			(effects
				(font
					(size 1.016 1.016)
					(thickness 0.1524)
				)
				(justify mirror)
			)
		)
		(property "Device Type" "C603H38"
			(at 0.0254 -3.5433 0)
			(unlocked yes)
			(layer "B.Fab")
			(hide yes)
			(effects
				(font
					(size 1.016 1.016)
					(thickness 0.1524)
				)
				(justify mirror)
			)
		)
		(duplicate_pad_numbers_are_jumpers no)
		(fp_line
			(start 0.4064 0)
			(end -0.4064 0)
			(stroke
				(width 0.2286)
				(type default)
			)
			(layer "B.SilkS")
		)
		(fp_rect
			(start 0.635 1.1811)
			(end -0.635 -1.1811)
			(stroke
				(width 0)
				(type default)
			)
			(fill no)
			(layer "B.CrtYd")
		)
		(fp_rect
			(start 0.635 1.1811)
			(end -0.635 -1.1811)
			(stroke
				(width 0)
				(type default)
			)
			(fill no)
			(layer "B.Fab")
		)
		(pad "1" smd custom
			(at 0 -0.6604 180)
			(size 0.19685 0.19685)
			(layers "B.Cu" "B.Mask" "B.Paste")
			(net "PV_VDDR")
			(options
				(clearance outline)
				(anchor circle)
			)
			(primitives
				(gr_poly
					(pts
						(arc
							(start 0.508 0.2921)
							(mid 0.478242 0.363942)
							(end 0.4064 0.3937)
						)
						(arc
							(start -0.4064 0.3937)
							(mid -0.478242 0.363942)
							(end -0.508 0.2921)
						)
						(arc
							(start -0.508 -0.2921)
							(mid -0.478242 -0.363942)
							(end -0.4064 -0.3937)
						)
						(arc
							(start 0.4064 -0.3937)
							(mid 0.478242 -0.363942)
							(end 0.508 -0.2921)
						)
					)
					(width 0)
					(fill yes)
				)
			)
		)
		(pad "2" smd custom
			(at 0 0.6604 180)
			(size 0.19685 0.19685)
			(layers "B.Cu" "B.Mask" "B.Paste")
			(net "GND")
			(options
				(clearance outline)
				(anchor circle)
			)
			(primitives
				(gr_poly
					(pts
						(arc
							(start 0.508 0.2921)
							(mid 0.478242 0.363942)
							(end 0.4064 0.3937)
						)
						(arc
							(start -0.4064 0.3937)
							(mid -0.478242 0.363942)
							(end -0.508 0.2921)
						)
						(arc
							(start -0.508 -0.2921)
							(mid -0.478242 -0.363942)
							(end -0.4064 -0.3937)
						)
						(arc
							(start 0.4064 -0.3937)
							(mid 0.478242 -0.363942)
							(end 0.508 -0.2921)
						)
					)
					(width 0)
					(fill yes)
				)
			)
		)
	)
	(footprint ""
		(layer "B.Cu")
		(at 187.0456 -33.2486 90)
		(property "Reference" "PC99"
			(at 0 0 90)
			(layer "B.SilkS")
			(hide yes)
			(effects
				(font
					(size 1.27 1.27)
				)
				(justify mirror)
			)
		)
		(property "Value" "SC1KP50V2KX-1GP"
			(at -1.8923 -1.2065 90)
			(unlocked yes)
			(layer "B.Fab")
			(hide yes)
			(effects
				(font
					(size 1.016 1.016)
					(thickness 0.1524)
				)
				(justify mirror)
			)
		)
		(property "Device Type" "C402H22"
			(at -1.8923 -2.7305 90)
			(unlocked yes)
			(layer "B.Fab")
			(hide yes)
			(effects
				(font
					(size 1.016 1.016)
					(thickness 0.1524)
				)
				(justify mirror)
			)
		)
		(duplicate_pad_numbers_are_jumpers no)
		(fp_rect
			(start 0.381 0.7366)
			(end -0.381 -0.7366)
			(stroke
				(width 0)
				(type default)
			)
			(fill no)
			(layer "B.CrtYd")
		)
		(fp_rect
			(start 0.381 0.7366)
			(end -0.381 -0.7366)
			(stroke
				(width 0)
				(type default)
			)
			(fill no)
			(layer "B.Fab")
		)
		(pad "1" smd custom
			(at 0 -0.4572 270)
			(size 0.1143 0.1143)
			(layers "B.Cu" "B.Mask" "B.Paste")
			(net "VR_PVDDR_A_NTC")
			(options
				(clearance outline)
				(anchor circle)
			)
			(primitives
				(gr_poly
					(pts
						(arc
							(start -0.254 0.1778)
							(mid -0.239121 0.213721)
							(end -0.2032 0.2286)
						)
						(arc
							(start 0.2032 0.2286)
							(mid 0.239121 0.213721)
							(end 0.254 0.1778)
						)
						(arc
							(start 0.254 -0.1778)
							(mid 0.239121 -0.213721)
							(end 0.2032 -0.2286)
						)
						(arc
							(start -0.2032 -0.2286)
							(mid -0.239121 -0.213721)
							(end -0.254 -0.1778)
						)
					)
					(width 0)
					(fill yes)
				)
			)
		)
		(pad "2" smd custom
			(at 0 0.4572 270)
			(size 0.1143 0.1143)
			(layers "B.Cu" "B.Mask" "B.Paste")
			(net "GND")
			(options
				(clearance outline)
				(anchor circle)
			)
			(primitives
				(gr_poly
					(pts
						(arc
							(start -0.254 0.1778)
							(mid -0.239121 0.213721)
							(end -0.2032 0.2286)
						)
						(arc
							(start 0.2032 0.2286)
							(mid 0.239121 0.213721)
							(end 0.254 0.1778)
						)
						(arc
							(start 0.254 -0.1778)
							(mid 0.239121 -0.213721)
							(end 0.2032 -0.2286)
						)
						(arc
							(start -0.2032 -0.2286)
							(mid -0.239121 -0.213721)
							(end -0.254 -0.1778)
						)
					)
					(width 0)
					(fill yes)
				)
			)
		)
	)
	(footprint ""
		(layer "B.Cu")
		(at 105.283 -15.875)
		(property "Reference" "R466"
			(at 0 0 0)
			(layer "B.SilkS")
			(hide yes)
			(effects
				(font
					(size 1.27 1.27)
				)
				(justify mirror)
			)
		)
		(property "Value" "4K7R2F-GP"
			(at -1.7907 -1.1176 0)
			(unlocked yes)
			(layer "B.Fab")
			(hide yes)
			(effects
				(font
					(size 1.016 1.016)
					(thickness 0.1524)
				)
				(justify mirror)
			)
		)
		(property "Device Type" "R402H16"
			(at -1.7907 -2.6416 0)
			(unlocked yes)
			(layer "B.Fab")
			(hide yes)
			(effects
				(font
					(size 1.016 1.016)
					(thickness 0.1524)
				)
				(justify mirror)
			)
		)
		(duplicate_pad_numbers_are_jumpers no)
		(fp_rect
			(start 0.381 0.8382)
			(end -0.381 -0.8382)
			(stroke
				(width 0)
				(type default)
			)
			(fill no)
			(layer "B.CrtYd")
		)
		(fp_rect
			(start 0.381 0.8382)
			(end -0.381 -0.8382)
			(stroke
				(width 0)
				(type default)
			)
			(fill no)
			(layer "B.Fab")
		)
		(pad "1" smd custom
			(at 0 -0.4318 180)
			(size 0.127 0.127)
			(layers "B.Cu" "B.Mask" "B.Paste")
			(net "P3V3_STBY")
			(options
				(clearance outline)
				(anchor circle)
			)
			(primitives
				(gr_poly
					(pts
						(arc
							(start -0.2032 0.2794)
							(mid -0.239121 0.264521)
							(end -0.254 0.2286)
						)
						(arc
							(start -0.254 -0.2286)
							(mid -0.239121 -0.264521)
							(end -0.2032 -0.2794)
						)
						(arc
							(start 0.2032 -0.2794)
							(mid 0.239121 -0.264521)
							(end 0.254 -0.2286)
						)
						(arc
							(start 0.254 0.2286)
							(mid 0.239121 0.264521)
							(end 0.2032 0.2794)
						)
					)
					(width 0)
					(fill yes)
				)
			)
		)
		(pad "2" smd custom
			(at 0 0.4318 180)
			(size 0.127 0.127)
			(layers "B.Cu" "B.Mask" "B.Paste")
			(net "IRQ_CPU_LV_IERR#")
			(options
				(clearance outline)
				(anchor circle)
			)
			(primitives
				(gr_poly
					(pts
						(arc
							(start -0.2032 0.2794)
							(mid -0.239121 0.264521)
							(end -0.254 0.2286)
						)
						(arc
							(start -0.254 -0.2286)
							(mid -0.239121 -0.264521)
							(end -0.2032 -0.2794)
						)
						(arc
							(start 0.2032 -0.2794)
							(mid 0.239121 -0.264521)
							(end 0.254 -0.2286)
						)
						(arc
							(start 0.254 0.2286)
							(mid 0.239121 0.264521)
							(end 0.2032 0.2794)
						)
					)
					(width 0)
					(fill yes)
				)
			)
		)
	)
	(footprint ""
		(layer "B.Cu")
		(at 201.295 -42.6466 90)
		(property "Reference" "LED12"
			(at 0 0 90)
			(layer "B.SilkS")
			(hide yes)
			(effects
				(font
					(size 1.27 1.27)
				)
				(justify mirror)
			)
		)
		(property "Value" "LED-YG-51-GP"
			(at 0.0381 -2.6162 90)
			(unlocked yes)
			(layer "B.Fab")
			(hide yes)
			(effects
				(font
					(size 1.016 1.016)
					(thickness 0.1524)
				)
				(justify mirror)
			)
		)
		(property "Device Type" "LED1608AKH40"
			(at 0.0381 -4.1402 90)
			(unlocked yes)
			(layer "B.Fab")
			(hide yes)
			(effects
				(font
					(size 1.016 1.016)
					(thickness 0.1524)
				)
				(justify mirror)
			)
		)
		(duplicate_pad_numbers_are_jumpers no)
		(fp_line
			(start 0.5334 1.3081)
			(end -0.5334 1.3081)
			(stroke
				(width 0.254)
				(type default)
			)
			(layer "B.SilkS")
		)
		(fp_rect
			(start 0.6604 1.1811)
			(end -0.6604 -1.1811)
			(stroke
				(width 0)
				(type default)
			)
			(fill no)
			(layer "B.CrtYd")
		)
		(fp_rect
			(start 0.6604 1.1811)
			(end -0.6604 -1.1811)
			(stroke
				(width 0)
				(type default)
			)
			(fill no)
			(layer "B.Fab")
		)
		(pad "A" smd rect
			(at 0 -0.652526 270)
			(size 1.0668 0.8128)
			(layers "B.Cu" "B.Mask" "B.Paste")
			(net "PORT80_R_BIT7")
		)
		(pad "K" smd rect
			(at 0 0.652526 270)
			(size 1.0668 0.8128)
			(layers "B.Cu" "B.Mask" "B.Paste")
			(net "PORT80_BIT7")
		)
	)
	(footprint ""
		(layer "B.Cu")
		(at 30.41904 -48.620426 90)
		(property "Reference" "PU14"
			(at 0 0 90)
			(layer "B.SilkS")
			(hide yes)
			(effects
				(font
					(size 1.27 1.27)
				)
				(justify mirror)
			)
		)
		(property "Value" "TPS74801RGW-GP"
			(at 3.7084 -0.127 90)
			(unlocked yes)
			(layer "B.Fab")
			(hide yes)
			(effects
				(font
					(size 1.016 1.016)
					(thickness 0.1524)
				)
				(justify mirror)
			)
		)
		(property "Device Type" "QFN20-1G3D15H40"
			(at 3.7084 -1.651 90)
			(unlocked yes)
			(layer "B.Fab")
			(hide yes)
			(effects
				(font
					(size 1.016 1.016)
					(thickness 0.1524)
				)
				(justify mirror)
			)
		)
		(duplicate_pad_numbers_are_jumpers no)
		(fp_poly
			(pts
				(xy -1.3208 -2.884932) (xy -1.941068 -3.5052) (xy -0.700786 -3.5052)
			)
			(stroke
				(width 0)
				(type default)
			)
			(fill yes)
			(layer "B.SilkS")
		)
		(fp_rect
			(start 2.8829 2.8829)
			(end -2.8829 -2.8829)
			(stroke
				(width 0)
				(type default)
			)
			(fill no)
			(layer "B.CrtYd")
		)
		(fp_rect
			(start 2.8829 2.8829)
			(end -2.8829 -2.8829)
			(stroke
				(width 0)
				(type default)
			)
			(fill no)
			(layer "B.Fab")
		)
		(pad "1" smd rect
			(at -1.299972 -2.347722 270)
			(size 0.3556 0.8128)
			(layers "B.Cu" "B.Mask" "B.Paste")
			(net "P1V5_STBY_OUT")
		)
		(pad "2" smd rect
			(at -0.649986 -2.347722 270)
			(size 0.3556 0.8128)
			(layers "B.Cu" "B.Mask" "B.Paste")
			(net "GND")
		)
		(pad "3" smd rect
			(at 0 -2.347722 270)
			(size 0.3556 0.8128)
			(layers "B.Cu" "B.Mask" "B.Paste")
			(net "GND")
		)
		(pad "4" smd rect
			(at 0.649986 -2.347722 270)
			(size 0.3556 0.8128)
			(layers "B.Cu" "B.Mask" "B.Paste")
			(net "GND")
		)
		(pad "5" smd rect
			(at 1.299972 -2.347722 270)
			(size 0.3556 0.8128)
			(layers "B.Cu" "B.Mask" "B.Paste")
			(net "P1V5_STBY_IN")
		)
		(pad "6" smd rect
			(at 2.347722 -1.299972 270)
			(size 0.8128 0.3556)
			(layers "B.Cu" "B.Mask" "B.Paste")
			(net "P1V5_STBY_IN")
		)
		(pad "7" smd rect
			(at 2.347722 -0.649986 270)
			(size 0.8128 0.3556)
			(layers "B.Cu" "B.Mask" "B.Paste")
			(net "P1V5_STBY_IN")
		)
		(pad "8" smd rect
			(at 2.347722 0 270)
			(size 0.8128 0.3556)
			(layers "B.Cu" "B.Mask" "B.Paste")
			(net "P1V5_STBY_IN")
		)
		(pad "9" smd rect
			(at 2.347722 0.649986 270)
			(size 0.8128 0.3556)
			(layers "B.Cu" "B.Mask" "B.Paste")
			(net "P1V5_STBY_PG")
		)
		(pad "10" smd rect
			(at 2.347722 1.299972 270)
			(size 0.8128 0.3556)
			(layers "B.Cu" "B.Mask" "B.Paste")
			(net "P1V5_STBY_BIAS")
		)
		(pad "11" smd rect
			(at 1.299972 2.347722 270)
			(size 0.3556 0.8128)
			(layers "B.Cu" "B.Mask" "B.Paste")
			(net "P1V5_STBY_EN")
		)
		(pad "12" smd rect
			(at 0.649986 2.347722 270)
			(size 0.3556 0.8128)
			(layers "B.Cu" "B.Mask" "B.Paste")
			(net "GND")
		)
		(pad "13" smd rect
			(at 0 2.347722 270)
			(size 0.3556 0.8128)
			(layers "B.Cu" "B.Mask" "B.Paste")
			(net "GND")
		)
		(pad "14" smd rect
			(at -0.649986 2.347722 270)
			(size 0.3556 0.8128)
			(layers "B.Cu" "B.Mask" "B.Paste")
			(net "GND")
		)
		(pad "15" smd rect
			(at -1.299972 2.347722 270)
			(size 0.3556 0.8128)
			(layers "B.Cu" "B.Mask" "B.Paste")
			(net "P1V5_STBY_SS")
		)
		(pad "16" smd rect
			(at -2.347722 1.299972 270)
			(size 0.8128 0.3556)
			(layers "B.Cu" "B.Mask" "B.Paste")
			(net "P1V5_STBY_FB")
		)
		(pad "17" smd rect
			(at -2.347722 0.649986 270)
			(size 0.8128 0.3556)
			(layers "B.Cu" "B.Mask" "B.Paste")
			(net "GND")
		)
		(pad "18" smd rect
			(at -2.347722 0 270)
			(size 0.8128 0.3556)
			(layers "B.Cu" "B.Mask" "B.Paste")
			(net "P1V5_STBY_OUT")
		)
		(pad "19" smd rect
			(at -2.347722 -0.649986 270)
			(size 0.8128 0.3556)
			(layers "B.Cu" "B.Mask" "B.Paste")
			(net "P1V5_STBY_OUT")
		)
		(pad "20" smd rect
			(at -2.347722 -1.299972 270)
			(size 0.8128 0.3556)
			(layers "B.Cu" "B.Mask" "B.Paste")
			(net "P1V5_STBY_OUT")
		)
		(pad "21" smd rect
			(at 0 0 270)
			(size 3.2512 3.2512)
			(layers "B.Cu" "B.Mask" "B.Paste")
			(net "GND")
		)
	)
	(footprint ""
		(layer "B.Cu")
		(at 99.187 -45.2882 -90)
		(property "Reference" "L4"
			(at 0 0 90)
			(layer "B.SilkS")
			(hide yes)
			(effects
				(font
					(size 1.27 1.27)
				)
				(justify mirror)
			)
		)
		(property "Value" "BLM18PG121SN1D-GP"
			(at 0.0254 -2.8956 270)
			(unlocked yes)
			(layer "B.Fab")
			(hide yes)
			(effects
				(font
					(size 1.016 1.016)
					(thickness 0.1524)
				)
				(justify mirror)
			)
		)
		(property "Device Type" "L1608-UH38"
			(at 0.0254 -4.4196 270)
			(unlocked yes)
			(layer "B.Fab")
			(hide yes)
			(effects
				(font
					(size 1.016 1.016)
					(thickness 0.1524)
				)
				(justify mirror)
			)
		)
		(duplicate_pad_numbers_are_jumpers no)
		(fp_line
			(start 0.4064 0)
			(end -0.4064 0)
			(stroke
				(width 0.2032)
				(type default)
			)
			(layer "B.SilkS")
		)
		(fp_rect
			(start 0.635 1.1811)
			(end -0.635 -1.1811)
			(stroke
				(width 0)
				(type default)
			)
			(fill no)
			(layer "B.CrtYd")
		)
		(fp_rect
			(start 0.635 1.1811)
			(end -0.635 -1.1811)
			(stroke
				(width 0)
				(type default)
			)
			(fill no)
			(layer "B.Fab")
		)
		(pad "1" smd custom
			(at 0 -0.6604 90)
			(size 0.19685 0.19685)
			(layers "B.Cu" "B.Mask" "B.Paste")
			(net "PV_VDDR")
			(options
				(clearance outline)
				(anchor circle)
			)
			(primitives
				(gr_poly
					(pts
						(arc
							(start 0.508 0.2921)
							(mid 0.478242 0.363942)
							(end 0.4064 0.3937)
						)
						(arc
							(start -0.4064 0.3937)
							(mid -0.478242 0.363942)
							(end -0.508 0.2921)
						)
						(arc
							(start -0.508 -0.2921)
							(mid -0.478242 -0.363942)
							(end -0.4064 -0.3937)
						)
						(arc
							(start 0.4064 -0.3937)
							(mid 0.478242 -0.363942)
							(end 0.508 -0.2921)
						)
					)
					(width 0)
					(fill yes)
				)
			)
		)
		(pad "2" smd custom
			(at 0 0.6604 90)
			(size 0.19685 0.19685)
			(layers "B.Cu" "B.Mask" "B.Paste")
			(net "VCCCLKDDR0")
			(options
				(clearance outline)
				(anchor circle)
			)
			(primitives
				(gr_poly
					(pts
						(arc
							(start 0.508 0.2921)
							(mid 0.478242 0.363942)
							(end 0.4064 0.3937)
						)
						(arc
							(start -0.4064 0.3937)
							(mid -0.478242 0.363942)
							(end -0.508 0.2921)
						)
						(arc
							(start -0.508 -0.2921)
							(mid -0.478242 -0.363942)
							(end -0.4064 -0.3937)
						)
						(arc
							(start 0.4064 -0.3937)
							(mid 0.478242 -0.363942)
							(end 0.508 -0.2921)
						)
					)
					(width 0)
					(fill yes)
				)
			)
		)
	)
	(footprint ""
		(layer "B.Cu")
		(at 51.816 -58.547 90)
		(property "Reference" "PR89"
			(at 0 0 90)
			(layer "B.SilkS")
			(hide yes)
			(effects
				(font
					(size 1.27 1.27)
				)
				(justify mirror)
			)
		)
		(property "Value" "0R2J-2-GP"
			(at -0.064008 -3.993896 90)
			(unlocked yes)
			(layer "B.Fab")
			(hide yes)
			(effects
				(font
					(size 1.016 1.016)
					(thickness 0.1524)
				)
				(justify mirror)
			)
		)
		(property "Device Type" "R402H16"
			(at -0.064008 -5.517896 90)
			(unlocked yes)
			(layer "B.Fab")
			(hide yes)
			(effects
				(font
					(size 1.016 1.016)
					(thickness 0.1524)
				)
				(justify mirror)
			)
		)
		(duplicate_pad_numbers_are_jumpers no)
		(fp_rect
			(start 0.381 0.8382)
			(end -0.381 -0.8382)
			(stroke
				(width 0)
				(type default)
			)
			(fill no)
			(layer "B.CrtYd")
		)
		(fp_rect
			(start 0.381 0.8382)
			(end -0.381 -0.8382)
			(stroke
				(width 0)
				(type default)
			)
			(fill no)
			(layer "B.Fab")
		)
		(pad "1" smd custom
			(at 0 -0.4318 270)
			(size 0.127 0.127)
			(layers "B.Cu" "B.Mask" "B.Paste")
			(net "VR_PVCCP_ISUMN_R2")
			(options
				(clearance outline)
				(anchor circle)
			)
			(primitives
				(gr_poly
					(pts
						(arc
							(start -0.2032 0.2794)
							(mid -0.239121 0.264521)
							(end -0.254 0.2286)
						)
						(arc
							(start -0.254 -0.2286)
							(mid -0.239121 -0.264521)
							(end -0.2032 -0.2794)
						)
						(arc
							(start 0.2032 -0.2794)
							(mid 0.239121 -0.264521)
							(end 0.254 -0.2286)
						)
						(arc
							(start 0.254 0.2286)
							(mid 0.239121 0.264521)
							(end 0.2032 0.2794)
						)
					)
					(width 0)
					(fill yes)
				)
			)
		)
		(pad "2" smd custom
			(at 0 0.4318 270)
			(size 0.127 0.127)
			(layers "B.Cu" "B.Mask" "B.Paste")
			(net "PVCCP")
			(options
				(clearance outline)
				(anchor circle)
			)
			(primitives
				(gr_poly
					(pts
						(arc
							(start -0.2032 0.2794)
							(mid -0.239121 0.264521)
							(end -0.254 0.2286)
						)
						(arc
							(start -0.254 -0.2286)
							(mid -0.239121 -0.264521)
							(end -0.2032 -0.2794)
						)
						(arc
							(start 0.2032 -0.2794)
							(mid 0.239121 -0.264521)
							(end 0.254 -0.2286)
						)
						(arc
							(start 0.254 0.2286)
							(mid 0.239121 0.264521)
							(end 0.2032 0.2794)
						)
					)
					(width 0)
					(fill yes)
				)
			)
		)
	)
	(footprint ""
		(layer "B.Cu")
		(at 189.865 -16.383 180)
		(property "Reference" "C289"
			(at 0 0 0)
			(layer "B.SilkS")
			(hide yes)
			(effects
				(font
					(size 1.27 1.27)
				)
				(justify mirror)
			)
		)
		(property "Value" "SC10U6D3V3MX-GP"
			(at 0 -2.8194 180)
			(unlocked yes)
			(layer "B.Fab")
			(hide yes)
			(effects
				(font
					(size 1.016 1.016)
					(thickness 0.1524)
				)
				(justify mirror)
			)
		)
		(property "Device Type" "C603H38"
			(at 0 -4.3434 180)
			(unlocked yes)
			(layer "B.Fab")
			(hide yes)
			(effects
				(font
					(size 1.016 1.016)
					(thickness 0.1524)
				)
				(justify mirror)
			)
		)
		(duplicate_pad_numbers_are_jumpers no)
		(fp_line
			(start 0.4064 0)
			(end -0.4064 0)
			(stroke
				(width 0.2286)
				(type default)
			)
			(layer "B.SilkS")
		)
		(fp_rect
			(start 0.635 1.1811)
			(end -0.635 -1.1811)
			(stroke
				(width 0)
				(type default)
			)
			(fill no)
			(layer "B.CrtYd")
		)
		(fp_rect
			(start 0.635 1.1811)
			(end -0.635 -1.1811)
			(stroke
				(width 0)
				(type default)
			)
			(fill no)
			(layer "B.Fab")
		)
		(pad "1" smd custom
			(at 0 -0.6604)
			(size 0.19685 0.19685)
			(layers "B.Cu" "B.Mask" "B.Paste")
			(net "PV_VTT_DDR_B")
			(options
				(clearance outline)
				(anchor circle)
			)
			(primitives
				(gr_poly
					(pts
						(arc
							(start 0.508 0.2921)
							(mid 0.478242 0.363942)
							(end 0.4064 0.3937)
						)
						(arc
							(start -0.4064 0.3937)
							(mid -0.478242 0.363942)
							(end -0.508 0.2921)
						)
						(arc
							(start -0.508 -0.2921)
							(mid -0.478242 -0.363942)
							(end -0.4064 -0.3937)
						)
						(arc
							(start 0.4064 -0.3937)
							(mid 0.478242 -0.363942)
							(end 0.508 -0.2921)
						)
					)
					(width 0)
					(fill yes)
				)
			)
		)
		(pad "2" smd custom
			(at 0 0.6604)
			(size 0.19685 0.19685)
			(layers "B.Cu" "B.Mask" "B.Paste")
			(net "GND")
			(options
				(clearance outline)
				(anchor circle)
			)
			(primitives
				(gr_poly
					(pts
						(arc
							(start 0.508 0.2921)
							(mid 0.478242 0.363942)
							(end 0.4064 0.3937)
						)
						(arc
							(start -0.4064 0.3937)
							(mid -0.478242 0.363942)
							(end -0.508 0.2921)
						)
						(arc
							(start -0.508 -0.2921)
							(mid -0.478242 -0.363942)
							(end -0.4064 -0.3937)
						)
						(arc
							(start 0.4064 -0.3937)
							(mid 0.478242 -0.363942)
							(end 0.508 -0.2921)
						)
					)
					(width 0)
					(fill yes)
				)
			)
		)
	)
	(footprint ""
		(layer "B.Cu")
		(at 146.431 -44.958 180)
		(property "Reference" "R130"
			(at 0 0 0)
			(layer "B.SilkS")
			(hide yes)
			(effects
				(font
					(size 1.27 1.27)
				)
				(justify mirror)
			)
		)
		(property "Value" "10KR2F-2-GP"
			(at -0.064008 -3.993896 180)
			(unlocked yes)
			(layer "B.Fab")
			(hide yes)
			(effects
				(font
					(size 1.016 1.016)
					(thickness 0.1524)
				)
				(justify mirror)
			)
		)
		(property "Device Type" "R402H16"
			(at -0.064008 -5.517896 180)
			(unlocked yes)
			(layer "B.Fab")
			(hide yes)
			(effects
				(font
					(size 1.016 1.016)
					(thickness 0.1524)
				)
				(justify mirror)
			)
		)
		(duplicate_pad_numbers_are_jumpers no)
		(fp_rect
			(start 0.381 0.8382)
			(end -0.381 -0.8382)
			(stroke
				(width 0)
				(type default)
			)
			(fill no)
			(layer "B.CrtYd")
		)
		(fp_rect
			(start 0.381 0.8382)
			(end -0.381 -0.8382)
			(stroke
				(width 0)
				(type default)
			)
			(fill no)
			(layer "B.Fab")
		)
		(pad "1" smd custom
			(at 0 -0.4318)
			(size 0.127 0.127)
			(layers "B.Cu" "B.Mask" "B.Paste")
			(net "P3V3_STBY")
			(options
				(clearance outline)
				(anchor circle)
			)
			(primitives
				(gr_poly
					(pts
						(arc
							(start -0.2032 0.2794)
							(mid -0.239121 0.264521)
							(end -0.254 0.2286)
						)
						(arc
							(start -0.254 -0.2286)
							(mid -0.239121 -0.264521)
							(end -0.2032 -0.2794)
						)
						(arc
							(start 0.2032 -0.2794)
							(mid 0.239121 -0.264521)
							(end 0.254 -0.2286)
						)
						(arc
							(start 0.254 0.2286)
							(mid 0.239121 0.264521)
							(end 0.2032 0.2794)
						)
					)
					(width 0)
					(fill yes)
				)
			)
		)
		(pad "2" smd custom
			(at 0 0.4318)
			(size 0.127 0.127)
			(layers "B.Cu" "B.Mask" "B.Paste")
			(net "C_NSTATUS#")
			(options
				(clearance outline)
				(anchor circle)
			)
			(primitives
				(gr_poly
					(pts
						(arc
							(start -0.2032 0.2794)
							(mid -0.239121 0.264521)
							(end -0.254 0.2286)
						)
						(arc
							(start -0.254 -0.2286)
							(mid -0.239121 -0.264521)
							(end -0.2032 -0.2794)
						)
						(arc
							(start 0.2032 -0.2794)
							(mid 0.239121 -0.264521)
							(end 0.254 -0.2286)
						)
						(arc
							(start 0.254 0.2286)
							(mid 0.239121 0.264521)
							(end 0.2032 0.2794)
						)
					)
					(width 0)
					(fill yes)
				)
			)
		)
	)
	(footprint ""
		(layer "B.Cu")
		(at 15.875 -55.372 -90)
		(property "Reference" "R370"
			(at 0 0 90)
			(layer "B.SilkS")
			(hide yes)
			(effects
				(font
					(size 1.27 1.27)
				)
				(justify mirror)
			)
		)
		(property "Value" "0R2J-2-GP"
			(at -1.7907 -1.1176 270)
			(unlocked yes)
			(layer "B.Fab")
			(hide yes)
			(effects
				(font
					(size 1.016 1.016)
					(thickness 0.1524)
				)
				(justify mirror)
			)
		)
		(property "Device Type" "R402H16"
			(at -1.7907 -2.6416 270)
			(unlocked yes)
			(layer "B.Fab")
			(hide yes)
			(effects
				(font
					(size 1.016 1.016)
					(thickness 0.1524)
				)
				(justify mirror)
			)
		)
		(duplicate_pad_numbers_are_jumpers no)
		(fp_rect
			(start 0.381 0.8382)
			(end -0.381 -0.8382)
			(stroke
				(width 0)
				(type default)
			)
			(fill no)
			(layer "B.CrtYd")
		)
		(fp_rect
			(start 0.381 0.8382)
			(end -0.381 -0.8382)
			(stroke
				(width 0)
				(type default)
			)
			(fill no)
			(layer "B.Fab")
		)
		(pad "1" smd custom
			(at 0 -0.4318 90)
			(size 0.127 0.127)
			(layers "B.Cu" "B.Mask" "B.Paste")
			(net "PMU_PLTRST#")
			(options
				(clearance outline)
				(anchor circle)
			)
			(primitives
				(gr_poly
					(pts
						(arc
							(start -0.2032 0.2794)
							(mid -0.239121 0.264521)
							(end -0.254 0.2286)
						)
						(arc
							(start -0.254 -0.2286)
							(mid -0.239121 -0.264521)
							(end -0.2032 -0.2794)
						)
						(arc
							(start 0.2032 -0.2794)
							(mid 0.239121 -0.264521)
							(end 0.254 -0.2286)
						)
						(arc
							(start 0.254 0.2286)
							(mid 0.239121 0.264521)
							(end 0.2032 0.2794)
						)
					)
					(width 0)
					(fill yes)
				)
			)
		)
		(pad "2" smd custom
			(at 0 0.4318 90)
			(size 0.127 0.127)
			(layers "B.Cu" "B.Mask" "B.Paste")
			(net "RST_PCIE_PCH_DEV_R#")
			(options
				(clearance outline)
				(anchor circle)
			)
			(primitives
				(gr_poly
					(pts
						(arc
							(start -0.2032 0.2794)
							(mid -0.239121 0.264521)
							(end -0.254 0.2286)
						)
						(arc
							(start -0.254 -0.2286)
							(mid -0.239121 -0.264521)
							(end -0.2032 -0.2794)
						)
						(arc
							(start 0.2032 -0.2794)
							(mid 0.239121 -0.264521)
							(end 0.254 -0.2286)
						)
						(arc
							(start 0.254 0.2286)
							(mid 0.239121 0.264521)
							(end 0.2032 0.2794)
						)
					)
					(width 0)
					(fill yes)
				)
			)
		)
	)
	(footprint ""
		(layer "B.Cu")
		(at 94.742 -18.5928 90)
		(property "Reference" "L7"
			(at 0 0 90)
			(layer "B.SilkS")
			(hide yes)
			(effects
				(font
					(size 1.27 1.27)
				)
				(justify mirror)
			)
		)
		(property "Value" "BLM18PG121SN1D-GP"
			(at 0.0254 -2.8956 90)
			(unlocked yes)
			(layer "B.Fab")
			(hide yes)
			(effects
				(font
					(size 1.016 1.016)
					(thickness 0.1524)
				)
				(justify mirror)
			)
		)
		(property "Device Type" "L1608-UH38"
			(at 0.0254 -4.4196 90)
			(unlocked yes)
			(layer "B.Fab")
			(hide yes)
			(effects
				(font
					(size 1.016 1.016)
					(thickness 0.1524)
				)
				(justify mirror)
			)
		)
		(duplicate_pad_numbers_are_jumpers no)
		(fp_line
			(start 0.4064 0)
			(end -0.4064 0)
			(stroke
				(width 0.2032)
				(type default)
			)
			(layer "B.SilkS")
		)
		(fp_rect
			(start 0.635 1.1811)
			(end -0.635 -1.1811)
			(stroke
				(width 0)
				(type default)
			)
			(fill no)
			(layer "B.CrtYd")
		)
		(fp_rect
			(start 0.635 1.1811)
			(end -0.635 -1.1811)
			(stroke
				(width 0)
				(type default)
			)
			(fill no)
			(layer "B.Fab")
		)
		(pad "1" smd custom
			(at 0 -0.6604 270)
			(size 0.19685 0.19685)
			(layers "B.Cu" "B.Mask" "B.Paste")
			(net "P1V0")
			(options
				(clearance outline)
				(anchor circle)
			)
			(primitives
				(gr_poly
					(pts
						(arc
							(start 0.508 0.2921)
							(mid 0.478242 0.363942)
							(end 0.4064 0.3937)
						)
						(arc
							(start -0.4064 0.3937)
							(mid -0.478242 0.363942)
							(end -0.508 0.2921)
						)
						(arc
							(start -0.508 -0.2921)
							(mid -0.478242 -0.363942)
							(end -0.4064 -0.3937)
						)
						(arc
							(start 0.4064 -0.3937)
							(mid 0.478242 -0.363942)
							(end 0.508 -0.2921)
						)
					)
					(width 0)
					(fill yes)
				)
			)
		)
		(pad "2" smd custom
			(at 0 0.6604 270)
			(size 0.19685 0.19685)
			(layers "B.Cu" "B.Mask" "B.Paste")
			(net "VCCA_PLLDDR1_AVN")
			(options
				(clearance outline)
				(anchor circle)
			)
			(primitives
				(gr_poly
					(pts
						(arc
							(start 0.508 0.2921)
							(mid 0.478242 0.363942)
							(end 0.4064 0.3937)
						)
						(arc
							(start -0.4064 0.3937)
							(mid -0.478242 0.363942)
							(end -0.508 0.2921)
						)
						(arc
							(start -0.508 -0.2921)
							(mid -0.478242 -0.363942)
							(end -0.4064 -0.3937)
						)
						(arc
							(start 0.4064 -0.3937)
							(mid 0.478242 -0.363942)
							(end 0.508 -0.2921)
						)
					)
					(width 0)
					(fill yes)
				)
			)
		)
	)
	(footprint ""
		(layer "B.Cu")
		(at 89.662 -39.243 180)
		(property "Reference" "R320"
			(at 0 0 0)
			(layer "B.SilkS")
			(hide yes)
			(effects
				(font
					(size 1.27 1.27)
				)
				(justify mirror)
			)
		)
		(property "Value" "49D9R2F-GP"
			(at -0.064008 -3.993896 180)
			(unlocked yes)
			(layer "B.Fab")
			(hide yes)
			(effects
				(font
					(size 1.016 1.016)
					(thickness 0.1524)
				)
				(justify mirror)
			)
		)
		(property "Device Type" "R402H16"
			(at -0.064008 -5.517896 180)
			(unlocked yes)
			(layer "B.Fab")
			(hide yes)
			(effects
				(font
					(size 1.016 1.016)
					(thickness 0.1524)
				)
				(justify mirror)
			)
		)
		(duplicate_pad_numbers_are_jumpers no)
		(fp_rect
			(start 0.381 0.8382)
			(end -0.381 -0.8382)
			(stroke
				(width 0)
				(type default)
			)
			(fill no)
			(layer "B.CrtYd")
		)
		(fp_rect
			(start 0.381 0.8382)
			(end -0.381 -0.8382)
			(stroke
				(width 0)
				(type default)
			)
			(fill no)
			(layer "B.Fab")
		)
		(pad "1" smd custom
			(at 0 -0.4318)
			(size 0.127 0.127)
			(layers "B.Cu" "B.Mask" "B.Paste")
			(net "RCOMP_CORE_LVT")
			(options
				(clearance outline)
				(anchor circle)
			)
			(primitives
				(gr_poly
					(pts
						(arc
							(start -0.2032 0.2794)
							(mid -0.239121 0.264521)
							(end -0.254 0.2286)
						)
						(arc
							(start -0.254 -0.2286)
							(mid -0.239121 -0.264521)
							(end -0.2032 -0.2794)
						)
						(arc
							(start 0.2032 -0.2794)
							(mid 0.239121 -0.264521)
							(end 0.254 -0.2286)
						)
						(arc
							(start 0.254 0.2286)
							(mid 0.239121 0.264521)
							(end 0.2032 0.2794)
						)
					)
					(width 0)
					(fill yes)
				)
			)
		)
		(pad "2" smd custom
			(at 0 0.4318)
			(size 0.127 0.127)
			(layers "B.Cu" "B.Mask" "B.Paste")
			(net "GND")
			(options
				(clearance outline)
				(anchor circle)
			)
			(primitives
				(gr_poly
					(pts
						(arc
							(start -0.2032 0.2794)
							(mid -0.239121 0.264521)
							(end -0.254 0.2286)
						)
						(arc
							(start -0.254 -0.2286)
							(mid -0.239121 -0.264521)
							(end -0.2032 -0.2794)
						)
						(arc
							(start 0.2032 -0.2794)
							(mid 0.239121 -0.264521)
							(end 0.254 -0.2286)
						)
						(arc
							(start 0.254 0.2286)
							(mid 0.239121 0.264521)
							(end 0.2032 0.2794)
						)
					)
					(width 0)
					(fill yes)
				)
			)
		)
	)
	(footprint ""
		(layer "B.Cu")
		(at 115.824 -41.3512 90)
		(property "Reference" "PTC5"
			(at 0 0 90)
			(layer "B.SilkS")
			(hide yes)
			(effects
				(font
					(size 1.27 1.27)
				)
				(justify mirror)
			)
		)
		(property "Value" "SE470UF2VDM-GP"
			(at 0 -9.6012 90)
			(unlocked yes)
			(layer "B.Fab")
			(hide yes)
			(effects
				(font
					(size 1.016 1.016)
					(thickness 0.1524)
				)
				(justify mirror)
			)
		)
		(property "Device Type" "CT7343H83"
			(at 0 -11.1252 90)
			(unlocked yes)
			(layer "B.Fab")
			(hide yes)
			(effects
				(font
					(size 1.016 1.016)
					(thickness 0.1524)
				)
				(justify mirror)
			)
		)
		(duplicate_pad_numbers_are_jumpers no)
		(fp_line
			(start 2.206752 -4.2926)
			(end -2.155698 -4.2926)
			(stroke
				(width 0.508)
				(type default)
			)
			(layer "B.SilkS")
		)
		(fp_rect
			(start 2.1463 3.6449)
			(end -2.1463 -3.6449)
			(stroke
				(width 0)
				(type default)
			)
			(fill no)
			(layer "B.CrtYd")
		)
		(fp_poly
			(pts
				(xy 3.81 3.9116) (xy 3.81 -3.9116) (xy 2.54 -3.9116) (xy 2.4003 -3.9116) (xy 2.4003 -4.0386) (xy -2.4003 -4.0386)
				(xy -2.4003 -3.9116) (xy -2.54 -3.9116) (xy -2.5654 -3.9116) (xy -3.81 -3.9116) (xy -3.81 -1.6256)
				(xy -2.1463 -1.6256) (xy -2.1463 -3.6449) (xy 2.1463 -3.6449) (xy 2.1463 3.6449) (xy -2.1463 3.6449)
				(xy -2.1463 -1.6129) (xy -3.81 -1.6129) (xy -3.81 3.9116) (xy -2.4003 3.9116) (xy -2.4003 3.9243)
				(xy -2.4003 4.0386) (xy 2.4003 4.0386) (xy 2.4003 3.9116)
			)
			(stroke
				(width 0)
				(type default)
			)
			(fill no)
			(layer "B.CrtYd")
		)
		(fp_rect
			(start 3.81 3.9116)
			(end 2.4003 -3.9116)
			(stroke
				(width 0)
				(type default)
			)
			(fill no)
			(layer "B.Fab")
		)
		(fp_rect
			(start -2.4003 3.9116)
			(end -3.81 -3.9116)
			(stroke
				(width 0)
				(type default)
			)
			(fill no)
			(layer "B.Fab")
		)
		(fp_rect
			(start 2.4003 4.0386)
			(end -2.4003 -4.0386)
			(stroke
				(width 0)
				(type default)
			)
			(fill no)
			(layer "B.Fab")
		)
		(pad "1" smd rect
			(at 0 -2.9591 270)
			(size 2.413 1.905)
			(layers "B.Cu" "B.Mask" "B.Paste")
			(net "PVCCP")
		)
		(pad "2" smd rect
			(at 0 2.9591 270)
			(size 2.413 1.905)
			(layers "B.Cu" "B.Mask" "B.Paste")
			(net "GND")
		)
	)
	(footprint ""
		(layer "B.Cu")
		(at 86.82736 -26.07056)
		(property "Reference" "R378"
			(at 0 0 0)
			(layer "B.SilkS")
			(hide yes)
			(effects
				(font
					(size 1.27 1.27)
				)
				(justify mirror)
			)
		)
		(property "Value" "1KR2F-3-GP"
			(at -0.064008 -3.993896 0)
			(unlocked yes)
			(layer "B.Fab")
			(hide yes)
			(effects
				(font
					(size 1.016 1.016)
					(thickness 0.1524)
				)
				(justify mirror)
			)
		)
		(property "Device Type" "R402H16"
			(at -0.064008 -5.517896 0)
			(unlocked yes)
			(layer "B.Fab")
			(hide yes)
			(effects
				(font
					(size 1.016 1.016)
					(thickness 0.1524)
				)
				(justify mirror)
			)
		)
		(duplicate_pad_numbers_are_jumpers no)
		(fp_rect
			(start 0.381 0.8382)
			(end -0.381 -0.8382)
			(stroke
				(width 0)
				(type default)
			)
			(fill no)
			(layer "B.CrtYd")
		)
		(fp_rect
			(start 0.381 0.8382)
			(end -0.381 -0.8382)
			(stroke
				(width 0)
				(type default)
			)
			(fill no)
			(layer "B.Fab")
		)
		(pad "1" smd custom
			(at 0 -0.4318 180)
			(size 0.127 0.127)
			(layers "B.Cu" "B.Mask" "B.Paste")
			(net "BD_REV_1")
			(options
				(clearance outline)
				(anchor circle)
			)
			(primitives
				(gr_poly
					(pts
						(arc
							(start -0.2032 0.2794)
							(mid -0.239121 0.264521)
							(end -0.254 0.2286)
						)
						(arc
							(start -0.254 -0.2286)
							(mid -0.239121 -0.264521)
							(end -0.2032 -0.2794)
						)
						(arc
							(start 0.2032 -0.2794)
							(mid 0.239121 -0.264521)
							(end 0.254 -0.2286)
						)
						(arc
							(start 0.254 0.2286)
							(mid 0.239121 0.264521)
							(end 0.2032 0.2794)
						)
					)
					(width 0)
					(fill yes)
				)
			)
		)
		(pad "2" smd custom
			(at 0 0.4318 180)
			(size 0.127 0.127)
			(layers "B.Cu" "B.Mask" "B.Paste")
			(net "GND")
			(options
				(clearance outline)
				(anchor circle)
			)
			(primitives
				(gr_poly
					(pts
						(arc
							(start -0.2032 0.2794)
							(mid -0.239121 0.264521)
							(end -0.254 0.2286)
						)
						(arc
							(start -0.254 -0.2286)
							(mid -0.239121 -0.264521)
							(end -0.2032 -0.2794)
						)
						(arc
							(start 0.2032 -0.2794)
							(mid 0.239121 -0.264521)
							(end 0.254 -0.2286)
						)
						(arc
							(start 0.254 0.2286)
							(mid 0.239121 0.264521)
							(end 0.2032 0.2794)
						)
					)
					(width 0)
					(fill yes)
				)
			)
		)
	)
	(footprint ""
		(layer "B.Cu")
		(at 54.229 -52.451 -90)
		(property "Reference" "PR155"
			(at 0 0 90)
			(layer "B.SilkS")
			(hide yes)
			(effects
				(font
					(size 1.27 1.27)
				)
				(justify mirror)
			)
		)
		(property "Value" "10KR2F-2-GP"
			(at -0.064008 -3.993896 270)
			(unlocked yes)
			(layer "B.Fab")
			(hide yes)
			(effects
				(font
					(size 1.016 1.016)
					(thickness 0.1524)
				)
				(justify mirror)
			)
		)
		(property "Device Type" "R402H16"
			(at -0.064008 -5.517896 270)
			(unlocked yes)
			(layer "B.Fab")
			(hide yes)
			(effects
				(font
					(size 1.016 1.016)
					(thickness 0.1524)
				)
				(justify mirror)
			)
		)
		(duplicate_pad_numbers_are_jumpers no)
		(fp_rect
			(start 0.381 0.8382)
			(end -0.381 -0.8382)
			(stroke
				(width 0)
				(type default)
			)
			(fill no)
			(layer "B.CrtYd")
		)
		(fp_rect
			(start 0.381 0.8382)
			(end -0.381 -0.8382)
			(stroke
				(width 0)
				(type default)
			)
			(fill no)
			(layer "B.Fab")
		)
		(pad "1" smd custom
			(at 0 -0.4318 90)
			(size 0.127 0.127)
			(layers "B.Cu" "B.Mask" "B.Paste")
			(net "P1V0_STBY_PG")
			(options
				(clearance outline)
				(anchor circle)
			)
			(primitives
				(gr_poly
					(pts
						(arc
							(start -0.2032 0.2794)
							(mid -0.239121 0.264521)
							(end -0.254 0.2286)
						)
						(arc
							(start -0.254 -0.2286)
							(mid -0.239121 -0.264521)
							(end -0.2032 -0.2794)
						)
						(arc
							(start 0.2032 -0.2794)
							(mid 0.239121 -0.264521)
							(end 0.254 -0.2286)
						)
						(arc
							(start 0.254 0.2286)
							(mid 0.239121 0.264521)
							(end 0.2032 0.2794)
						)
					)
					(width 0)
					(fill yes)
				)
			)
		)
		(pad "2" smd custom
			(at 0 0.4318 90)
			(size 0.127 0.127)
			(layers "B.Cu" "B.Mask" "B.Paste")
			(net "P3V3_STBY")
			(options
				(clearance outline)
				(anchor circle)
			)
			(primitives
				(gr_poly
					(pts
						(arc
							(start -0.2032 0.2794)
							(mid -0.239121 0.264521)
							(end -0.254 0.2286)
						)
						(arc
							(start -0.254 -0.2286)
							(mid -0.239121 -0.264521)
							(end -0.2032 -0.2794)
						)
						(arc
							(start 0.2032 -0.2794)
							(mid 0.239121 -0.264521)
							(end 0.254 -0.2286)
						)
						(arc
							(start 0.254 0.2286)
							(mid 0.239121 0.264521)
							(end 0.2032 0.2794)
						)
					)
					(width 0)
					(fill yes)
				)
			)
		)
	)
	(footprint ""
		(layer "B.Cu")
		(at 34.671 -17.018 90)
		(property "Reference" "R435"
			(at 0 0 90)
			(layer "B.SilkS")
			(hide yes)
			(effects
				(font
					(size 1.27 1.27)
				)
				(justify mirror)
			)
		)
		(property "Value" "0R2J-2-GP"
			(at -1.7907 -1.1176 90)
			(unlocked yes)
			(layer "B.Fab")
			(hide yes)
			(effects
				(font
					(size 1.016 1.016)
					(thickness 0.1524)
				)
				(justify mirror)
			)
		)
		(property "Device Type" "R402H16"
			(at -1.7907 -2.6416 90)
			(unlocked yes)
			(layer "B.Fab")
			(hide yes)
			(effects
				(font
					(size 1.016 1.016)
					(thickness 0.1524)
				)
				(justify mirror)
			)
		)
		(duplicate_pad_numbers_are_jumpers no)
		(fp_rect
			(start 0.381 0.8382)
			(end -0.381 -0.8382)
			(stroke
				(width 0)
				(type default)
			)
			(fill no)
			(layer "B.CrtYd")
		)
		(fp_rect
			(start 0.381 0.8382)
			(end -0.381 -0.8382)
			(stroke
				(width 0)
				(type default)
			)
			(fill no)
			(layer "B.Fab")
		)
		(pad "1" smd custom
			(at 0 -0.4318 270)
			(size 0.127 0.127)
			(layers "B.Cu" "B.Mask" "B.Paste")
			(net "SMBUS_HOST_CLK")
			(options
				(clearance outline)
				(anchor circle)
			)
			(primitives
				(gr_poly
					(pts
						(arc
							(start -0.2032 0.2794)
							(mid -0.239121 0.264521)
							(end -0.254 0.2286)
						)
						(arc
							(start -0.254 -0.2286)
							(mid -0.239121 -0.264521)
							(end -0.2032 -0.2794)
						)
						(arc
							(start 0.2032 -0.2794)
							(mid 0.239121 -0.264521)
							(end 0.254 -0.2286)
						)
						(arc
							(start 0.254 0.2286)
							(mid 0.239121 0.264521)
							(end 0.2032 0.2794)
						)
					)
					(width 0)
					(fill yes)
				)
			)
		)
		(pad "2" smd custom
			(at 0 0.4318 270)
			(size 0.127 0.127)
			(layers "B.Cu" "B.Mask" "B.Paste")
			(net "SMB_CLKBUFF_R_CLK")
			(options
				(clearance outline)
				(anchor circle)
			)
			(primitives
				(gr_poly
					(pts
						(arc
							(start -0.2032 0.2794)
							(mid -0.239121 0.264521)
							(end -0.254 0.2286)
						)
						(arc
							(start -0.254 -0.2286)
							(mid -0.239121 -0.264521)
							(end -0.2032 -0.2794)
						)
						(arc
							(start 0.2032 -0.2794)
							(mid 0.239121 -0.264521)
							(end 0.254 -0.2286)
						)
						(arc
							(start 0.254 0.2286)
							(mid 0.239121 0.264521)
							(end 0.2032 0.2794)
						)
					)
					(width 0)
					(fill yes)
				)
			)
		)
	)
	(footprint ""
		(layer "B.Cu")
		(at 72.898 -13.589)
		(property "Reference" "C279"
			(at 0 0 0)
			(layer "B.SilkS")
			(hide yes)
			(effects
				(font
					(size 1.27 1.27)
				)
				(justify mirror)
			)
		)
		(property "Value" "SCD1U16V2KX-3GP"
			(at -1.1811 -2.7051 0)
			(unlocked yes)
			(layer "B.Fab")
			(hide yes)
			(effects
				(font
					(size 1.016 1.016)
					(thickness 0.1524)
				)
				(justify mirror)
			)
		)
		(property "Device Type" "C402H22"
			(at -1.1811 -4.2291 0)
			(unlocked yes)
			(layer "B.Fab")
			(hide yes)
			(effects
				(font
					(size 1.016 1.016)
					(thickness 0.1524)
				)
				(justify mirror)
			)
		)
		(duplicate_pad_numbers_are_jumpers no)
		(fp_rect
			(start 0.381 0.7366)
			(end -0.381 -0.7366)
			(stroke
				(width 0)
				(type default)
			)
			(fill no)
			(layer "B.CrtYd")
		)
		(fp_rect
			(start 0.381 0.7366)
			(end -0.381 -0.7366)
			(stroke
				(width 0)
				(type default)
			)
			(fill no)
			(layer "B.Fab")
		)
		(pad "1" smd custom
			(at 0 -0.4572 180)
			(size 0.1143 0.1143)
			(layers "B.Cu" "B.Mask" "B.Paste")
			(net "P2E_CPU_SAS_C_TX_DN2")
			(options
				(clearance outline)
				(anchor circle)
			)
			(primitives
				(gr_poly
					(pts
						(arc
							(start -0.254 0.1778)
							(mid -0.239121 0.213721)
							(end -0.2032 0.2286)
						)
						(arc
							(start 0.2032 0.2286)
							(mid 0.239121 0.213721)
							(end 0.254 0.1778)
						)
						(arc
							(start 0.254 -0.1778)
							(mid 0.239121 -0.213721)
							(end 0.2032 -0.2286)
						)
						(arc
							(start -0.2032 -0.2286)
							(mid -0.239121 -0.213721)
							(end -0.254 -0.1778)
						)
					)
					(width 0)
					(fill yes)
				)
			)
		)
		(pad "2" smd custom
			(at 0 0.4572 180)
			(size 0.1143 0.1143)
			(layers "B.Cu" "B.Mask" "B.Paste")
			(net "P2E_CPU_SAS_TX_DN2")
			(options
				(clearance outline)
				(anchor circle)
			)
			(primitives
				(gr_poly
					(pts
						(arc
							(start -0.254 0.1778)
							(mid -0.239121 0.213721)
							(end -0.2032 0.2286)
						)
						(arc
							(start 0.2032 0.2286)
							(mid 0.239121 0.213721)
							(end 0.254 0.1778)
						)
						(arc
							(start 0.254 -0.1778)
							(mid 0.239121 -0.213721)
							(end 0.2032 -0.2286)
						)
						(arc
							(start -0.2032 -0.2286)
							(mid -0.239121 -0.213721)
							(end -0.254 -0.1778)
						)
					)
					(width 0)
					(fill yes)
				)
			)
		)
	)
	(footprint ""
		(layer "B.Cu")
		(at 92.3544 -30.861 90)
		(property "Reference" "C229"
			(at 0 0 90)
			(layer "B.SilkS")
			(hide yes)
			(effects
				(font
					(size 1.27 1.27)
				)
				(justify mirror)
			)
		)
		(property "Value" "SC1U10V2KX-1GP"
			(at -1.1811 -2.7051 90)
			(unlocked yes)
			(layer "B.Fab")
			(hide yes)
			(effects
				(font
					(size 1.016 1.016)
					(thickness 0.1524)
				)
				(justify mirror)
			)
		)
		(property "Device Type" "C402H22"
			(at -1.1811 -4.2291 90)
			(unlocked yes)
			(layer "B.Fab")
			(hide yes)
			(effects
				(font
					(size 1.016 1.016)
					(thickness 0.1524)
				)
				(justify mirror)
			)
		)
		(duplicate_pad_numbers_are_jumpers no)
		(fp_rect
			(start 0.381 0.7366)
			(end -0.381 -0.7366)
			(stroke
				(width 0)
				(type default)
			)
			(fill no)
			(layer "B.CrtYd")
		)
		(fp_rect
			(start 0.381 0.7366)
			(end -0.381 -0.7366)
			(stroke
				(width 0)
				(type default)
			)
			(fill no)
			(layer "B.Fab")
		)
		(pad "1" smd custom
			(at 0 -0.4572 270)
			(size 0.1143 0.1143)
			(layers "B.Cu" "B.Mask" "B.Paste")
			(net "P1V0")
			(options
				(clearance outline)
				(anchor circle)
			)
			(primitives
				(gr_poly
					(pts
						(arc
							(start -0.254 0.1778)
							(mid -0.239121 0.213721)
							(end -0.2032 0.2286)
						)
						(arc
							(start 0.2032 0.2286)
							(mid 0.239121 0.213721)
							(end 0.254 0.1778)
						)
						(arc
							(start 0.254 -0.1778)
							(mid 0.239121 -0.213721)
							(end 0.2032 -0.2286)
						)
						(arc
							(start -0.2032 -0.2286)
							(mid -0.239121 -0.213721)
							(end -0.254 -0.1778)
						)
					)
					(width 0)
					(fill yes)
				)
			)
		)
		(pad "2" smd custom
			(at 0 0.4572 270)
			(size 0.1143 0.1143)
			(layers "B.Cu" "B.Mask" "B.Paste")
			(net "GND")
			(options
				(clearance outline)
				(anchor circle)
			)
			(primitives
				(gr_poly
					(pts
						(arc
							(start -0.254 0.1778)
							(mid -0.239121 0.213721)
							(end -0.2032 0.2286)
						)
						(arc
							(start 0.2032 0.2286)
							(mid 0.239121 0.213721)
							(end 0.254 0.1778)
						)
						(arc
							(start 0.254 -0.1778)
							(mid 0.239121 -0.213721)
							(end 0.2032 -0.2286)
						)
						(arc
							(start -0.2032 -0.2286)
							(mid -0.239121 -0.213721)
							(end -0.254 -0.1778)
						)
					)
					(width 0)
					(fill yes)
				)
			)
		)
	)
	(footprint ""
		(layer "B.Cu")
		(at 18.796 -57.9882)
		(property "Reference" "PR1"
			(at 0 0 0)
			(layer "B.SilkS")
			(hide yes)
			(effects
				(font
					(size 1.27 1.27)
				)
				(justify mirror)
			)
		)
		(property "Value" "100R3F-1-GP"
			(at 0.0254 -2.0193 0)
			(unlocked yes)
			(layer "B.Fab")
			(hide yes)
			(effects
				(font
					(size 1.016 1.016)
					(thickness 0.1524)
				)
				(justify mirror)
			)
		)
		(property "Device Type" "R603H22"
			(at 0.0254 -3.5433 0)
			(unlocked yes)
			(layer "B.Fab")
			(hide yes)
			(effects
				(font
					(size 1.016 1.016)
					(thickness 0.1524)
				)
				(justify mirror)
			)
		)
		(duplicate_pad_numbers_are_jumpers no)
		(fp_line
			(start -0.4318 0)
			(end -0.2032 0)
			(stroke
				(width 0.2032)
				(type default)
			)
			(layer "B.SilkS")
		)
		(fp_line
			(start 0.2032 0)
			(end 0.4191 0)
			(stroke
				(width 0.2032)
				(type default)
			)
			(layer "B.SilkS")
		)
		(fp_rect
			(start 0.635 1.1811)
			(end -0.635 -1.1811)
			(stroke
				(width 0)
				(type default)
			)
			(fill no)
			(layer "B.CrtYd")
		)
		(fp_rect
			(start 0.635 1.1811)
			(end -0.635 -1.1811)
			(stroke
				(width 0)
				(type default)
			)
			(fill no)
			(layer "B.Fab")
		)
		(pad "1" smd custom
			(at 0 -0.6604 180)
			(size 0.19685 0.19685)
			(layers "B.Cu" "B.Mask" "B.Paste")
			(net "VR_PVNN_FB")
			(options
				(clearance outline)
				(anchor circle)
			)
			(primitives
				(gr_poly
					(pts
						(arc
							(start 0.508 0.2921)
							(mid 0.478242 0.363942)
							(end 0.4064 0.3937)
						)
						(arc
							(start -0.4064 0.3937)
							(mid -0.478242 0.363942)
							(end -0.508 0.2921)
						)
						(arc
							(start -0.508 -0.2921)
							(mid -0.478242 -0.363942)
							(end -0.4064 -0.3937)
						)
						(arc
							(start 0.4064 -0.3937)
							(mid 0.478242 -0.363942)
							(end 0.508 -0.2921)
						)
					)
					(width 0)
					(fill yes)
				)
			)
		)
		(pad "2" smd custom
			(at 0 0.6604 180)
			(size 0.19685 0.19685)
			(layers "B.Cu" "B.Mask" "B.Paste")
			(net "VR_PVNN_FB_RC1")
			(options
				(clearance outline)
				(anchor circle)
			)
			(primitives
				(gr_poly
					(pts
						(arc
							(start 0.508 0.2921)
							(mid 0.478242 0.363942)
							(end 0.4064 0.3937)
						)
						(arc
							(start -0.4064 0.3937)
							(mid -0.478242 0.363942)
							(end -0.508 0.2921)
						)
						(arc
							(start -0.508 -0.2921)
							(mid -0.478242 -0.363942)
							(end -0.4064 -0.3937)
						)
						(arc
							(start 0.4064 -0.3937)
							(mid 0.478242 -0.363942)
							(end 0.508 -0.2921)
						)
					)
					(width 0)
					(fill yes)
				)
			)
		)
	)
	(footprint ""
		(layer "B.Cu")
		(at 107.696 -19.939 -90)
		(property "Reference" "L8"
			(at 0 0 90)
			(layer "B.SilkS")
			(hide yes)
			(effects
				(font
					(size 1.27 1.27)
				)
				(justify mirror)
			)
		)
		(property "Value" "BLM18PG121SN1D-GP"
			(at 0.0254 -2.8956 270)
			(unlocked yes)
			(layer "B.Fab")
			(hide yes)
			(effects
				(font
					(size 1.016 1.016)
					(thickness 0.1524)
				)
				(justify mirror)
			)
		)
		(property "Device Type" "L1608-UH38"
			(at 0.0254 -4.4196 270)
			(unlocked yes)
			(layer "B.Fab")
			(hide yes)
			(effects
				(font
					(size 1.016 1.016)
					(thickness 0.1524)
				)
				(justify mirror)
			)
		)
		(duplicate_pad_numbers_are_jumpers no)
		(fp_line
			(start 0.4064 0)
			(end -0.4064 0)
			(stroke
				(width 0.2032)
				(type default)
			)
			(layer "B.SilkS")
		)
		(fp_rect
			(start 0.635 1.1811)
			(end -0.635 -1.1811)
			(stroke
				(width 0)
				(type default)
			)
			(fill no)
			(layer "B.CrtYd")
		)
		(fp_rect
			(start 0.635 1.1811)
			(end -0.635 -1.1811)
			(stroke
				(width 0)
				(type default)
			)
			(fill no)
			(layer "B.Fab")
		)
		(pad "1" smd custom
			(at 0 -0.6604 90)
			(size 0.19685 0.19685)
			(layers "B.Cu" "B.Mask" "B.Paste")
			(net "PV_VDDR")
			(options
				(clearance outline)
				(anchor circle)
			)
			(primitives
				(gr_poly
					(pts
						(arc
							(start 0.508 0.2921)
							(mid 0.478242 0.363942)
							(end 0.4064 0.3937)
						)
						(arc
							(start -0.4064 0.3937)
							(mid -0.478242 0.363942)
							(end -0.508 0.2921)
						)
						(arc
							(start -0.508 -0.2921)
							(mid -0.478242 -0.363942)
							(end -0.4064 -0.3937)
						)
						(arc
							(start 0.4064 -0.3937)
							(mid 0.478242 -0.363942)
							(end 0.508 -0.2921)
						)
					)
					(width 0)
					(fill yes)
				)
			)
		)
		(pad "2" smd custom
			(at 0 0.6604 90)
			(size 0.19685 0.19685)
			(layers "B.Cu" "B.Mask" "B.Paste")
			(net "VCCCLKDDR1")
			(options
				(clearance outline)
				(anchor circle)
			)
			(primitives
				(gr_poly
					(pts
						(arc
							(start 0.508 0.2921)
							(mid 0.478242 0.363942)
							(end 0.4064 0.3937)
						)
						(arc
							(start -0.4064 0.3937)
							(mid -0.478242 0.363942)
							(end -0.508 0.2921)
						)
						(arc
							(start -0.508 -0.2921)
							(mid -0.478242 -0.363942)
							(end -0.4064 -0.3937)
						)
						(arc
							(start 0.4064 -0.3937)
							(mid 0.478242 -0.363942)
							(end 0.508 -0.2921)
						)
					)
					(width 0)
					(fill yes)
				)
			)
		)
	)
	(footprint ""
		(layer "B.Cu")
		(at 71.247 -53.467 180)
		(property "Reference" "R262"
			(at 0 0 0)
			(layer "B.SilkS")
			(hide yes)
			(effects
				(font
					(size 1.27 1.27)
				)
				(justify mirror)
			)
		)
		(property "Value" "0R2J-2-GP"
			(at -0.064008 -3.993896 180)
			(unlocked yes)
			(layer "B.Fab")
			(hide yes)
			(effects
				(font
					(size 1.016 1.016)
					(thickness 0.1524)
				)
				(justify mirror)
			)
		)
		(property "Device Type" "R402H16"
			(at -0.064008 -5.517896 180)
			(unlocked yes)
			(layer "B.Fab")
			(hide yes)
			(effects
				(font
					(size 1.016 1.016)
					(thickness 0.1524)
				)
				(justify mirror)
			)
		)
		(duplicate_pad_numbers_are_jumpers no)
		(fp_rect
			(start 0.381 0.8382)
			(end -0.381 -0.8382)
			(stroke
				(width 0)
				(type default)
			)
			(fill no)
			(layer "B.CrtYd")
		)
		(fp_rect
			(start 0.381 0.8382)
			(end -0.381 -0.8382)
			(stroke
				(width 0)
				(type default)
			)
			(fill no)
			(layer "B.Fab")
		)
		(pad "1" smd custom
			(at 0 -0.4318)
			(size 0.127 0.127)
			(layers "B.Cu" "B.Mask" "B.Paste")
			(net "MEMORY_HOT_LV_R#")
			(options
				(clearance outline)
				(anchor circle)
			)
			(primitives
				(gr_poly
					(pts
						(arc
							(start -0.2032 0.2794)
							(mid -0.239121 0.264521)
							(end -0.254 0.2286)
						)
						(arc
							(start -0.254 -0.2286)
							(mid -0.239121 -0.264521)
							(end -0.2032 -0.2794)
						)
						(arc
							(start 0.2032 -0.2794)
							(mid 0.239121 -0.264521)
							(end 0.254 -0.2286)
						)
						(arc
							(start 0.254 0.2286)
							(mid 0.239121 0.264521)
							(end 0.2032 0.2794)
						)
					)
					(width 0)
					(fill yes)
				)
			)
		)
		(pad "2" smd custom
			(at 0 0.4318)
			(size 0.127 0.127)
			(layers "B.Cu" "B.Mask" "B.Paste")
			(net "MEMORY_HOT_LV_E1#")
			(options
				(clearance outline)
				(anchor circle)
			)
			(primitives
				(gr_poly
					(pts
						(arc
							(start -0.2032 0.2794)
							(mid -0.239121 0.264521)
							(end -0.254 0.2286)
						)
						(arc
							(start -0.254 -0.2286)
							(mid -0.239121 -0.264521)
							(end -0.2032 -0.2794)
						)
						(arc
							(start 0.2032 -0.2794)
							(mid 0.239121 -0.264521)
							(end 0.254 -0.2286)
						)
						(arc
							(start 0.254 0.2286)
							(mid 0.239121 0.264521)
							(end 0.2032 0.2794)
						)
					)
					(width 0)
					(fill yes)
				)
			)
		)
	)
	(footprint ""
		(layer "B.Cu")
		(at 177.292 -42.545 180)
		(property "Reference" "R177"
			(at 0 0 0)
			(layer "B.SilkS")
			(hide yes)
			(effects
				(font
					(size 1.27 1.27)
				)
				(justify mirror)
			)
		)
		(property "Value" "10KR2F-2-GP"
			(at -1.7907 -1.1176 180)
			(unlocked yes)
			(layer "B.Fab")
			(hide yes)
			(effects
				(font
					(size 1.016 1.016)
					(thickness 0.1524)
				)
				(justify mirror)
			)
		)
		(property "Device Type" "R402H16"
			(at -1.7907 -2.6416 180)
			(unlocked yes)
			(layer "B.Fab")
			(hide yes)
			(effects
				(font
					(size 1.016 1.016)
					(thickness 0.1524)
				)
				(justify mirror)
			)
		)
		(duplicate_pad_numbers_are_jumpers no)
		(fp_rect
			(start 0.381 0.8382)
			(end -0.381 -0.8382)
			(stroke
				(width 0)
				(type default)
			)
			(fill no)
			(layer "B.CrtYd")
		)
		(fp_rect
			(start 0.381 0.8382)
			(end -0.381 -0.8382)
			(stroke
				(width 0)
				(type default)
			)
			(fill no)
			(layer "B.Fab")
		)
		(pad "1" smd custom
			(at 0 -0.4318)
			(size 0.127 0.127)
			(layers "B.Cu" "B.Mask" "B.Paste")
			(net "P3V3_STBY")
			(options
				(clearance outline)
				(anchor circle)
			)
			(primitives
				(gr_poly
					(pts
						(arc
							(start -0.2032 0.2794)
							(mid -0.239121 0.264521)
							(end -0.254 0.2286)
						)
						(arc
							(start -0.254 -0.2286)
							(mid -0.239121 -0.264521)
							(end -0.2032 -0.2794)
						)
						(arc
							(start 0.2032 -0.2794)
							(mid 0.239121 -0.264521)
							(end 0.254 -0.2286)
						)
						(arc
							(start 0.254 0.2286)
							(mid 0.239121 0.264521)
							(end 0.2032 0.2794)
						)
					)
					(width 0)
					(fill yes)
				)
			)
		)
		(pad "2" smd custom
			(at 0 0.4318)
			(size 0.127 0.127)
			(layers "B.Cu" "B.Mask" "B.Paste")
			(net "SPI_SW_RST#")
			(options
				(clearance outline)
				(anchor circle)
			)
			(primitives
				(gr_poly
					(pts
						(arc
							(start -0.2032 0.2794)
							(mid -0.239121 0.264521)
							(end -0.254 0.2286)
						)
						(arc
							(start -0.254 -0.2286)
							(mid -0.239121 -0.264521)
							(end -0.2032 -0.2794)
						)
						(arc
							(start 0.2032 -0.2794)
							(mid 0.239121 -0.264521)
							(end 0.254 -0.2286)
						)
						(arc
							(start 0.254 0.2286)
							(mid 0.239121 0.264521)
							(end 0.2032 0.2794)
						)
					)
					(width 0)
					(fill yes)
				)
			)
		)
	)
	(footprint ""
		(layer "B.Cu")
		(at 6.223 -35.179 90)
		(property "Reference" "PC185"
			(at 0 0 90)
			(layer "B.SilkS")
			(hide yes)
			(effects
				(font
					(size 1.27 1.27)
				)
				(justify mirror)
			)
		)
		(property "Value" "SC1U10V2KX-1GP"
			(at -1.8923 -1.2065 90)
			(unlocked yes)
			(layer "B.Fab")
			(hide yes)
			(effects
				(font
					(size 1.016 1.016)
					(thickness 0.1524)
				)
				(justify mirror)
			)
		)
		(property "Device Type" "C402H22"
			(at -1.8923 -2.7305 90)
			(unlocked yes)
			(layer "B.Fab")
			(hide yes)
			(effects
				(font
					(size 1.016 1.016)
					(thickness 0.1524)
				)
				(justify mirror)
			)
		)
		(duplicate_pad_numbers_are_jumpers no)
		(fp_rect
			(start 0.381 0.7366)
			(end -0.381 -0.7366)
			(stroke
				(width 0)
				(type default)
			)
			(fill no)
			(layer "B.CrtYd")
		)
		(fp_rect
			(start 0.381 0.7366)
			(end -0.381 -0.7366)
			(stroke
				(width 0)
				(type default)
			)
			(fill no)
			(layer "B.Fab")
		)
		(pad "1" smd custom
			(at 0 -0.4572 270)
			(size 0.1143 0.1143)
			(layers "B.Cu" "B.Mask" "B.Paste")
			(net "GND")
			(options
				(clearance outline)
				(anchor circle)
			)
			(primitives
				(gr_poly
					(pts
						(arc
							(start -0.254 0.1778)
							(mid -0.239121 0.213721)
							(end -0.2032 0.2286)
						)
						(arc
							(start 0.2032 0.2286)
							(mid 0.239121 0.213721)
							(end 0.254 0.1778)
						)
						(arc
							(start 0.254 -0.1778)
							(mid 0.239121 -0.213721)
							(end 0.2032 -0.2286)
						)
						(arc
							(start -0.2032 -0.2286)
							(mid -0.239121 -0.213721)
							(end -0.254 -0.1778)
						)
					)
					(width 0)
					(fill yes)
				)
			)
		)
		(pad "2" smd custom
			(at 0 0.4572 270)
			(size 0.1143 0.1143)
			(layers "B.Cu" "B.Mask" "B.Paste")
			(net "P3V3_STBY_VREG")
			(options
				(clearance outline)
				(anchor circle)
			)
			(primitives
				(gr_poly
					(pts
						(arc
							(start -0.254 0.1778)
							(mid -0.239121 0.213721)
							(end -0.2032 0.2286)
						)
						(arc
							(start 0.2032 0.2286)
							(mid 0.239121 0.213721)
							(end 0.254 0.1778)
						)
						(arc
							(start 0.254 -0.1778)
							(mid 0.239121 -0.213721)
							(end 0.2032 -0.2286)
						)
						(arc
							(start -0.2032 -0.2286)
							(mid -0.239121 -0.213721)
							(end -0.254 -0.1778)
						)
					)
					(width 0)
					(fill yes)
				)
			)
		)
	)
	(footprint ""
		(layer "B.Cu")
		(at 71.9074 -22.8092)
		(property "Reference" "PR171"
			(at 0 0 0)
			(layer "B.SilkS")
			(hide yes)
			(effects
				(font
					(size 1.27 1.27)
				)
				(justify mirror)
			)
		)
		(property "Value" "0R2J-2-GP"
			(at -1.7907 -1.1176 0)
			(unlocked yes)
			(layer "B.Fab")
			(hide yes)
			(effects
				(font
					(size 1.016 1.016)
					(thickness 0.1524)
				)
				(justify mirror)
			)
		)
		(property "Device Type" "R402H16"
			(at -1.7907 -2.6416 0)
			(unlocked yes)
			(layer "B.Fab")
			(hide yes)
			(effects
				(font
					(size 1.016 1.016)
					(thickness 0.1524)
				)
				(justify mirror)
			)
		)
		(duplicate_pad_numbers_are_jumpers no)
		(fp_rect
			(start 0.381 0.8382)
			(end -0.381 -0.8382)
			(stroke
				(width 0)
				(type default)
			)
			(fill no)
			(layer "B.CrtYd")
		)
		(fp_rect
			(start 0.381 0.8382)
			(end -0.381 -0.8382)
			(stroke
				(width 0)
				(type default)
			)
			(fill no)
			(layer "B.Fab")
		)
		(pad "1" smd custom
			(at 0 -0.4318 180)
			(size 0.127 0.127)
			(layers "B.Cu" "B.Mask" "B.Paste")
			(net "P3V3_STBY_PG")
			(options
				(clearance outline)
				(anchor circle)
			)
			(primitives
				(gr_poly
					(pts
						(arc
							(start -0.2032 0.2794)
							(mid -0.239121 0.264521)
							(end -0.254 0.2286)
						)
						(arc
							(start -0.254 -0.2286)
							(mid -0.239121 -0.264521)
							(end -0.2032 -0.2794)
						)
						(arc
							(start 0.2032 -0.2794)
							(mid 0.239121 -0.264521)
							(end 0.254 -0.2286)
						)
						(arc
							(start 0.254 0.2286)
							(mid 0.239121 0.264521)
							(end 0.2032 0.2794)
						)
					)
					(width 0)
					(fill yes)
				)
			)
		)
		(pad "2" smd custom
			(at 0 0.4318 180)
			(size 0.127 0.127)
			(layers "B.Cu" "B.Mask" "B.Paste")
			(net "VR_EN_P1V8_STBY")
			(options
				(clearance outline)
				(anchor circle)
			)
			(primitives
				(gr_poly
					(pts
						(arc
							(start -0.2032 0.2794)
							(mid -0.239121 0.264521)
							(end -0.254 0.2286)
						)
						(arc
							(start -0.254 -0.2286)
							(mid -0.239121 -0.264521)
							(end -0.2032 -0.2794)
						)
						(arc
							(start 0.2032 -0.2794)
							(mid 0.239121 -0.264521)
							(end 0.254 -0.2286)
						)
						(arc
							(start 0.254 0.2286)
							(mid 0.239121 0.264521)
							(end 0.2032 0.2794)
						)
					)
					(width 0)
					(fill yes)
				)
			)
		)
	)
	(footprint ""
		(layer "B.Cu")
		(at 56.3372 -12.2174)
		(property "Reference" "TP59"
			(at 0 0 0)
			(layer "B.SilkS")
			(hide yes)
			(effects
				(font
					(size 1.27 1.27)
				)
				(justify mirror)
			)
		)
		(property "Value" "TPAD32-GP"
			(at 0 -3.166364 0)
			(unlocked yes)
			(layer "B.Fab")
			(hide yes)
			(effects
				(font
					(size 1.016 1.016)
					(thickness 0.1524)
				)
				(justify mirror)
			)
		)
		(property "Device Type" "TPAD32"
			(at 0 -4.690618 0)
			(unlocked yes)
			(layer "B.Fab")
			(hide yes)
			(effects
				(font
					(size 1.016 1.016)
					(thickness 0.1524)
				)
				(justify mirror)
			)
		)
		(duplicate_pad_numbers_are_jumpers no)
		(fp_poly
			(pts
				(arc
					(start 0.7112 0)
					(mid -0.7112 0)
					(end 0.7112 0)
				)
			)
			(stroke
				(width 0)
				(type default)
			)
			(fill no)
			(layer "B.CrtYd")
		)
		(fp_poly
			(pts
				(arc
					(start 0.7112 0)
					(mid -0.7112 0)
					(end 0.7112 0)
				)
			)
			(stroke
				(width 0)
				(type default)
			)
			(fill no)
			(layer "B.Fab")
		)
		(pad "1" smd circle
			(at 0 0 180)
			(size 0.8128 0.8128)
			(layers "B.Cu" "B.Mask" "B.Paste")
			(net "XDP_SOC_CPU_TRST#")
		)
	)
	(footprint ""
		(layer "B.Cu")
		(at 111.379 -70.866)
		(property "Reference" "TP53"
			(at 0 0 0)
			(layer "B.SilkS")
			(hide yes)
			(effects
				(font
					(size 1.27 1.27)
				)
				(justify mirror)
			)
		)
		(property "Value" "TPAD32-GP"
			(at 0 -3.166364 0)
			(unlocked yes)
			(layer "B.Fab")
			(hide yes)
			(effects
				(font
					(size 1.016 1.016)
					(thickness 0.1524)
				)
				(justify mirror)
			)
		)
		(property "Device Type" "TPAD32"
			(at 0 -4.690618 0)
			(unlocked yes)
			(layer "B.Fab")
			(hide yes)
			(effects
				(font
					(size 1.016 1.016)
					(thickness 0.1524)
				)
				(justify mirror)
			)
		)
		(duplicate_pad_numbers_are_jumpers no)
		(fp_poly
			(pts
				(arc
					(start 0.7112 0)
					(mid -0.7112 0)
					(end 0.7112 0)
				)
			)
			(stroke
				(width 0)
				(type default)
			)
			(fill no)
			(layer "B.CrtYd")
		)
		(fp_poly
			(pts
				(arc
					(start 0.7112 0)
					(mid -0.7112 0)
					(end 0.7112 0)
				)
			)
			(stroke
				(width 0)
				(type default)
			)
			(fill no)
			(layer "B.Fab")
		)
		(pad "1" smd circle
			(at 0 0 180)
			(size 0.8128 0.8128)
			(layers "B.Cu" "B.Mask" "B.Paste")
			(net "XDP_SOC_CPU_TMS")
		)
	)
	(footprint ""
		(layer "B.Cu")
		(at 67.056 -21.082 90)
		(property "Reference" "PR184"
			(at 0 0 90)
			(layer "B.SilkS")
			(hide yes)
			(effects
				(font
					(size 1.27 1.27)
				)
				(justify mirror)
			)
		)
		(property "Value" "118KR3B-GP"
			(at 0.0254 -2.0193 90)
			(unlocked yes)
			(layer "B.Fab")
			(hide yes)
			(effects
				(font
					(size 1.016 1.016)
					(thickness 0.1524)
				)
				(justify mirror)
			)
		)
		(property "Device Type" "R603H22"
			(at 0.0254 -3.5433 90)
			(unlocked yes)
			(layer "B.Fab")
			(hide yes)
			(effects
				(font
					(size 1.016 1.016)
					(thickness 0.1524)
				)
				(justify mirror)
			)
		)
		(duplicate_pad_numbers_are_jumpers no)
		(fp_line
			(start 0.2032 0)
			(end 0.4191 0)
			(stroke
				(width 0.2032)
				(type default)
			)
			(layer "B.SilkS")
		)
		(fp_line
			(start -0.4318 0)
			(end -0.2032 0)
			(stroke
				(width 0.2032)
				(type default)
			)
			(layer "B.SilkS")
		)
		(fp_rect
			(start 0.635 1.1811)
			(end -0.635 -1.1811)
			(stroke
				(width 0)
				(type default)
			)
			(fill no)
			(layer "B.CrtYd")
		)
		(fp_rect
			(start 0.635 1.1811)
			(end -0.635 -1.1811)
			(stroke
				(width 0)
				(type default)
			)
			(fill no)
			(layer "B.Fab")
		)
		(pad "1" smd custom
			(at 0 -0.6604 270)
			(size 0.19685 0.19685)
			(layers "B.Cu" "B.Mask" "B.Paste")
			(net "VR_FB_P1V8_STBY")
			(options
				(clearance outline)
				(anchor circle)
			)
			(primitives
				(gr_poly
					(pts
						(arc
							(start 0.508 0.2921)
							(mid 0.478242 0.363942)
							(end 0.4064 0.3937)
						)
						(arc
							(start -0.4064 0.3937)
							(mid -0.478242 0.363942)
							(end -0.508 0.2921)
						)
						(arc
							(start -0.508 -0.2921)
							(mid -0.478242 -0.363942)
							(end -0.4064 -0.3937)
						)
						(arc
							(start 0.4064 -0.3937)
							(mid 0.478242 -0.363942)
							(end 0.508 -0.2921)
						)
					)
					(width 0)
					(fill yes)
				)
			)
		)
		(pad "2" smd custom
			(at 0 0.6604 270)
			(size 0.19685 0.19685)
			(layers "B.Cu" "B.Mask" "B.Paste")
			(net "AGND_P1V8_STBY")
			(options
				(clearance outline)
				(anchor circle)
			)
			(primitives
				(gr_poly
					(pts
						(arc
							(start 0.508 0.2921)
							(mid 0.478242 0.363942)
							(end 0.4064 0.3937)
						)
						(arc
							(start -0.4064 0.3937)
							(mid -0.478242 0.363942)
							(end -0.508 0.2921)
						)
						(arc
							(start -0.508 -0.2921)
							(mid -0.478242 -0.363942)
							(end -0.4064 -0.3937)
						)
						(arc
							(start 0.4064 -0.3937)
							(mid 0.478242 -0.363942)
							(end 0.508 -0.2921)
						)
					)
					(width 0)
					(fill yes)
				)
			)
		)
	)
	(footprint ""
		(layer "B.Cu")
		(at 67.31 -16.637 90)
		(property "Reference" "PR181"
			(at 0 0 90)
			(layer "B.SilkS")
			(hide yes)
			(effects
				(font
					(size 1.27 1.27)
				)
				(justify mirror)
			)
		)
		(property "Value" "0R3J-6-GP"
			(at 0.0254 -2.0193 90)
			(unlocked yes)
			(layer "B.Fab")
			(hide yes)
			(effects
				(font
					(size 1.016 1.016)
					(thickness 0.1524)
				)
				(justify mirror)
			)
		)
		(property "Device Type" "R603H22"
			(at 0.0254 -3.5433 90)
			(unlocked yes)
			(layer "B.Fab")
			(hide yes)
			(effects
				(font
					(size 1.016 1.016)
					(thickness 0.1524)
				)
				(justify mirror)
			)
		)
		(duplicate_pad_numbers_are_jumpers no)
		(fp_line
			(start 0.2032 0)
			(end 0.4191 0)
			(stroke
				(width 0.2032)
				(type default)
			)
			(layer "B.SilkS")
		)
		(fp_line
			(start -0.4318 0)
			(end -0.2032 0)
			(stroke
				(width 0.2032)
				(type default)
			)
			(layer "B.SilkS")
		)
		(fp_rect
			(start 0.635 1.1811)
			(end -0.635 -1.1811)
			(stroke
				(width 0)
				(type default)
			)
			(fill no)
			(layer "B.CrtYd")
		)
		(fp_rect
			(start 0.635 1.1811)
			(end -0.635 -1.1811)
			(stroke
				(width 0)
				(type default)
			)
			(fill no)
			(layer "B.Fab")
		)
		(pad "1" smd custom
			(at 0 -0.6604 270)
			(size 0.19685 0.19685)
			(layers "B.Cu" "B.Mask" "B.Paste")
			(net "P1V8_STBY")
			(options
				(clearance outline)
				(anchor circle)
			)
			(primitives
				(gr_poly
					(pts
						(arc
							(start 0.508 0.2921)
							(mid 0.478242 0.363942)
							(end 0.4064 0.3937)
						)
						(arc
							(start -0.4064 0.3937)
							(mid -0.478242 0.363942)
							(end -0.508 0.2921)
						)
						(arc
							(start -0.508 -0.2921)
							(mid -0.478242 -0.363942)
							(end -0.4064 -0.3937)
						)
						(arc
							(start 0.4064 -0.3937)
							(mid 0.478242 -0.363942)
							(end 0.508 -0.2921)
						)
					)
					(width 0)
					(fill yes)
				)
			)
		)
		(pad "2" smd custom
			(at 0 0.6604 270)
			(size 0.19685 0.19685)
			(layers "B.Cu" "B.Mask" "B.Paste")
			(net "P1V8_STBY_VOUT")
			(options
				(clearance outline)
				(anchor circle)
			)
			(primitives
				(gr_poly
					(pts
						(arc
							(start 0.508 0.2921)
							(mid 0.478242 0.363942)
							(end 0.4064 0.3937)
						)
						(arc
							(start -0.4064 0.3937)
							(mid -0.478242 0.363942)
							(end -0.508 0.2921)
						)
						(arc
							(start -0.508 -0.2921)
							(mid -0.478242 -0.363942)
							(end -0.4064 -0.3937)
						)
						(arc
							(start 0.4064 -0.3937)
							(mid 0.478242 -0.363942)
							(end 0.508 -0.2921)
						)
					)
					(width 0)
					(fill yes)
				)
			)
		)
	)
	(footprint ""
		(layer "B.Cu")
		(at 195.2498 -37.338 180)
		(property "Reference" "PQ3"
			(at 0 0 0)
			(layer "B.SilkS")
			(hide yes)
			(effects
				(font
					(size 1.27 1.27)
				)
				(justify mirror)
			)
		)
		(property "Value" "MMBT3904TT1G-GP"
			(at 2.032 -3.674618 180)
			(unlocked yes)
			(layer "B.Fab")
			(hide yes)
			(effects
				(font
					(size 1.016 1.016)
					(thickness 0.1524)
				)
				(justify mirror)
			)
		)
		(property "Device Type" "SC75CBE1D6H36"
			(at 2.032 -5.198618 180)
			(unlocked yes)
			(layer "B.Fab")
			(hide yes)
			(effects
				(font
					(size 1.016 1.016)
					(thickness 0.1524)
				)
				(justify mirror)
			)
		)
		(duplicate_pad_numbers_are_jumpers no)
		(fp_poly
			(pts
				(xy -0.381 -1.1938) (xy 0.381 -1.1938) (xy 0.381 -0.6604) (xy 1.0541 -0.6604) (xy 1.0541 0.6604)
				(xy 0.889 0.6604) (xy 0.889 1.1938) (xy -0.889 1.1938) (xy -0.889 0.6604) (xy -1.0541 0.6604) (xy -1.0541 -0.6604)
				(xy -0.381 -0.6604)
			)
			(stroke
				(width 0)
				(type default)
			)
			(fill no)
			(layer "B.CrtYd")
		)
		(fp_poly
			(pts
				(xy -0.381 -1.1938) (xy 0.381 -1.1938) (xy 0.381 -0.6604) (xy 1.0541 -0.6604) (xy 1.0541 0.6604)
				(xy 0.889 0.6604) (xy 0.889 1.1938) (xy -0.889 1.1938) (xy -0.889 0.6604) (xy -1.0541 0.6604) (xy -1.0541 -0.6604)
				(xy -0.381 -0.6604)
			)
			(stroke
				(width 0)
				(type default)
			)
			(fill no)
			(layer "B.Fab")
		)
		(pad "B" smd custom
			(at 0.508 0.6604)
			(size 0.127 0.127)
			(layers "B.Cu" "B.Mask" "B.Paste")
			(net "VDDR_Z")
			(options
				(clearance outline)
				(anchor circle)
			)
			(primitives
				(gr_poly
					(pts
						(arc
							(start -0.0508 -0.4064)
							(mid -0.194484 -0.346884)
							(end -0.254 -0.2032)
						)
						(arc
							(start -0.254 0.2032)
							(mid -0.194484 0.346884)
							(end -0.0508 0.4064)
						)
						(arc
							(start 0.0508 0.4064)
							(mid 0.194484 0.346884)
							(end 0.254 0.2032)
						)
						(arc
							(start 0.254 -0.2032)
							(mid 0.194484 -0.346884)
							(end 0.0508 -0.4064)
						)
					)
					(width 0)
					(fill yes)
				)
			)
		)
		(pad "C" smd custom
			(at 0 -0.6604)
			(size 0.127 0.127)
			(layers "B.Cu" "B.Mask" "B.Paste")
			(net "P12V")
			(options
				(clearance outline)
				(anchor circle)
			)
			(primitives
				(gr_poly
					(pts
						(arc
							(start -0.0508 -0.4064)
							(mid -0.194484 -0.346884)
							(end -0.254 -0.2032)
						)
						(arc
							(start -0.254 0.2032)
							(mid -0.194484 0.346884)
							(end -0.0508 0.4064)
						)
						(arc
							(start 0.0508 0.4064)
							(mid 0.194484 0.346884)
							(end 0.254 0.2032)
						)
						(arc
							(start 0.254 -0.2032)
							(mid 0.194484 -0.346884)
							(end 0.0508 -0.4064)
						)
					)
					(width 0)
					(fill yes)
				)
			)
		)
		(pad "E" smd custom
			(at -0.508 0.6604)
			(size 0.127 0.127)
			(layers "B.Cu" "B.Mask" "B.Paste")
			(net "VDDR_5VBIAS")
			(options
				(clearance outline)
				(anchor circle)
			)
			(primitives
				(gr_poly
					(pts
						(arc
							(start -0.0508 -0.4064)
							(mid -0.194484 -0.346884)
							(end -0.254 -0.2032)
						)
						(arc
							(start -0.254 0.2032)
							(mid -0.194484 0.346884)
							(end -0.0508 0.4064)
						)
						(arc
							(start 0.0508 0.4064)
							(mid 0.194484 0.346884)
							(end 0.254 0.2032)
						)
						(arc
							(start 0.254 -0.2032)
							(mid 0.194484 -0.346884)
							(end 0.0508 -0.4064)
						)
					)
					(width 0)
					(fill yes)
				)
			)
		)
	)
	(footprint ""
		(layer "B.Cu")
		(at 186.6392 -27.6098 90)
		(property "Reference" "C75"
			(at 0 0 90)
			(layer "B.SilkS")
			(hide yes)
			(effects
				(font
					(size 1.27 1.27)
				)
				(justify mirror)
			)
		)
		(property "Value" "SCD22U16V2KX-GP"
			(at -1.8923 -1.2065 90)
			(unlocked yes)
			(layer "B.Fab")
			(hide yes)
			(effects
				(font
					(size 1.016 1.016)
					(thickness 0.1524)
				)
				(justify mirror)
			)
		)
		(property "Device Type" "C402H22"
			(at -1.8923 -2.7305 90)
			(unlocked yes)
			(layer "B.Fab")
			(hide yes)
			(effects
				(font
					(size 1.016 1.016)
					(thickness 0.1524)
				)
				(justify mirror)
			)
		)
		(duplicate_pad_numbers_are_jumpers no)
		(fp_rect
			(start 0.381 0.7366)
			(end -0.381 -0.7366)
			(stroke
				(width 0)
				(type default)
			)
			(fill no)
			(layer "B.CrtYd")
		)
		(fp_rect
			(start 0.381 0.7366)
			(end -0.381 -0.7366)
			(stroke
				(width 0)
				(type default)
			)
			(fill no)
			(layer "B.Fab")
		)
		(pad "1" smd custom
			(at 0 -0.4572 270)
			(size 0.1143 0.1143)
			(layers "B.Cu" "B.Mask" "B.Paste")
			(net "VR_PVDDRA_ISUMP1")
			(options
				(clearance outline)
				(anchor circle)
			)
			(primitives
				(gr_poly
					(pts
						(arc
							(start -0.254 0.1778)
							(mid -0.239121 0.213721)
							(end -0.2032 0.2286)
						)
						(arc
							(start 0.2032 0.2286)
							(mid 0.239121 0.213721)
							(end 0.254 0.1778)
						)
						(arc
							(start 0.254 -0.1778)
							(mid 0.239121 -0.213721)
							(end 0.2032 -0.2286)
						)
						(arc
							(start -0.2032 -0.2286)
							(mid -0.239121 -0.213721)
							(end -0.254 -0.1778)
						)
					)
					(width 0)
					(fill yes)
				)
			)
		)
		(pad "2" smd custom
			(at 0 0.4572 270)
			(size 0.1143 0.1143)
			(layers "B.Cu" "B.Mask" "B.Paste")
			(net "VR_PVDDRA_ISUMN1")
			(options
				(clearance outline)
				(anchor circle)
			)
			(primitives
				(gr_poly
					(pts
						(arc
							(start -0.254 0.1778)
							(mid -0.239121 0.213721)
							(end -0.2032 0.2286)
						)
						(arc
							(start 0.2032 0.2286)
							(mid 0.239121 0.213721)
							(end 0.254 0.1778)
						)
						(arc
							(start 0.254 -0.1778)
							(mid 0.239121 -0.213721)
							(end 0.2032 -0.2286)
						)
						(arc
							(start -0.2032 -0.2286)
							(mid -0.239121 -0.213721)
							(end -0.254 -0.1778)
						)
					)
					(width 0)
					(fill yes)
				)
			)
		)
	)
	(footprint ""
		(layer "B.Cu")
		(at 36.957 -28.448 90)
		(property "Reference" "R449"
			(at 0 0 90)
			(layer "B.SilkS")
			(hide yes)
			(effects
				(font
					(size 1.27 1.27)
				)
				(justify mirror)
			)
		)
		(property "Value" "4K7R2F-GP"
			(at -1.7907 -1.1176 90)
			(unlocked yes)
			(layer "B.Fab")
			(hide yes)
			(effects
				(font
					(size 1.016 1.016)
					(thickness 0.1524)
				)
				(justify mirror)
			)
		)
		(property "Device Type" "R402H16"
			(at -1.7907 -2.6416 90)
			(unlocked yes)
			(layer "B.Fab")
			(hide yes)
			(effects
				(font
					(size 1.016 1.016)
					(thickness 0.1524)
				)
				(justify mirror)
			)
		)
		(duplicate_pad_numbers_are_jumpers no)
		(fp_rect
			(start 0.381 0.8382)
			(end -0.381 -0.8382)
			(stroke
				(width 0)
				(type default)
			)
			(fill no)
			(layer "B.CrtYd")
		)
		(fp_rect
			(start 0.381 0.8382)
			(end -0.381 -0.8382)
			(stroke
				(width 0)
				(type default)
			)
			(fill no)
			(layer "B.Fab")
		)
		(pad "1" smd custom
			(at 0 -0.4318 270)
			(size 0.127 0.127)
			(layers "B.Cu" "B.Mask" "B.Paste")
			(net "P3V3")
			(options
				(clearance outline)
				(anchor circle)
			)
			(primitives
				(gr_poly
					(pts
						(arc
							(start -0.2032 0.2794)
							(mid -0.239121 0.264521)
							(end -0.254 0.2286)
						)
						(arc
							(start -0.254 -0.2286)
							(mid -0.239121 -0.264521)
							(end -0.2032 -0.2794)
						)
						(arc
							(start 0.2032 -0.2794)
							(mid 0.239121 -0.264521)
							(end 0.254 -0.2286)
						)
						(arc
							(start 0.254 0.2286)
							(mid 0.239121 0.264521)
							(end 0.2032 0.2794)
						)
					)
					(width 0)
					(fill yes)
				)
			)
		)
		(pad "2" smd custom
			(at 0 0.4318 270)
			(size 0.127 0.127)
			(layers "B.Cu" "B.Mask" "B.Paste")
			(net "CLKCUFF_SMB_ADDR")
			(options
				(clearance outline)
				(anchor circle)
			)
			(primitives
				(gr_poly
					(pts
						(arc
							(start -0.2032 0.2794)
							(mid -0.239121 0.264521)
							(end -0.254 0.2286)
						)
						(arc
							(start -0.254 -0.2286)
							(mid -0.239121 -0.264521)
							(end -0.2032 -0.2794)
						)
						(arc
							(start 0.2032 -0.2794)
							(mid 0.239121 -0.264521)
							(end 0.254 -0.2286)
						)
						(arc
							(start 0.254 0.2286)
							(mid 0.239121 0.264521)
							(end 0.2032 0.2794)
						)
					)
					(width 0)
					(fill yes)
				)
			)
		)
	)
	(footprint ""
		(layer "B.Cu")
		(at 144.4244 -48.26 -90)
		(property "Reference" "R80"
			(at 0 0 90)
			(layer "B.SilkS")
			(hide yes)
			(effects
				(font
					(size 1.27 1.27)
				)
				(justify mirror)
			)
		)
		(property "Value" "1KR2F-3-GP"
			(at -0.064008 -3.993896 270)
			(unlocked yes)
			(layer "B.Fab")
			(hide yes)
			(effects
				(font
					(size 1.016 1.016)
					(thickness 0.1524)
				)
				(justify mirror)
			)
		)
		(property "Device Type" "R402H16"
			(at -0.064008 -5.517896 270)
			(unlocked yes)
			(layer "B.Fab")
			(hide yes)
			(effects
				(font
					(size 1.016 1.016)
					(thickness 0.1524)
				)
				(justify mirror)
			)
		)
		(duplicate_pad_numbers_are_jumpers no)
		(fp_rect
			(start 0.381 0.8382)
			(end -0.381 -0.8382)
			(stroke
				(width 0)
				(type default)
			)
			(fill no)
			(layer "B.CrtYd")
		)
		(fp_rect
			(start 0.381 0.8382)
			(end -0.381 -0.8382)
			(stroke
				(width 0)
				(type default)
			)
			(fill no)
			(layer "B.Fab")
		)
		(pad "1" smd custom
			(at 0 -0.4318 90)
			(size 0.127 0.127)
			(layers "B.Cu" "B.Mask" "B.Paste")
			(net "C_DCLK")
			(options
				(clearance outline)
				(anchor circle)
			)
			(primitives
				(gr_poly
					(pts
						(arc
							(start -0.2032 0.2794)
							(mid -0.239121 0.264521)
							(end -0.254 0.2286)
						)
						(arc
							(start -0.254 -0.2286)
							(mid -0.239121 -0.264521)
							(end -0.2032 -0.2794)
						)
						(arc
							(start 0.2032 -0.2794)
							(mid 0.239121 -0.264521)
							(end 0.254 -0.2286)
						)
						(arc
							(start 0.254 0.2286)
							(mid 0.239121 0.264521)
							(end 0.2032 0.2794)
						)
					)
					(width 0)
					(fill yes)
				)
			)
		)
		(pad "2" smd custom
			(at 0 0.4318 90)
			(size 0.127 0.127)
			(layers "B.Cu" "B.Mask" "B.Paste")
			(net "P3V3_STBY")
			(options
				(clearance outline)
				(anchor circle)
			)
			(primitives
				(gr_poly
					(pts
						(arc
							(start -0.2032 0.2794)
							(mid -0.239121 0.264521)
							(end -0.254 0.2286)
						)
						(arc
							(start -0.254 -0.2286)
							(mid -0.239121 -0.264521)
							(end -0.2032 -0.2794)
						)
						(arc
							(start 0.2032 -0.2794)
							(mid 0.239121 -0.264521)
							(end 0.254 -0.2286)
						)
						(arc
							(start 0.254 0.2286)
							(mid 0.239121 0.264521)
							(end 0.2032 0.2794)
						)
					)
					(width 0)
					(fill yes)
				)
			)
		)
	)
	(footprint ""
		(layer "B.Cu")
		(at 70.358 -20.066 180)
		(property "Reference" "PU13"
			(at 0 0 0)
			(layer "B.SilkS")
			(hide yes)
			(effects
				(font
					(size 1.27 1.27)
				)
				(justify mirror)
			)
		)
		(property "Value" "EP53F8QI-T-GP"
			(at -2.827274 -2.223262 180)
			(unlocked yes)
			(layer "B.Fab")
			(hide yes)
			(effects
				(font
					(size 1.016 1.016)
					(thickness 0.1524)
				)
				(justify mirror)
			)
		)
		(property "Device Type" "QFN16G3H46"
			(at -2.827274 -3.747262 180)
			(unlocked yes)
			(layer "B.Fab")
			(hide yes)
			(effects
				(font
					(size 1.016 1.016)
					(thickness 0.1524)
				)
				(justify mirror)
			)
		)
		(duplicate_pad_numbers_are_jumpers no)
		(fp_poly
			(pts
				(xy -1.819656 -2.195576) (xy -1.506728 -1.882648) (xy -1.1938 -2.195576)
			)
			(stroke
				(width 0)
				(type default)
			)
			(fill yes)
			(layer "B.SilkS")
		)
		(fp_rect
			(start 1.8796 1.8796)
			(end -1.8796 -1.8796)
			(stroke
				(width 0)
				(type default)
			)
			(fill no)
			(layer "B.CrtYd")
		)
		(fp_rect
			(start 1.8796 1.8796)
			(end -1.8796 -1.8796)
			(stroke
				(width 0)
				(type default)
			)
			(fill no)
			(layer "B.Fab")
		)
		(pad "1" smd rect
			(at -1.249934 -1.32207)
			(size 0.3048 0.8636)
			(layers "B.Cu" "B.Mask" "B.Paste")
			(net "Net_641")
		)
		(pad "2" smd rect
			(at -0.750062 -1.32207)
			(size 0.3048 0.8636)
			(layers "B.Cu" "B.Mask" "B.Paste")
			(net "GND")
		)
		(pad "3" smd rect
			(at -0.249936 -1.32207)
			(size 0.3048 0.8636)
			(layers "B.Cu" "B.Mask" "B.Paste")
			(net "GND")
		)
		(pad "4" smd rect
			(at 0.249936 -1.32207)
			(size 0.3048 0.8636)
			(layers "B.Cu" "B.Mask" "B.Paste")
			(net "VR_AVIN_P1V8_STBY")
		)
		(pad "5" smd rect
			(at 0.750062 -1.32207)
			(size 0.3048 0.8636)
			(layers "B.Cu" "B.Mask" "B.Paste")
			(net "VR_FB_P1V8_STBY")
		)
		(pad "6" smd rect
			(at 1.249934 -1.32207)
			(size 0.3048 0.8636)
			(layers "B.Cu" "B.Mask" "B.Paste")
			(net "Net_644")
		)
		(pad "7" smd rect
			(at 1.32207 -0.249936)
			(size 0.8636 0.3048)
			(layers "B.Cu" "B.Mask" "B.Paste")
			(net "P1V8_STBY_VOUT")
		)
		(pad "8" smd rect
			(at 1.32207 0.249936)
			(size 0.8636 0.3048)
			(layers "B.Cu" "B.Mask" "B.Paste")
			(net "P1V8_STBY_VOUT")
		)
		(pad "9" smd rect
			(at 1.249934 1.32207)
			(size 0.3048 0.8636)
			(layers "B.Cu" "B.Mask" "B.Paste")
			(net "AGND_P1V8_STBY")
		)
		(pad "10" smd rect
			(at 0.750062 1.32207)
			(size 0.3048 0.8636)
			(layers "B.Cu" "B.Mask" "B.Paste")
			(net "VR_AVIN_P1V8_STBY")
		)
		(pad "11" smd rect
			(at 0.249936 1.32207)
			(size 0.3048 0.8636)
			(layers "B.Cu" "B.Mask" "B.Paste")
			(net "P1V8_STBY_PG")
		)
		(pad "12" smd rect
			(at -0.249936 1.32207)
			(size 0.3048 0.8636)
			(layers "B.Cu" "B.Mask" "B.Paste")
			(net "VR_EN_P1V8_STBY")
		)
		(pad "13" smd rect
			(at -0.750062 1.32207)
			(size 0.3048 0.8636)
			(layers "B.Cu" "B.Mask" "B.Paste")
			(net "VR_PVIN_P1V8_STBY")
		)
		(pad "14" smd rect
			(at -1.249934 1.32207)
			(size 0.3048 0.8636)
			(layers "B.Cu" "B.Mask" "B.Paste")
			(net "VR_PVIN_P1V8_STBY")
		)
		(pad "15" smd rect
			(at -1.32207 0.249936)
			(size 0.8636 0.3048)
			(layers "B.Cu" "B.Mask" "B.Paste")
			(net "Net_642")
		)
		(pad "16" smd rect
			(at -1.32207 -0.249936)
			(size 0.8636 0.3048)
			(layers "B.Cu" "B.Mask" "B.Paste")
			(net "Net_643")
		)
	)
	(footprint ""
		(layer "B.Cu")
		(at 78.232 -13.462)
		(property "Reference" "C276"
			(at 0 0 0)
			(layer "B.SilkS")
			(hide yes)
			(effects
				(font
					(size 1.27 1.27)
				)
				(justify mirror)
			)
		)
		(property "Value" "SCD1U16V2KX-3GP"
			(at -1.1811 -2.7051 0)
			(unlocked yes)
			(layer "B.Fab")
			(hide yes)
			(effects
				(font
					(size 1.016 1.016)
					(thickness 0.1524)
				)
				(justify mirror)
			)
		)
		(property "Device Type" "C402H22"
			(at -1.1811 -4.2291 0)
			(unlocked yes)
			(layer "B.Fab")
			(hide yes)
			(effects
				(font
					(size 1.016 1.016)
					(thickness 0.1524)
				)
				(justify mirror)
			)
		)
		(duplicate_pad_numbers_are_jumpers no)
		(fp_rect
			(start 0.381 0.7366)
			(end -0.381 -0.7366)
			(stroke
				(width 0)
				(type default)
			)
			(fill no)
			(layer "B.CrtYd")
		)
		(fp_rect
			(start 0.381 0.7366)
			(end -0.381 -0.7366)
			(stroke
				(width 0)
				(type default)
			)
			(fill no)
			(layer "B.Fab")
		)
		(pad "1" smd custom
			(at 0 -0.4572 180)
			(size 0.1143 0.1143)
			(layers "B.Cu" "B.Mask" "B.Paste")
			(net "P2E_CPU_SAS_C_TX_DP1")
			(options
				(clearance outline)
				(anchor circle)
			)
			(primitives
				(gr_poly
					(pts
						(arc
							(start -0.254 0.1778)
							(mid -0.239121 0.213721)
							(end -0.2032 0.2286)
						)
						(arc
							(start 0.2032 0.2286)
							(mid 0.239121 0.213721)
							(end 0.254 0.1778)
						)
						(arc
							(start 0.254 -0.1778)
							(mid 0.239121 -0.213721)
							(end 0.2032 -0.2286)
						)
						(arc
							(start -0.2032 -0.2286)
							(mid -0.239121 -0.213721)
							(end -0.254 -0.1778)
						)
					)
					(width 0)
					(fill yes)
				)
			)
		)
		(pad "2" smd custom
			(at 0 0.4572 180)
			(size 0.1143 0.1143)
			(layers "B.Cu" "B.Mask" "B.Paste")
			(net "P2E_CPU_SAS_TX_DP1")
			(options
				(clearance outline)
				(anchor circle)
			)
			(primitives
				(gr_poly
					(pts
						(arc
							(start -0.254 0.1778)
							(mid -0.239121 0.213721)
							(end -0.2032 0.2286)
						)
						(arc
							(start 0.2032 0.2286)
							(mid 0.239121 0.213721)
							(end 0.254 0.1778)
						)
						(arc
							(start 0.254 -0.1778)
							(mid 0.239121 -0.213721)
							(end 0.2032 -0.2286)
						)
						(arc
							(start -0.2032 -0.2286)
							(mid -0.239121 -0.213721)
							(end -0.254 -0.1778)
						)
					)
					(width 0)
					(fill yes)
				)
			)
		)
	)
	(footprint ""
		(layer "B.Cu")
		(at 44.1452 -16.7894)
		(property "Reference" "R351"
			(at 0 0 0)
			(layer "B.SilkS")
			(hide yes)
			(effects
				(font
					(size 1.27 1.27)
				)
				(justify mirror)
			)
		)
		(property "Value" "33R2F-3-GP"
			(at -0.064008 -3.993896 0)
			(unlocked yes)
			(layer "B.Fab")
			(hide yes)
			(effects
				(font
					(size 1.016 1.016)
					(thickness 0.1524)
				)
				(justify mirror)
			)
		)
		(property "Device Type" "R402H16"
			(at -0.064008 -5.517896 0)
			(unlocked yes)
			(layer "B.Fab")
			(hide yes)
			(effects
				(font
					(size 1.016 1.016)
					(thickness 0.1524)
				)
				(justify mirror)
			)
		)
		(duplicate_pad_numbers_are_jumpers no)
		(fp_rect
			(start 0.381 0.8382)
			(end -0.381 -0.8382)
			(stroke
				(width 0)
				(type default)
			)
			(fill no)
			(layer "B.CrtYd")
		)
		(fp_rect
			(start 0.381 0.8382)
			(end -0.381 -0.8382)
			(stroke
				(width 0)
				(type default)
			)
			(fill no)
			(layer "B.Fab")
		)
		(pad "1" smd custom
			(at 0 -0.4318 180)
			(size 0.127 0.127)
			(layers "B.Cu" "B.Mask" "B.Paste")
			(net "CLK_100M_CLKBUFF_ENET_R_DP")
			(options
				(clearance outline)
				(anchor circle)
			)
			(primitives
				(gr_poly
					(pts
						(arc
							(start -0.2032 0.2794)
							(mid -0.239121 0.264521)
							(end -0.254 0.2286)
						)
						(arc
							(start -0.254 -0.2286)
							(mid -0.239121 -0.264521)
							(end -0.2032 -0.2794)
						)
						(arc
							(start 0.2032 -0.2794)
							(mid 0.239121 -0.264521)
							(end 0.254 -0.2286)
						)
						(arc
							(start 0.254 0.2286)
							(mid 0.239121 0.264521)
							(end 0.2032 0.2794)
						)
					)
					(width 0)
					(fill yes)
				)
			)
		)
		(pad "2" smd custom
			(at 0 0.4318 180)
			(size 0.127 0.127)
			(layers "B.Cu" "B.Mask" "B.Paste")
			(net "CLK_100M_CLKBUFF_ENET_DP")
			(options
				(clearance outline)
				(anchor circle)
			)
			(primitives
				(gr_poly
					(pts
						(arc
							(start -0.2032 0.2794)
							(mid -0.239121 0.264521)
							(end -0.254 0.2286)
						)
						(arc
							(start -0.254 -0.2286)
							(mid -0.239121 -0.264521)
							(end -0.2032 -0.2794)
						)
						(arc
							(start 0.2032 -0.2794)
							(mid 0.239121 -0.264521)
							(end 0.254 -0.2286)
						)
						(arc
							(start 0.254 0.2286)
							(mid 0.239121 0.264521)
							(end 0.2032 0.2794)
						)
					)
					(width 0)
					(fill yes)
				)
			)
		)
	)
	(footprint ""
		(layer "B.Cu")
		(at 74.549 -21.9964 -90)
		(property "Reference" "PR173"
			(at 0 0 90)
			(layer "B.SilkS")
			(hide yes)
			(effects
				(font
					(size 1.27 1.27)
				)
				(justify mirror)
			)
		)
		(property "Value" "0R3J-6-GP"
			(at 0.0254 -2.0193 270)
			(unlocked yes)
			(layer "B.Fab")
			(hide yes)
			(effects
				(font
					(size 1.016 1.016)
					(thickness 0.1524)
				)
				(justify mirror)
			)
		)
		(property "Device Type" "R603H22"
			(at 0.0254 -3.5433 270)
			(unlocked yes)
			(layer "B.Fab")
			(hide yes)
			(effects
				(font
					(size 1.016 1.016)
					(thickness 0.1524)
				)
				(justify mirror)
			)
		)
		(duplicate_pad_numbers_are_jumpers no)
		(fp_line
			(start -0.4318 0)
			(end -0.2032 0)
			(stroke
				(width 0.2032)
				(type default)
			)
			(layer "B.SilkS")
		)
		(fp_line
			(start 0.2032 0)
			(end 0.4191 0)
			(stroke
				(width 0.2032)
				(type default)
			)
			(layer "B.SilkS")
		)
		(fp_rect
			(start 0.635 1.1811)
			(end -0.635 -1.1811)
			(stroke
				(width 0)
				(type default)
			)
			(fill no)
			(layer "B.CrtYd")
		)
		(fp_rect
			(start 0.635 1.1811)
			(end -0.635 -1.1811)
			(stroke
				(width 0)
				(type default)
			)
			(fill no)
			(layer "B.Fab")
		)
		(pad "1" smd custom
			(at 0 -0.6604 90)
			(size 0.19685 0.19685)
			(layers "B.Cu" "B.Mask" "B.Paste")
			(net "P3V3_STBY")
			(options
				(clearance outline)
				(anchor circle)
			)
			(primitives
				(gr_poly
					(pts
						(arc
							(start 0.508 0.2921)
							(mid 0.478242 0.363942)
							(end 0.4064 0.3937)
						)
						(arc
							(start -0.4064 0.3937)
							(mid -0.478242 0.363942)
							(end -0.508 0.2921)
						)
						(arc
							(start -0.508 -0.2921)
							(mid -0.478242 -0.363942)
							(end -0.4064 -0.3937)
						)
						(arc
							(start 0.4064 -0.3937)
							(mid 0.478242 -0.363942)
							(end 0.508 -0.2921)
						)
					)
					(width 0)
					(fill yes)
				)
			)
		)
		(pad "2" smd custom
			(at 0 0.6604 90)
			(size 0.19685 0.19685)
			(layers "B.Cu" "B.Mask" "B.Paste")
			(net "VR_PVIN_P1V8_STBY")
			(options
				(clearance outline)
				(anchor circle)
			)
			(primitives
				(gr_poly
					(pts
						(arc
							(start 0.508 0.2921)
							(mid 0.478242 0.363942)
							(end 0.4064 0.3937)
						)
						(arc
							(start -0.4064 0.3937)
							(mid -0.478242 0.363942)
							(end -0.508 0.2921)
						)
						(arc
							(start -0.508 -0.2921)
							(mid -0.478242 -0.363942)
							(end -0.4064 -0.3937)
						)
						(arc
							(start 0.4064 -0.3937)
							(mid 0.478242 -0.363942)
							(end 0.508 -0.2921)
						)
					)
					(width 0)
					(fill yes)
				)
			)
		)
	)
	(footprint ""
		(layer "B.Cu")
		(at 203.4794 -56.4642 90)
		(property "Reference" "PC160"
			(at 0 0 90)
			(layer "B.SilkS")
			(hide yes)
			(effects
				(font
					(size 1.27 1.27)
				)
				(justify mirror)
			)
		)
		(property "Value" "SC22U6D3V5MX-2GP"
			(at 0 -4.9022 90)
			(unlocked yes)
			(layer "B.Fab")
			(hide yes)
			(effects
				(font
					(size 1.016 1.016)
					(thickness 0.1524)
				)
				(justify mirror)
			)
		)
		(property "Device Type" "C805H58"
			(at 0 -6.8072 90)
			(unlocked yes)
			(layer "B.Fab")
			(hide yes)
			(effects
				(font
					(size 1.016 1.016)
					(thickness 0.1524)
				)
				(justify mirror)
			)
		)
		(duplicate_pad_numbers_are_jumpers no)
		(fp_line
			(start -0.6096 0)
			(end 0.6096 0)
			(stroke
				(width 0.3048)
				(type default)
			)
			(layer "B.SilkS")
		)
		(fp_poly
			(pts
				(xy 0.9017 1.4351) (xy -0.9017 1.4351) (xy -0.9017 -1.4351) (xy 0.9017 -1.4351)
			)
			(stroke
				(width 0)
				(type default)
			)
			(fill no)
			(layer "B.CrtYd")
		)
		(fp_poly
			(pts
				(xy -0.9017 1.4351) (xy -0.9017 -1.4351) (xy 0.9017 -1.4351) (xy 0.9017 1.4351)
			)
			(stroke
				(width 0)
				(type default)
			)
			(fill no)
			(layer "B.Fab")
		)
		(pad "1" smd rect
			(at 0 -0.8382 270)
			(size 1.5494 0.9398)
			(layers "B.Cu" "B.Mask" "B.Paste")
			(net "PV_VDDR")
		)
		(pad "2" smd rect
			(at 0 0.8382 270)
			(size 1.5494 0.9398)
			(layers "B.Cu" "B.Mask" "B.Paste")
			(net "GND")
		)
	)
	(footprint ""
		(layer "B.Cu")
		(at 99.06 -43.18)
		(property "Reference" "C156"
			(at 0 0 0)
			(layer "B.SilkS")
			(hide yes)
			(effects
				(font
					(size 1.27 1.27)
				)
				(justify mirror)
			)
		)
		(property "Value" "SC1U10V2KX-1GP"
			(at -1.1811 -2.7051 0)
			(unlocked yes)
			(layer "B.Fab")
			(hide yes)
			(effects
				(font
					(size 1.016 1.016)
					(thickness 0.1524)
				)
				(justify mirror)
			)
		)
		(property "Device Type" "C402H22"
			(at -1.1811 -4.2291 0)
			(unlocked yes)
			(layer "B.Fab")
			(hide yes)
			(effects
				(font
					(size 1.016 1.016)
					(thickness 0.1524)
				)
				(justify mirror)
			)
		)
		(duplicate_pad_numbers_are_jumpers no)
		(fp_rect
			(start 0.381 0.7366)
			(end -0.381 -0.7366)
			(stroke
				(width 0)
				(type default)
			)
			(fill no)
			(layer "B.CrtYd")
		)
		(fp_rect
			(start 0.381 0.7366)
			(end -0.381 -0.7366)
			(stroke
				(width 0)
				(type default)
			)
			(fill no)
			(layer "B.Fab")
		)
		(pad "1" smd custom
			(at 0 -0.4572 180)
			(size 0.1143 0.1143)
			(layers "B.Cu" "B.Mask" "B.Paste")
			(net "VCCCLKDDR0")
			(options
				(clearance outline)
				(anchor circle)
			)
			(primitives
				(gr_poly
					(pts
						(arc
							(start -0.254 0.1778)
							(mid -0.239121 0.213721)
							(end -0.2032 0.2286)
						)
						(arc
							(start 0.2032 0.2286)
							(mid 0.239121 0.213721)
							(end 0.254 0.1778)
						)
						(arc
							(start 0.254 -0.1778)
							(mid 0.239121 -0.213721)
							(end 0.2032 -0.2286)
						)
						(arc
							(start -0.2032 -0.2286)
							(mid -0.239121 -0.213721)
							(end -0.254 -0.1778)
						)
					)
					(width 0)
					(fill yes)
				)
			)
		)
		(pad "2" smd custom
			(at 0 0.4572 180)
			(size 0.1143 0.1143)
			(layers "B.Cu" "B.Mask" "B.Paste")
			(net "GND")
			(options
				(clearance outline)
				(anchor circle)
			)
			(primitives
				(gr_poly
					(pts
						(arc
							(start -0.254 0.1778)
							(mid -0.239121 0.213721)
							(end -0.2032 0.2286)
						)
						(arc
							(start 0.2032 0.2286)
							(mid 0.239121 0.213721)
							(end 0.254 0.1778)
						)
						(arc
							(start 0.254 -0.1778)
							(mid 0.239121 -0.213721)
							(end 0.2032 -0.2286)
						)
						(arc
							(start -0.2032 -0.2286)
							(mid -0.239121 -0.213721)
							(end -0.254 -0.1778)
						)
					)
					(width 0)
					(fill yes)
				)
			)
		)
	)
	(footprint ""
		(layer "B.Cu")
		(at 74.041 -37.465 90)
		(property "Reference" "R94"
			(at 0 0 90)
			(layer "B.SilkS")
			(hide yes)
			(effects
				(font
					(size 1.27 1.27)
				)
				(justify mirror)
			)
		)
		(property "Value" "10KR2F-2-GP"
			(at -0.064008 -3.993896 90)
			(unlocked yes)
			(layer "B.Fab")
			(hide yes)
			(effects
				(font
					(size 1.016 1.016)
					(thickness 0.1524)
				)
				(justify mirror)
			)
		)
		(property "Device Type" "R402H16"
			(at -0.064008 -5.517896 90)
			(unlocked yes)
			(layer "B.Fab")
			(hide yes)
			(effects
				(font
					(size 1.016 1.016)
					(thickness 0.1524)
				)
				(justify mirror)
			)
		)
		(duplicate_pad_numbers_are_jumpers no)
		(fp_rect
			(start 0.381 0.8382)
			(end -0.381 -0.8382)
			(stroke
				(width 0)
				(type default)
			)
			(fill no)
			(layer "B.CrtYd")
		)
		(fp_rect
			(start 0.381 0.8382)
			(end -0.381 -0.8382)
			(stroke
				(width 0)
				(type default)
			)
			(fill no)
			(layer "B.Fab")
		)
		(pad "1" smd custom
			(at 0 -0.4318 270)
			(size 0.127 0.127)
			(layers "B.Cu" "B.Mask" "B.Paste")
			(net "P3V3")
			(options
				(clearance outline)
				(anchor circle)
			)
			(primitives
				(gr_poly
					(pts
						(arc
							(start -0.2032 0.2794)
							(mid -0.239121 0.264521)
							(end -0.254 0.2286)
						)
						(arc
							(start -0.254 -0.2286)
							(mid -0.239121 -0.264521)
							(end -0.2032 -0.2794)
						)
						(arc
							(start 0.2032 -0.2794)
							(mid 0.239121 -0.264521)
							(end 0.254 -0.2286)
						)
						(arc
							(start 0.254 0.2286)
							(mid 0.239121 0.264521)
							(end 0.2032 0.2794)
						)
					)
					(width 0)
					(fill yes)
				)
			)
		)
		(pad "2" smd custom
			(at 0 0.4318 270)
			(size 0.127 0.127)
			(layers "B.Cu" "B.Mask" "B.Paste")
			(net "FLEX_CLK_SE0")
			(options
				(clearance outline)
				(anchor circle)
			)
			(primitives
				(gr_poly
					(pts
						(arc
							(start -0.2032 0.2794)
							(mid -0.239121 0.264521)
							(end -0.254 0.2286)
						)
						(arc
							(start -0.254 -0.2286)
							(mid -0.239121 -0.264521)
							(end -0.2032 -0.2794)
						)
						(arc
							(start 0.2032 -0.2794)
							(mid 0.239121 -0.264521)
							(end 0.254 -0.2286)
						)
						(arc
							(start 0.254 0.2286)
							(mid 0.239121 0.264521)
							(end 0.2032 0.2794)
						)
					)
					(width 0)
					(fill yes)
				)
			)
		)
	)
	(footprint ""
		(layer "B.Cu")
		(at 75.946 -40.005 -90)
		(property "Reference" "R322"
			(at 0 0 90)
			(layer "B.SilkS")
			(hide yes)
			(effects
				(font
					(size 1.27 1.27)
				)
				(justify mirror)
			)
		)
		(property "Value" "0R2J-2-GP"
			(at -0.064008 -3.993896 270)
			(unlocked yes)
			(layer "B.Fab")
			(hide yes)
			(effects
				(font
					(size 1.016 1.016)
					(thickness 0.1524)
				)
				(justify mirror)
			)
		)
		(property "Device Type" "R402H16"
			(at -0.064008 -5.517896 270)
			(unlocked yes)
			(layer "B.Fab")
			(hide yes)
			(effects
				(font
					(size 1.016 1.016)
					(thickness 0.1524)
				)
				(justify mirror)
			)
		)
		(duplicate_pad_numbers_are_jumpers no)
		(fp_rect
			(start 0.381 0.8382)
			(end -0.381 -0.8382)
			(stroke
				(width 0)
				(type default)
			)
			(fill no)
			(layer "B.CrtYd")
		)
		(fp_rect
			(start 0.381 0.8382)
			(end -0.381 -0.8382)
			(stroke
				(width 0)
				(type default)
			)
			(fill no)
			(layer "B.Fab")
		)
		(pad "1" smd custom
			(at 0 -0.4318 90)
			(size 0.127 0.127)
			(layers "B.Cu" "B.Mask" "B.Paste")
			(net "CORE_PWROK_R")
			(options
				(clearance outline)
				(anchor circle)
			)
			(primitives
				(gr_poly
					(pts
						(arc
							(start -0.2032 0.2794)
							(mid -0.239121 0.264521)
							(end -0.254 0.2286)
						)
						(arc
							(start -0.254 -0.2286)
							(mid -0.239121 -0.264521)
							(end -0.2032 -0.2794)
						)
						(arc
							(start 0.2032 -0.2794)
							(mid 0.239121 -0.264521)
							(end 0.254 -0.2286)
						)
						(arc
							(start 0.254 0.2286)
							(mid 0.239121 0.264521)
							(end 0.2032 0.2794)
						)
					)
					(width 0)
					(fill yes)
				)
			)
		)
		(pad "2" smd custom
			(at 0 0.4318 90)
			(size 0.127 0.127)
			(layers "B.Cu" "B.Mask" "B.Paste")
			(net "CORE_PWROK")
			(options
				(clearance outline)
				(anchor circle)
			)
			(primitives
				(gr_poly
					(pts
						(arc
							(start -0.2032 0.2794)
							(mid -0.239121 0.264521)
							(end -0.254 0.2286)
						)
						(arc
							(start -0.254 -0.2286)
							(mid -0.239121 -0.264521)
							(end -0.2032 -0.2794)
						)
						(arc
							(start 0.2032 -0.2794)
							(mid 0.239121 -0.264521)
							(end 0.254 -0.2286)
						)
						(arc
							(start 0.254 0.2286)
							(mid 0.239121 0.264521)
							(end 0.2032 0.2794)
						)
					)
					(width 0)
					(fill yes)
				)
			)
		)
	)
	(footprint ""
		(layer "B.Cu")
		(at 199.300084 -66.300096 90)
		(property "Reference" "LED17"
			(at 0 0 90)
			(layer "B.SilkS")
			(hide yes)
			(effects
				(font
					(size 1.27 1.27)
				)
				(justify mirror)
			)
		)
		(property "Value" "LED-YG-51-GP"
			(at 0.0381 -2.6162 90)
			(unlocked yes)
			(layer "B.Fab")
			(hide yes)
			(effects
				(font
					(size 1.016 1.016)
					(thickness 0.1524)
				)
				(justify mirror)
			)
		)
		(property "Device Type" "LED1608AKH40"
			(at 0.0381 -4.1402 90)
			(unlocked yes)
			(layer "B.Fab")
			(hide yes)
			(effects
				(font
					(size 1.016 1.016)
					(thickness 0.1524)
				)
				(justify mirror)
			)
		)
		(duplicate_pad_numbers_are_jumpers no)
		(fp_line
			(start 0.5334 1.3081)
			(end -0.5334 1.3081)
			(stroke
				(width 0.254)
				(type default)
			)
			(layer "B.SilkS")
		)
		(fp_rect
			(start 0.6604 1.1811)
			(end -0.6604 -1.1811)
			(stroke
				(width 0)
				(type default)
			)
			(fill no)
			(layer "B.CrtYd")
		)
		(fp_rect
			(start 0.6604 1.1811)
			(end -0.6604 -1.1811)
			(stroke
				(width 0)
				(type default)
			)
			(fill no)
			(layer "B.Fab")
		)
		(pad "A" smd rect
			(at 0 -0.652526 270)
			(size 1.0668 0.8128)
			(layers "B.Cu" "B.Mask" "B.Paste")
			(net "DIAG_LED")
		)
		(pad "K" smd rect
			(at 0 0.652526 270)
			(size 1.0668 0.8128)
			(layers "B.Cu" "B.Mask" "B.Paste")
			(net "CPU_DIAG_LED_D")
		)
	)
	(footprint ""
		(layer "B.Cu")
		(at 17.272 -60.071)
		(property "Reference" "PC5"
			(at 0 0 0)
			(layer "B.SilkS")
			(hide yes)
			(effects
				(font
					(size 1.27 1.27)
				)
				(justify mirror)
			)
		)
		(property "Value" "SC5600P25V2KX-2-GP"
			(at -1.8923 -1.2065 0)
			(unlocked yes)
			(layer "B.Fab")
			(hide yes)
			(effects
				(font
					(size 1.016 1.016)
					(thickness 0.1524)
				)
				(justify mirror)
			)
		)
		(property "Device Type" "C402H22"
			(at -1.8923 -2.7305 0)
			(unlocked yes)
			(layer "B.Fab")
			(hide yes)
			(effects
				(font
					(size 1.016 1.016)
					(thickness 0.1524)
				)
				(justify mirror)
			)
		)
		(duplicate_pad_numbers_are_jumpers no)
		(fp_rect
			(start 0.381 0.7366)
			(end -0.381 -0.7366)
			(stroke
				(width 0)
				(type default)
			)
			(fill no)
			(layer "B.CrtYd")
		)
		(fp_rect
			(start 0.381 0.7366)
			(end -0.381 -0.7366)
			(stroke
				(width 0)
				(type default)
			)
			(fill no)
			(layer "B.Fab")
		)
		(pad "1" smd custom
			(at 0 -0.4572 180)
			(size 0.1143 0.1143)
			(layers "B.Cu" "B.Mask" "B.Paste")
			(net "VR_PVNN_COMP")
			(options
				(clearance outline)
				(anchor circle)
			)
			(primitives
				(gr_poly
					(pts
						(arc
							(start -0.254 0.1778)
							(mid -0.239121 0.213721)
							(end -0.2032 0.2286)
						)
						(arc
							(start 0.2032 0.2286)
							(mid 0.239121 0.213721)
							(end 0.254 0.1778)
						)
						(arc
							(start 0.254 -0.1778)
							(mid 0.239121 -0.213721)
							(end 0.2032 -0.2286)
						)
						(arc
							(start -0.2032 -0.2286)
							(mid -0.239121 -0.213721)
							(end -0.254 -0.1778)
						)
					)
					(width 0)
					(fill yes)
				)
			)
		)
		(pad "2" smd custom
			(at 0 0.4572 180)
			(size 0.1143 0.1143)
			(layers "B.Cu" "B.Mask" "B.Paste")
			(net "VR_PVNN_COMP_RC")
			(options
				(clearance outline)
				(anchor circle)
			)
			(primitives
				(gr_poly
					(pts
						(arc
							(start -0.254 0.1778)
							(mid -0.239121 0.213721)
							(end -0.2032 0.2286)
						)
						(arc
							(start 0.2032 0.2286)
							(mid 0.239121 0.213721)
							(end 0.254 0.1778)
						)
						(arc
							(start 0.254 -0.1778)
							(mid 0.239121 -0.213721)
							(end 0.2032 -0.2286)
						)
						(arc
							(start -0.2032 -0.2286)
							(mid -0.239121 -0.213721)
							(end -0.254 -0.1778)
						)
					)
					(width 0)
					(fill yes)
				)
			)
		)
	)
	(footprint ""
		(layer "B.Cu")
		(at 50.038 -58.547 -90)
		(property "Reference" "PR43"
			(at 0 0 90)
			(layer "B.SilkS")
			(hide yes)
			(effects
				(font
					(size 1.27 1.27)
				)
				(justify mirror)
			)
		)
		(property "Value" "0R2J-2-GP"
			(at -1.7907 -1.1176 270)
			(unlocked yes)
			(layer "B.Fab")
			(hide yes)
			(effects
				(font
					(size 1.016 1.016)
					(thickness 0.1524)
				)
				(justify mirror)
			)
		)
		(property "Device Type" "R402H16"
			(at -1.7907 -2.6416 270)
			(unlocked yes)
			(layer "B.Fab")
			(hide yes)
			(effects
				(font
					(size 1.016 1.016)
					(thickness 0.1524)
				)
				(justify mirror)
			)
		)
		(duplicate_pad_numbers_are_jumpers no)
		(fp_rect
			(start 0.381 0.8382)
			(end -0.381 -0.8382)
			(stroke
				(width 0)
				(type default)
			)
			(fill no)
			(layer "B.CrtYd")
		)
		(fp_rect
			(start 0.381 0.8382)
			(end -0.381 -0.8382)
			(stroke
				(width 0)
				(type default)
			)
			(fill no)
			(layer "B.Fab")
		)
		(pad "1" smd custom
			(at 0 -0.4318 90)
			(size 0.127 0.127)
			(layers "B.Cu" "B.Mask" "B.Paste")
			(net "VR_PVCCP_ISUMP_R2")
			(options
				(clearance outline)
				(anchor circle)
			)
			(primitives
				(gr_poly
					(pts
						(arc
							(start -0.2032 0.2794)
							(mid -0.239121 0.264521)
							(end -0.254 0.2286)
						)
						(arc
							(start -0.254 -0.2286)
							(mid -0.239121 -0.264521)
							(end -0.2032 -0.2794)
						)
						(arc
							(start 0.2032 -0.2794)
							(mid 0.239121 -0.264521)
							(end 0.254 -0.2286)
						)
						(arc
							(start 0.254 0.2286)
							(mid 0.239121 0.264521)
							(end 0.2032 0.2794)
						)
					)
					(width 0)
					(fill yes)
				)
			)
		)
		(pad "2" smd custom
			(at 0 0.4318 90)
			(size 0.127 0.127)
			(layers "B.Cu" "B.Mask" "B.Paste")
			(net "VR_PVCCP_PWM_OUT")
			(options
				(clearance outline)
				(anchor circle)
			)
			(primitives
				(gr_poly
					(pts
						(arc
							(start -0.2032 0.2794)
							(mid -0.239121 0.264521)
							(end -0.254 0.2286)
						)
						(arc
							(start -0.254 -0.2286)
							(mid -0.239121 -0.264521)
							(end -0.2032 -0.2794)
						)
						(arc
							(start 0.2032 -0.2794)
							(mid 0.239121 -0.264521)
							(end 0.254 -0.2286)
						)
						(arc
							(start 0.254 0.2286)
							(mid 0.239121 0.264521)
							(end 0.2032 0.2794)
						)
					)
					(width 0)
					(fill yes)
				)
			)
		)
	)
	(footprint ""
		(layer "B.Cu")
		(at 80.01 -23.6474)
		(property "Reference" "PR219"
			(at 0 0 0)
			(layer "B.SilkS")
			(hide yes)
			(effects
				(font
					(size 1.27 1.27)
				)
				(justify mirror)
			)
		)
		(property "Value" "0R2J-2-GP"
			(at -0.064008 -3.993896 0)
			(unlocked yes)
			(layer "B.Fab")
			(hide yes)
			(effects
				(font
					(size 1.016 1.016)
					(thickness 0.1524)
				)
				(justify mirror)
			)
		)
		(property "Device Type" "R402H16"
			(at -0.064008 -5.517896 0)
			(unlocked yes)
			(layer "B.Fab")
			(hide yes)
			(effects
				(font
					(size 1.016 1.016)
					(thickness 0.1524)
				)
				(justify mirror)
			)
		)
		(duplicate_pad_numbers_are_jumpers no)
		(fp_rect
			(start 0.381 0.8382)
			(end -0.381 -0.8382)
			(stroke
				(width 0)
				(type default)
			)
			(fill no)
			(layer "B.CrtYd")
		)
		(fp_rect
			(start 0.381 0.8382)
			(end -0.381 -0.8382)
			(stroke
				(width 0)
				(type default)
			)
			(fill no)
			(layer "B.Fab")
		)
		(pad "1" smd custom
			(at 0 -0.4318 180)
			(size 0.127 0.127)
			(layers "B.Cu" "B.Mask" "B.Paste")
			(net "PWRGD_P1V1_PG")
			(options
				(clearance outline)
				(anchor circle)
			)
			(primitives
				(gr_poly
					(pts
						(arc
							(start -0.2032 0.2794)
							(mid -0.239121 0.264521)
							(end -0.254 0.2286)
						)
						(arc
							(start -0.254 -0.2286)
							(mid -0.239121 -0.264521)
							(end -0.2032 -0.2794)
						)
						(arc
							(start 0.2032 -0.2794)
							(mid 0.239121 -0.264521)
							(end 0.254 -0.2286)
						)
						(arc
							(start 0.254 0.2286)
							(mid 0.239121 0.264521)
							(end 0.2032 0.2794)
						)
					)
					(width 0)
					(fill yes)
				)
			)
		)
		(pad "2" smd custom
			(at 0 0.4318 180)
			(size 0.127 0.127)
			(layers "B.Cu" "B.Mask" "B.Paste")
			(net "TPS74801_1V35_EN")
			(options
				(clearance outline)
				(anchor circle)
			)
			(primitives
				(gr_poly
					(pts
						(arc
							(start -0.2032 0.2794)
							(mid -0.239121 0.264521)
							(end -0.254 0.2286)
						)
						(arc
							(start -0.254 -0.2286)
							(mid -0.239121 -0.264521)
							(end -0.2032 -0.2794)
						)
						(arc
							(start 0.2032 -0.2794)
							(mid 0.239121 -0.264521)
							(end 0.254 -0.2286)
						)
						(arc
							(start 0.254 0.2286)
							(mid 0.239121 0.264521)
							(end 0.2032 0.2794)
						)
					)
					(width 0)
					(fill yes)
				)
			)
		)
	)
	(footprint ""
		(layer "B.Cu")
		(at 165.227 -12.574778 180)
		(property "Reference" "C301"
			(at 0 0 0)
			(layer "B.SilkS")
			(hide yes)
			(effects
				(font
					(size 1.27 1.27)
				)
				(justify mirror)
			)
		)
		(property "Value" "SC10U6D3V3MX-GP"
			(at 0.0254 -2.0193 180)
			(unlocked yes)
			(layer "B.Fab")
			(hide yes)
			(effects
				(font
					(size 1.016 1.016)
					(thickness 0.1524)
				)
				(justify mirror)
			)
		)
		(property "Device Type" "C603H38"
			(at 0.0254 -3.5433 180)
			(unlocked yes)
			(layer "B.Fab")
			(hide yes)
			(effects
				(font
					(size 1.016 1.016)
					(thickness 0.1524)
				)
				(justify mirror)
			)
		)
		(duplicate_pad_numbers_are_jumpers no)
		(fp_line
			(start 0.4064 0)
			(end -0.4064 0)
			(stroke
				(width 0.2286)
				(type default)
			)
			(layer "B.SilkS")
		)
		(fp_rect
			(start 0.635 1.1811)
			(end -0.635 -1.1811)
			(stroke
				(width 0)
				(type default)
			)
			(fill no)
			(layer "B.CrtYd")
		)
		(fp_rect
			(start 0.635 1.1811)
			(end -0.635 -1.1811)
			(stroke
				(width 0)
				(type default)
			)
			(fill no)
			(layer "B.Fab")
		)
		(pad "1" smd custom
			(at 0 -0.6604)
			(size 0.19685 0.19685)
			(layers "B.Cu" "B.Mask" "B.Paste")
			(net "PV_VDDR")
			(options
				(clearance outline)
				(anchor circle)
			)
			(primitives
				(gr_poly
					(pts
						(arc
							(start 0.508 0.2921)
							(mid 0.478242 0.363942)
							(end 0.4064 0.3937)
						)
						(arc
							(start -0.4064 0.3937)
							(mid -0.478242 0.363942)
							(end -0.508 0.2921)
						)
						(arc
							(start -0.508 -0.2921)
							(mid -0.478242 -0.363942)
							(end -0.4064 -0.3937)
						)
						(arc
							(start 0.4064 -0.3937)
							(mid 0.478242 -0.363942)
							(end 0.508 -0.2921)
						)
					)
					(width 0)
					(fill yes)
				)
			)
		)
		(pad "2" smd custom
			(at 0 0.6604)
			(size 0.19685 0.19685)
			(layers "B.Cu" "B.Mask" "B.Paste")
			(net "GND")
			(options
				(clearance outline)
				(anchor circle)
			)
			(primitives
				(gr_poly
					(pts
						(arc
							(start 0.508 0.2921)
							(mid 0.478242 0.363942)
							(end 0.4064 0.3937)
						)
						(arc
							(start -0.4064 0.3937)
							(mid -0.478242 0.363942)
							(end -0.508 0.2921)
						)
						(arc
							(start -0.508 -0.2921)
							(mid -0.478242 -0.363942)
							(end -0.4064 -0.3937)
						)
						(arc
							(start 0.4064 -0.3937)
							(mid 0.478242 -0.363942)
							(end 0.508 -0.2921)
						)
					)
					(width 0)
					(fill yes)
				)
			)
		)
	)
	(footprint ""
		(layer "B.Cu")
		(at 187.7822 -28.067 180)
		(property "Reference" "PC190"
			(at 0 0 0)
			(layer "B.SilkS")
			(hide yes)
			(effects
				(font
					(size 1.27 1.27)
				)
				(justify mirror)
			)
		)
		(property "Value" "SCD1U16V2KX-3GP"
			(at -1.8923 -1.2065 180)
			(unlocked yes)
			(layer "B.Fab")
			(hide yes)
			(effects
				(font
					(size 1.016 1.016)
					(thickness 0.1524)
				)
				(justify mirror)
			)
		)
		(property "Device Type" "C402H22"
			(at -1.8923 -2.7305 180)
			(unlocked yes)
			(layer "B.Fab")
			(hide yes)
			(effects
				(font
					(size 1.016 1.016)
					(thickness 0.1524)
				)
				(justify mirror)
			)
		)
		(duplicate_pad_numbers_are_jumpers no)
		(fp_rect
			(start 0.381 0.7366)
			(end -0.381 -0.7366)
			(stroke
				(width 0)
				(type default)
			)
			(fill no)
			(layer "B.CrtYd")
		)
		(fp_rect
			(start 0.381 0.7366)
			(end -0.381 -0.7366)
			(stroke
				(width 0)
				(type default)
			)
			(fill no)
			(layer "B.Fab")
		)
		(pad "1" smd custom
			(at 0 -0.4572)
			(size 0.1143 0.1143)
			(layers "B.Cu" "B.Mask" "B.Paste")
			(net "VR_PVDDRA_ISUMN1")
			(options
				(clearance outline)
				(anchor circle)
			)
			(primitives
				(gr_poly
					(pts
						(arc
							(start -0.254 0.1778)
							(mid -0.239121 0.213721)
							(end -0.2032 0.2286)
						)
						(arc
							(start 0.2032 0.2286)
							(mid 0.239121 0.213721)
							(end 0.254 0.1778)
						)
						(arc
							(start 0.254 -0.1778)
							(mid 0.239121 -0.213721)
							(end 0.2032 -0.2286)
						)
						(arc
							(start -0.2032 -0.2286)
							(mid -0.239121 -0.213721)
							(end -0.254 -0.1778)
						)
					)
					(width 0)
					(fill yes)
				)
			)
		)
		(pad "2" smd custom
			(at 0 0.4572)
			(size 0.1143 0.1143)
			(layers "B.Cu" "B.Mask" "B.Paste")
			(net "GND")
			(options
				(clearance outline)
				(anchor circle)
			)
			(primitives
				(gr_poly
					(pts
						(arc
							(start -0.254 0.1778)
							(mid -0.239121 0.213721)
							(end -0.2032 0.2286)
						)
						(arc
							(start 0.2032 0.2286)
							(mid 0.239121 0.213721)
							(end 0.254 0.1778)
						)
						(arc
							(start 0.254 -0.1778)
							(mid 0.239121 -0.213721)
							(end 0.2032 -0.2286)
						)
						(arc
							(start -0.2032 -0.2286)
							(mid -0.239121 -0.213721)
							(end -0.254 -0.1778)
						)
					)
					(width 0)
					(fill yes)
				)
			)
		)
	)
	(footprint ""
		(layer "B.Cu")
		(at 72.4916 -42.672 -90)
		(property "Reference" "R404"
			(at 0 0 90)
			(layer "B.SilkS")
			(hide yes)
			(effects
				(font
					(size 1.27 1.27)
				)
				(justify mirror)
			)
		)
		(property "Value" "0R2J-2-GP"
			(at -1.7907 -1.1176 270)
			(unlocked yes)
			(layer "B.Fab")
			(hide yes)
			(effects
				(font
					(size 1.016 1.016)
					(thickness 0.1524)
				)
				(justify mirror)
			)
		)
		(property "Device Type" "R402H16"
			(at -1.7907 -2.6416 270)
			(unlocked yes)
			(layer "B.Fab")
			(hide yes)
			(effects
				(font
					(size 1.016 1.016)
					(thickness 0.1524)
				)
				(justify mirror)
			)
		)
		(duplicate_pad_numbers_are_jumpers no)
		(fp_rect
			(start 0.381 0.8382)
			(end -0.381 -0.8382)
			(stroke
				(width 0)
				(type default)
			)
			(fill no)
			(layer "B.CrtYd")
		)
		(fp_rect
			(start 0.381 0.8382)
			(end -0.381 -0.8382)
			(stroke
				(width 0)
				(type default)
			)
			(fill no)
			(layer "B.Fab")
		)
		(pad "1" smd custom
			(at 0 -0.4318 90)
			(size 0.127 0.127)
			(layers "B.Cu" "B.Mask" "B.Paste")
			(net "CPU_DIAG_LED")
			(options
				(clearance outline)
				(anchor circle)
			)
			(primitives
				(gr_poly
					(pts
						(arc
							(start -0.2032 0.2794)
							(mid -0.239121 0.264521)
							(end -0.254 0.2286)
						)
						(arc
							(start -0.254 -0.2286)
							(mid -0.239121 -0.264521)
							(end -0.2032 -0.2794)
						)
						(arc
							(start 0.2032 -0.2794)
							(mid 0.239121 -0.264521)
							(end 0.254 -0.2286)
						)
						(arc
							(start 0.254 0.2286)
							(mid 0.239121 0.264521)
							(end 0.2032 0.2794)
						)
					)
					(width 0)
					(fill yes)
				)
			)
		)
		(pad "2" smd custom
			(at 0 0.4318 90)
			(size 0.127 0.127)
			(layers "B.Cu" "B.Mask" "B.Paste")
			(net "CPU_DIAG_LED_R")
			(options
				(clearance outline)
				(anchor circle)
			)
			(primitives
				(gr_poly
					(pts
						(arc
							(start -0.2032 0.2794)
							(mid -0.239121 0.264521)
							(end -0.254 0.2286)
						)
						(arc
							(start -0.254 -0.2286)
							(mid -0.239121 -0.264521)
							(end -0.2032 -0.2794)
						)
						(arc
							(start 0.2032 -0.2794)
							(mid 0.239121 -0.264521)
							(end 0.254 -0.2286)
						)
						(arc
							(start 0.254 0.2286)
							(mid 0.239121 0.264521)
							(end 0.2032 0.2794)
						)
					)
					(width 0)
					(fill yes)
				)
			)
		)
	)
	(footprint ""
		(layer "B.Cu")
		(at 46.863 -14.605 -90)
		(property "Reference" "R426"
			(at 0 0 90)
			(layer "B.SilkS")
			(hide yes)
			(effects
				(font
					(size 1.27 1.27)
				)
				(justify mirror)
			)
		)
		(property "Value" "43D2R2F-GP"
			(at -1.7907 -1.1176 270)
			(unlocked yes)
			(layer "B.Fab")
			(hide yes)
			(effects
				(font
					(size 1.016 1.016)
					(thickness 0.1524)
				)
				(justify mirror)
			)
		)
		(property "Device Type" "R402H16"
			(at -1.7907 -2.6416 270)
			(unlocked yes)
			(layer "B.Fab")
			(hide yes)
			(effects
				(font
					(size 1.016 1.016)
					(thickness 0.1524)
				)
				(justify mirror)
			)
		)
		(duplicate_pad_numbers_are_jumpers no)
		(fp_rect
			(start 0.381 0.8382)
			(end -0.381 -0.8382)
			(stroke
				(width 0)
				(type default)
			)
			(fill no)
			(layer "B.CrtYd")
		)
		(fp_rect
			(start 0.381 0.8382)
			(end -0.381 -0.8382)
			(stroke
				(width 0)
				(type default)
			)
			(fill no)
			(layer "B.Fab")
		)
		(pad "1" smd custom
			(at 0 -0.4318 90)
			(size 0.127 0.127)
			(layers "B.Cu" "B.Mask" "B.Paste")
			(net "CLK_100M_PCIE2_REFCLK_DN")
			(options
				(clearance outline)
				(anchor circle)
			)
			(primitives
				(gr_poly
					(pts
						(arc
							(start -0.2032 0.2794)
							(mid -0.239121 0.264521)
							(end -0.254 0.2286)
						)
						(arc
							(start -0.254 -0.2286)
							(mid -0.239121 -0.264521)
							(end -0.2032 -0.2794)
						)
						(arc
							(start 0.2032 -0.2794)
							(mid 0.239121 -0.264521)
							(end 0.254 -0.2286)
						)
						(arc
							(start 0.254 0.2286)
							(mid 0.239121 0.264521)
							(end 0.2032 0.2794)
						)
					)
					(width 0)
					(fill yes)
				)
			)
		)
		(pad "2" smd custom
			(at 0 0.4318 90)
			(size 0.127 0.127)
			(layers "B.Cu" "B.Mask" "B.Paste")
			(net "GND")
			(options
				(clearance outline)
				(anchor circle)
			)
			(primitives
				(gr_poly
					(pts
						(arc
							(start -0.2032 0.2794)
							(mid -0.239121 0.264521)
							(end -0.254 0.2286)
						)
						(arc
							(start -0.254 -0.2286)
							(mid -0.239121 -0.264521)
							(end -0.2032 -0.2794)
						)
						(arc
							(start 0.2032 -0.2794)
							(mid 0.239121 -0.264521)
							(end 0.254 -0.2286)
						)
						(arc
							(start 0.254 0.2286)
							(mid 0.239121 0.264521)
							(end 0.2032 0.2794)
						)
					)
					(width 0)
					(fill yes)
				)
			)
		)
	)
	(footprint ""
		(layer "B.Cu")
		(at 10.850118 -58.699908 90)
		(property "Reference" "NGFF1"
			(at 0 0 90)
			(layer "B.SilkS")
			(hide yes)
			(effects
				(font
					(size 1.27 1.27)
				)
				(justify mirror)
			)
		)
		(property "Value" "SKT-MINI67P-10-GP"
			(at -3.6957 -7.7851 90)
			(unlocked yes)
			(layer "B.Fab")
			(hide yes)
			(effects
				(font
					(size 1.016 1.016)
					(thickness 0.1524)
				)
				(justify mirror)
			)
		)
		(property "Device Type" "80159-4225"
			(at -3.6957 -9.3091 90)
			(unlocked yes)
			(layer "B.Fab")
			(hide yes)
			(effects
				(font
					(size 1.016 1.016)
					(thickness 0.1524)
				)
				(justify mirror)
			)
		)
		(duplicate_pad_numbers_are_jumpers no)
		(fp_poly
			(pts
				(xy 9.24179 -6.1722) (xy 8.73379 -6.6802) (xy 9.74979 -6.6802)
			)
			(stroke
				(width 0)
				(type default)
			)
			(fill yes)
			(layer "B.SilkS")
		)
		(fp_rect
			(start 11.2141 3.175)
			(end -11.2141 -6.1722)
			(stroke
				(width 0)
				(type default)
			)
			(fill no)
			(layer "B.CrtYd")
		)
		(fp_rect
			(start 11.2141 3.175)
			(end -11.2141 -6.1722)
			(stroke
				(width 0)
				(type default)
			)
			(fill no)
			(layer "B.Fab")
		)
		(pad "" np_thru_hole circle
			(at -9.99998 0 270)
			(size 0.254 0.254)
			(drill 1.651)
			(layers "*.Cu" "*.Mask")
			(clearance 1.0541)
			(thermal_gap 1.0541)
		)
		(pad "" np_thru_hole circle
			(at 9.99998 0 270)
			(size 0.254 0.254)
			(drill 1.1176)
			(layers "*.Cu" "*.Mask")
			(clearance 0.7874)
			(thermal_gap 0.7874)
		)
		(pad "1" smd rect
			(at 9.249918 -5.275072 270)
			(size 0.3048 1.5494)
			(layers "B.Cu" "B.Mask" "B.Paste")
			(net "NGFF_PRESENT_R#")
		)
		(pad "2" smd rect
			(at 8.999982 2.275078 270)
			(size 0.3048 1.5494)
			(layers "B.Cu" "B.Mask" "B.Paste")
			(net "P3V3")
		)
		(pad "3" smd rect
			(at 8.750046 -5.275072 270)
			(size 0.3048 1.5494)
			(layers "B.Cu" "B.Mask" "B.Paste")
			(net "GND")
		)
		(pad "4" smd rect
			(at 8.50011 2.275078 270)
			(size 0.3048 1.5494)
			(layers "B.Cu" "B.Mask" "B.Paste")
			(net "P3V3")
		)
		(pad "5" smd rect
			(at 8.24992 -5.275072 270)
			(size 0.3048 1.5494)
			(layers "B.Cu" "B.Mask" "B.Paste")
			(net "P2E_CPU_NGFF_C_RX_DN15")
		)
		(pad "6" smd rect
			(at 7.999984 2.275078 270)
			(size 0.3048 1.5494)
			(layers "B.Cu" "B.Mask" "B.Paste")
			(net "Net_1393")
		)
		(pad "7" smd rect
			(at 7.750048 -5.275072 270)
			(size 0.3048 1.5494)
			(layers "B.Cu" "B.Mask" "B.Paste")
			(net "P2E_CPU_NGFF_C_RX_DP15")
		)
		(pad "8" smd rect
			(at 7.500112 2.275078 270)
			(size 0.3048 1.5494)
			(layers "B.Cu" "B.Mask" "B.Paste")
			(net "Net_1392")
		)
		(pad "9" smd rect
			(at 7.249922 -5.275072 270)
			(size 0.3048 1.5494)
			(layers "B.Cu" "B.Mask" "B.Paste")
			(net "GND")
		)
		(pad "10" smd rect
			(at 6.999986 2.275078 270)
			(size 0.3048 1.5494)
			(layers "B.Cu" "B.Mask" "B.Paste")
			(net "LED_NGFF_DAS")
		)
		(pad "11" smd rect
			(at 6.75005 -5.275072 270)
			(size 0.3048 1.5494)
			(layers "B.Cu" "B.Mask" "B.Paste")
			(net "P2E_CPU_NGFF_TX_DN15")
		)
		(pad "12" smd rect
			(at 6.500114 2.275078 270)
			(size 0.3048 1.5494)
			(layers "B.Cu" "B.Mask" "B.Paste")
			(net "P3V3")
		)
		(pad "13" smd rect
			(at 6.249924 -5.275072 270)
			(size 0.3048 1.5494)
			(layers "B.Cu" "B.Mask" "B.Paste")
			(net "P2E_CPU_NGFF_TX_DP15")
		)
		(pad "14" smd rect
			(at 5.999988 2.275078 270)
			(size 0.3048 1.5494)
			(layers "B.Cu" "B.Mask" "B.Paste")
			(net "P3V3")
		)
		(pad "15" smd rect
			(at 5.750052 -5.275072 270)
			(size 0.3048 1.5494)
			(layers "B.Cu" "B.Mask" "B.Paste")
			(net "GND")
		)
		(pad "16" smd rect
			(at 5.500116 2.275078 270)
			(size 0.3048 1.5494)
			(layers "B.Cu" "B.Mask" "B.Paste")
			(net "P3V3")
		)
		(pad "17" smd rect
			(at 5.249926 -5.275072 270)
			(size 0.3048 1.5494)
			(layers "B.Cu" "B.Mask" "B.Paste")
			(net "P2E_CPU_NGFF_C_RX_DN14")
		)
		(pad "18" smd rect
			(at 4.99999 2.275078 270)
			(size 0.3048 1.5494)
			(layers "B.Cu" "B.Mask" "B.Paste")
			(net "P3V3")
		)
		(pad "19" smd rect
			(at 4.750054 -5.275072 270)
			(size 0.3048 1.5494)
			(layers "B.Cu" "B.Mask" "B.Paste")
			(net "P2E_CPU_NGFF_C_RX_DP14")
		)
		(pad "20" smd rect
			(at 4.500118 2.275078 270)
			(size 0.3048 1.5494)
			(layers "B.Cu" "B.Mask" "B.Paste")
			(net "Net_1391")
		)
		(pad "21" smd rect
			(at 4.249928 -5.275072 270)
			(size 0.3048 1.5494)
			(layers "B.Cu" "B.Mask" "B.Paste")
			(net "GND")
		)
		(pad "22" smd rect
			(at 3.999992 2.275078 270)
			(size 0.3048 1.5494)
			(layers "B.Cu" "B.Mask" "B.Paste")
			(net "Net_1390")
		)
		(pad "23" smd rect
			(at 3.750056 -5.275072 270)
			(size 0.3048 1.5494)
			(layers "B.Cu" "B.Mask" "B.Paste")
			(net "P2E_CPU_NGFF_TX_DN14")
		)
		(pad "24" smd rect
			(at 3.50012 2.275078 270)
			(size 0.3048 1.5494)
			(layers "B.Cu" "B.Mask" "B.Paste")
			(net "Net_1389")
		)
		(pad "25" smd rect
			(at 3.24993 -5.275072 270)
			(size 0.3048 1.5494)
			(layers "B.Cu" "B.Mask" "B.Paste")
			(net "P2E_CPU_NGFF_TX_DP14")
		)
		(pad "26" smd rect
			(at 2.999994 2.275078 270)
			(size 0.3048 1.5494)
			(layers "B.Cu" "B.Mask" "B.Paste")
			(net "Net_1388")
		)
		(pad "27" smd rect
			(at 2.750058 -5.275072 270)
			(size 0.3048 1.5494)
			(layers "B.Cu" "B.Mask" "B.Paste")
			(net "GND")
		)
		(pad "28" smd rect
			(at 2.500122 2.275078 270)
			(size 0.3048 1.5494)
			(layers "B.Cu" "B.Mask" "B.Paste")
			(net "Net_1387")
		)
		(pad "29" smd rect
			(at 2.249932 -5.275072 270)
			(size 0.3048 1.5494)
			(layers "B.Cu" "B.Mask" "B.Paste")
			(net "P2E_CPU_NGFF_C_RX_DN13")
		)
		(pad "30" smd rect
			(at 1.999996 2.275078 270)
			(size 0.3048 1.5494)
			(layers "B.Cu" "B.Mask" "B.Paste")
			(net "Net_1386")
		)
		(pad "31" smd rect
			(at 1.75006 -5.275072 270)
			(size 0.3048 1.5494)
			(layers "B.Cu" "B.Mask" "B.Paste")
			(net "P2E_CPU_NGFF_C_RX_DP13")
		)
		(pad "32" smd rect
			(at 1.500124 2.275078 270)
			(size 0.3048 1.5494)
			(layers "B.Cu" "B.Mask" "B.Paste")
			(net "Net_1385")
		)
		(pad "33" smd rect
			(at 1.249934 -5.275072 270)
			(size 0.3048 1.5494)
			(layers "B.Cu" "B.Mask" "B.Paste")
			(net "GND")
		)
		(pad "34" smd rect
			(at 0.999998 2.275078 270)
			(size 0.3048 1.5494)
			(layers "B.Cu" "B.Mask" "B.Paste")
			(net "Net_1384")
		)
		(pad "35" smd rect
			(at 0.750062 -5.275072 270)
			(size 0.3048 1.5494)
			(layers "B.Cu" "B.Mask" "B.Paste")
			(net "P2E_CPU_NGFF_TX_DN13")
		)
		(pad "36" smd rect
			(at 0.500126 2.275078 270)
			(size 0.3048 1.5494)
			(layers "B.Cu" "B.Mask" "B.Paste")
			(net "Net_1383")
		)
		(pad "37" smd rect
			(at 0.249936 -5.275072 270)
			(size 0.3048 1.5494)
			(layers "B.Cu" "B.Mask" "B.Paste")
			(net "P2E_CPU_NGFF_TX_DP13")
		)
		(pad "38" smd rect
			(at 0 2.275078 270)
			(size 0.3048 1.5494)
			(layers "B.Cu" "B.Mask" "B.Paste")
			(net "Net_1382")
		)
		(pad "39" smd rect
			(at -0.249936 -5.275072 270)
			(size 0.3048 1.5494)
			(layers "B.Cu" "B.Mask" "B.Paste")
			(net "GND")
		)
		(pad "40" smd rect
			(at -0.500126 2.275078 270)
			(size 0.3048 1.5494)
			(layers "B.Cu" "B.Mask" "B.Paste")
			(net "Net_1381")
		)
		(pad "41" smd rect
			(at -0.750062 -5.275072 270)
			(size 0.3048 1.5494)
			(layers "B.Cu" "B.Mask" "B.Paste")
			(net "P2E_CPU_NGFF_C_RX_DN12")
		)
		(pad "42" smd rect
			(at -0.999998 2.275078 270)
			(size 0.3048 1.5494)
			(layers "B.Cu" "B.Mask" "B.Paste")
			(net "Net_1380")
		)
		(pad "43" smd rect
			(at -1.249934 -5.275072 270)
			(size 0.3048 1.5494)
			(layers "B.Cu" "B.Mask" "B.Paste")
			(net "P2E_CPU_NGFF_C_RX_DP12")
		)
		(pad "44" smd rect
			(at -1.500124 2.275078 270)
			(size 0.3048 1.5494)
			(layers "B.Cu" "B.Mask" "B.Paste")
			(net "Net_1379")
		)
		(pad "45" smd rect
			(at -1.75006 -5.275072 270)
			(size 0.3048 1.5494)
			(layers "B.Cu" "B.Mask" "B.Paste")
			(net "GND")
		)
		(pad "46" smd rect
			(at -1.999996 2.275078 270)
			(size 0.3048 1.5494)
			(layers "B.Cu" "B.Mask" "B.Paste")
			(net "Net_1378")
		)
		(pad "47" smd rect
			(at -2.249932 -5.275072 270)
			(size 0.3048 1.5494)
			(layers "B.Cu" "B.Mask" "B.Paste")
			(net "P2E_CPU_NGFF_TX_DN12")
		)
		(pad "48" smd rect
			(at -2.500122 2.275078 270)
			(size 0.3048 1.5494)
			(layers "B.Cu" "B.Mask" "B.Paste")
			(net "Net_1377")
		)
		(pad "49" smd rect
			(at -2.750058 -5.275072 270)
			(size 0.3048 1.5494)
			(layers "B.Cu" "B.Mask" "B.Paste")
			(net "P2E_CPU_NGFF_TX_DP12")
		)
		(pad "50" smd rect
			(at -2.999994 2.275078 270)
			(size 0.3048 1.5494)
			(layers "B.Cu" "B.Mask" "B.Paste")
			(net "RST_PCIE_PCH_DEV_R#")
		)
		(pad "51" smd rect
			(at -3.24993 -5.275072 270)
			(size 0.3048 1.5494)
			(layers "B.Cu" "B.Mask" "B.Paste")
			(net "GND")
		)
		(pad "52" smd rect
			(at -3.50012 2.275078 270)
			(size 0.3048 1.5494)
			(layers "B.Cu" "B.Mask" "B.Paste")
			(net "Net_1376")
		)
		(pad "53" smd rect
			(at -3.750056 -5.275072 270)
			(size 0.3048 1.5494)
			(layers "B.Cu" "B.Mask" "B.Paste")
			(net "CLK_100M_CLKBUFF_NGFF_DN")
		)
		(pad "54" smd rect
			(at -3.999992 2.275078 270)
			(size 0.3048 1.5494)
			(layers "B.Cu" "B.Mask" "B.Paste")
			(net "Net_1374")
		)
		(pad "55" smd rect
			(at -4.249928 -5.275072 270)
			(size 0.3048 1.5494)
			(layers "B.Cu" "B.Mask" "B.Paste")
			(net "CLK_100M_CLKBUFF_NGFF_DP")
		)
		(pad "56" smd rect
			(at -4.500118 2.275078 270)
			(size 0.3048 1.5494)
			(layers "B.Cu" "B.Mask" "B.Paste")
			(net "Net_1373")
		)
		(pad "57" smd rect
			(at -4.750054 -5.275072 270)
			(size 0.3048 1.5494)
			(layers "B.Cu" "B.Mask" "B.Paste")
			(net "GND")
		)
		(pad "58" smd rect
			(at -4.99999 2.275078 270)
			(size 0.3048 1.5494)
			(layers "B.Cu" "B.Mask" "B.Paste")
			(net "Net_1372")
		)
		(pad "67" smd rect
			(at -7.249922 -5.275072 270)
			(size 0.3048 1.5494)
			(layers "B.Cu" "B.Mask" "B.Paste")
			(net "Net_1371")
		)
		(pad "68" smd rect
			(at -7.500112 2.275078 270)
			(size 0.3048 1.5494)
			(layers "B.Cu" "B.Mask" "B.Paste")
			(net "PMU_SUS_CLK")
		)
		(pad "69" smd rect
			(at -7.750048 -5.275072 270)
			(size 0.3048 1.5494)
			(layers "B.Cu" "B.Mask" "B.Paste")
			(net "PEDET_SEL")
		)
		(pad "70" smd rect
			(at -7.999984 2.275078 270)
			(size 0.3048 1.5494)
			(layers "B.Cu" "B.Mask" "B.Paste")
			(net "P3V3")
		)
		(pad "71" smd rect
			(at -8.24992 -5.275072 270)
			(size 0.3048 1.5494)
			(layers "B.Cu" "B.Mask" "B.Paste")
			(net "GND")
		)
		(pad "72" smd rect
			(at -8.50011 2.275078 270)
			(size 0.3048 1.5494)
			(layers "B.Cu" "B.Mask" "B.Paste")
			(net "P3V3")
		)
		(pad "73" smd rect
			(at -8.750046 -5.275072 270)
			(size 0.3048 1.5494)
			(layers "B.Cu" "B.Mask" "B.Paste")
			(net "GND")
		)
		(pad "74" smd rect
			(at -8.999982 2.275078 270)
			(size 0.3048 1.5494)
			(layers "B.Cu" "B.Mask" "B.Paste")
			(net "P3V3")
		)
		(pad "75" smd rect
			(at -9.249918 -5.275072 270)
			(size 0.3048 1.5494)
			(layers "B.Cu" "B.Mask" "B.Paste")
			(net "GND")
		)
		(pad "76" smd rect
			(at 10.349992 -4.500118 270)
			(size 1.1938 2.7432)
			(layers "B.Cu" "B.Mask" "B.Paste")
			(net "GND")
		)
		(pad "77" smd rect
			(at -10.349992 -4.500118 270)
			(size 1.1938 2.7432)
			(layers "B.Cu" "B.Mask" "B.Paste")
			(net "GND")
		)
		(zone
			(layers "F.Cu" "B.Cu" "In1.Cu" "In2.Cu" "In3.Cu" "In4.Cu" "In5.Cu" "In6.Cu"
				"In7.Cu" "In8.Cu" "In9.Cu" "In10.Cu"
			)
			(hatch none 0.5)
			(connect_pads
				(clearance 0)
			)
			(min_thickness 0.25)
			(keepout
				(tracks not_allowed)
				(vias allowed)
				(pads allowed)
				(copperpour not_allowed)
				(footprints allowed)
			)
			(placement
				(enabled no)
				(sheetname "")
			)
			(fill
				(thermal_gap 0.5)
				(thermal_bridge_width 0.5)
				(island_removal_mode 0)
			)
			(polygon
				(pts
					(arc
						(start 11.713718 -68.699888)
						(mid 9.986518 -68.699888)
						(end 11.713718 -68.699888)
					)
				)
			)
		)
		(zone
			(layers "F.Cu" "B.Cu" "In1.Cu" "In2.Cu" "In3.Cu" "In4.Cu" "In5.Cu" "In6.Cu"
				"In7.Cu" "In8.Cu" "In9.Cu" "In10.Cu"
			)
			(hatch none 0.5)
			(connect_pads
				(clearance 0)
			)
			(min_thickness 0.25)
			(keepout
				(tracks not_allowed)
				(vias allowed)
				(pads allowed)
				(copperpour not_allowed)
				(footprints allowed)
			)
			(placement
				(enabled no)
				(sheetname "")
			)
			(fill
				(thermal_gap 0.5)
				(thermal_bridge_width 0.5)
				(island_removal_mode 0)
			)
			(polygon
				(pts
					(arc
						(start 11.980418 -48.699928)
						(mid 9.719818 -48.699928)
						(end 11.980418 -48.699928)
					)
				)
			)
		)
		(zone
			(layer "B.Cu")
			(hatch none 0.5)
			(connect_pads
				(clearance 0)
			)
			(min_thickness 0.25)
			(keepout
				(tracks allowed)
				(vias not_allowed)
				(pads allowed)
				(copperpour not_allowed)
				(footprints allowed)
			)
			(placement
				(enabled no)
				(sheetname "")
			)
			(fill
				(thermal_gap 0.5)
				(thermal_bridge_width 0.5)
				(island_removal_mode 0)
			)
			(polygon
				(pts
					(xy 6.349746 -68.102226) (xy 6.857746 -68.102226) (xy 6.857746 -53.797454) (xy 6.349746 -53.797454)
				)
			)
		)
		(zone
			(layer "B.Cu")
			(hatch none 0.5)
			(connect_pads
				(clearance 0)
			)
			(min_thickness 0.25)
			(keepout
				(tracks allowed)
				(vias not_allowed)
				(pads allowed)
				(copperpour not_allowed)
				(footprints allowed)
			)
			(placement
				(enabled no)
				(sheetname "")
			)
			(fill
				(thermal_gap 0.5)
				(thermal_bridge_width 0.5)
				(island_removal_mode 0)
			)
			(polygon
				(pts
					(xy 6.349746 -51.602386) (xy 6.857746 -51.602386) (xy 6.857746 -49.29759) (xy 6.349746 -49.29759)
				)
			)
		)
		(zone
			(layer "B.Cu")
			(hatch none 0.5)
			(connect_pads
				(clearance 0)
			)
			(min_thickness 0.25)
			(keepout
				(tracks allowed)
				(vias not_allowed)
				(pads allowed)
				(copperpour not_allowed)
				(footprints allowed)
			)
			(placement
				(enabled no)
				(sheetname "")
			)
			(fill
				(thermal_gap 0.5)
				(thermal_bridge_width 0.5)
				(island_removal_mode 0)
			)
			(polygon
				(pts
					(xy 11.842496 -67.85229) (xy 12.350496 -67.85229) (xy 12.350496 -53.547518) (xy 11.842496 -53.547518)
				)
			)
		)
		(zone
			(layer "B.Cu")
			(hatch none 0.5)
			(connect_pads
				(clearance 0)
			)
			(min_thickness 0.25)
			(keepout
				(tracks allowed)
				(vias not_allowed)
				(pads allowed)
				(copperpour not_allowed)
				(footprints allowed)
			)
			(placement
				(enabled no)
				(sheetname "")
			)
			(fill
				(thermal_gap 0.5)
				(thermal_bridge_width 0.5)
				(island_removal_mode 0)
			)
			(polygon
				(pts
					(xy 11.842496 -51.352196) (xy 12.350496 -51.352196) (xy 12.350496 -49.547526) (xy 11.842496 -49.547526)
				)
			)
		)
	)
	(footprint ""
		(layer "B.Cu")
		(at 43.1038 -28.7528 90)
		(property "Reference" "R431"
			(at 0 0 90)
			(layer "B.SilkS")
			(hide yes)
			(effects
				(font
					(size 1.27 1.27)
				)
				(justify mirror)
			)
		)
		(property "Value" "43D2R2F-GP"
			(at -1.7907 -1.1176 90)
			(unlocked yes)
			(layer "B.Fab")
			(hide yes)
			(effects
				(font
					(size 1.016 1.016)
					(thickness 0.1524)
				)
				(justify mirror)
			)
		)
		(property "Device Type" "R402H16"
			(at -1.7907 -2.6416 90)
			(unlocked yes)
			(layer "B.Fab")
			(hide yes)
			(effects
				(font
					(size 1.016 1.016)
					(thickness 0.1524)
				)
				(justify mirror)
			)
		)
		(duplicate_pad_numbers_are_jumpers no)
		(fp_rect
			(start 0.381 0.8382)
			(end -0.381 -0.8382)
			(stroke
				(width 0)
				(type default)
			)
			(fill no)
			(layer "B.CrtYd")
		)
		(fp_rect
			(start 0.381 0.8382)
			(end -0.381 -0.8382)
			(stroke
				(width 0)
				(type default)
			)
			(fill no)
			(layer "B.Fab")
		)
		(pad "1" smd custom
			(at 0 -0.4318 270)
			(size 0.127 0.127)
			(layers "B.Cu" "B.Mask" "B.Paste")
			(net "CLK_100M_CLKBUFF_PCIE_DP")
			(options
				(clearance outline)
				(anchor circle)
			)
			(primitives
				(gr_poly
					(pts
						(arc
							(start -0.2032 0.2794)
							(mid -0.239121 0.264521)
							(end -0.254 0.2286)
						)
						(arc
							(start -0.254 -0.2286)
							(mid -0.239121 -0.264521)
							(end -0.2032 -0.2794)
						)
						(arc
							(start 0.2032 -0.2794)
							(mid 0.239121 -0.264521)
							(end 0.254 -0.2286)
						)
						(arc
							(start 0.254 0.2286)
							(mid 0.239121 0.264521)
							(end 0.2032 0.2794)
						)
					)
					(width 0)
					(fill yes)
				)
			)
		)
		(pad "2" smd custom
			(at 0 0.4318 270)
			(size 0.127 0.127)
			(layers "B.Cu" "B.Mask" "B.Paste")
			(net "GND")
			(options
				(clearance outline)
				(anchor circle)
			)
			(primitives
				(gr_poly
					(pts
						(arc
							(start -0.2032 0.2794)
							(mid -0.239121 0.264521)
							(end -0.254 0.2286)
						)
						(arc
							(start -0.254 -0.2286)
							(mid -0.239121 -0.264521)
							(end -0.2032 -0.2794)
						)
						(arc
							(start 0.2032 -0.2794)
							(mid 0.239121 -0.264521)
							(end 0.254 -0.2286)
						)
						(arc
							(start 0.254 0.2286)
							(mid 0.239121 0.264521)
							(end 0.2032 0.2794)
						)
					)
					(width 0)
					(fill yes)
				)
			)
		)
	)
	(footprint ""
		(layer "B.Cu")
		(at 144.4244 -47.498 90)
		(property "Reference" "R492"
			(at 0 0 90)
			(layer "B.SilkS")
			(hide yes)
			(effects
				(font
					(size 1.27 1.27)
				)
				(justify mirror)
			)
		)
		(property "Value" "1KR2F-3-GP"
			(at -1.7907 -1.1176 90)
			(unlocked yes)
			(layer "B.Fab")
			(hide yes)
			(effects
				(font
					(size 1.016 1.016)
					(thickness 0.1524)
				)
				(justify mirror)
			)
		)
		(property "Device Type" "R402H16"
			(at -1.7907 -2.6416 90)
			(unlocked yes)
			(layer "B.Fab")
			(hide yes)
			(effects
				(font
					(size 1.016 1.016)
					(thickness 0.1524)
				)
				(justify mirror)
			)
		)
		(duplicate_pad_numbers_are_jumpers no)
		(fp_rect
			(start 0.381 0.8382)
			(end -0.381 -0.8382)
			(stroke
				(width 0)
				(type default)
			)
			(fill no)
			(layer "B.CrtYd")
		)
		(fp_rect
			(start 0.381 0.8382)
			(end -0.381 -0.8382)
			(stroke
				(width 0)
				(type default)
			)
			(fill no)
			(layer "B.Fab")
		)
		(pad "1" smd custom
			(at 0 -0.4318 270)
			(size 0.127 0.127)
			(layers "B.Cu" "B.Mask" "B.Paste")
			(net "P3V3_STBY")
			(options
				(clearance outline)
				(anchor circle)
			)
			(primitives
				(gr_poly
					(pts
						(arc
							(start -0.2032 0.2794)
							(mid -0.239121 0.264521)
							(end -0.254 0.2286)
						)
						(arc
							(start -0.254 -0.2286)
							(mid -0.239121 -0.264521)
							(end -0.2032 -0.2794)
						)
						(arc
							(start 0.2032 -0.2794)
							(mid 0.239121 -0.264521)
							(end 0.254 -0.2286)
						)
						(arc
							(start 0.254 0.2286)
							(mid 0.239121 0.264521)
							(end 0.2032 0.2794)
						)
					)
					(width 0)
					(fill yes)
				)
			)
		)
		(pad "2" smd custom
			(at 0 0.4318 270)
			(size 0.127 0.127)
			(layers "B.Cu" "B.Mask" "B.Paste")
			(net "JTAG_PLD_TCK")
			(options
				(clearance outline)
				(anchor circle)
			)
			(primitives
				(gr_poly
					(pts
						(arc
							(start -0.2032 0.2794)
							(mid -0.239121 0.264521)
							(end -0.254 0.2286)
						)
						(arc
							(start -0.254 -0.2286)
							(mid -0.239121 -0.264521)
							(end -0.2032 -0.2794)
						)
						(arc
							(start 0.2032 -0.2794)
							(mid 0.239121 -0.264521)
							(end 0.254 -0.2286)
						)
						(arc
							(start 0.254 0.2286)
							(mid 0.239121 0.264521)
							(end 0.2032 0.2794)
						)
					)
					(width 0)
					(fill yes)
				)
			)
		)
	)
	(footprint ""
		(layer "B.Cu")
		(at 22.4028 -61.087 180)
		(property "Reference" "PR27"
			(at 0 0 0)
			(layer "B.SilkS")
			(hide yes)
			(effects
				(font
					(size 1.27 1.27)
				)
				(justify mirror)
			)
		)
		(property "Value" "2MR2F-GP"
			(at -1.7907 -1.1176 180)
			(unlocked yes)
			(layer "B.Fab")
			(hide yes)
			(effects
				(font
					(size 1.016 1.016)
					(thickness 0.1524)
				)
				(justify mirror)
			)
		)
		(property "Device Type" "R402H16"
			(at -1.7907 -2.6416 180)
			(unlocked yes)
			(layer "B.Fab")
			(hide yes)
			(effects
				(font
					(size 1.016 1.016)
					(thickness 0.1524)
				)
				(justify mirror)
			)
		)
		(duplicate_pad_numbers_are_jumpers no)
		(fp_rect
			(start 0.381 0.8382)
			(end -0.381 -0.8382)
			(stroke
				(width 0)
				(type default)
			)
			(fill no)
			(layer "B.CrtYd")
		)
		(fp_rect
			(start 0.381 0.8382)
			(end -0.381 -0.8382)
			(stroke
				(width 0)
				(type default)
			)
			(fill no)
			(layer "B.Fab")
		)
		(pad "1" smd custom
			(at 0 -0.4318)
			(size 0.127 0.127)
			(layers "B.Cu" "B.Mask" "B.Paste")
			(net "GND")
			(options
				(clearance outline)
				(anchor circle)
			)
			(primitives
				(gr_poly
					(pts
						(arc
							(start -0.2032 0.2794)
							(mid -0.239121 0.264521)
							(end -0.254 0.2286)
						)
						(arc
							(start -0.254 -0.2286)
							(mid -0.239121 -0.264521)
							(end -0.2032 -0.2794)
						)
						(arc
							(start 0.2032 -0.2794)
							(mid 0.239121 -0.264521)
							(end 0.254 -0.2286)
						)
						(arc
							(start 0.254 0.2286)
							(mid 0.239121 0.264521)
							(end 0.2032 0.2794)
						)
					)
					(width 0)
					(fill yes)
				)
			)
		)
		(pad "2" smd custom
			(at 0 0.4318)
			(size 0.127 0.127)
			(layers "B.Cu" "B.Mask" "B.Paste")
			(net "VR_PVNN_ISUMP")
			(options
				(clearance outline)
				(anchor circle)
			)
			(primitives
				(gr_poly
					(pts
						(arc
							(start -0.2032 0.2794)
							(mid -0.239121 0.264521)
							(end -0.254 0.2286)
						)
						(arc
							(start -0.254 -0.2286)
							(mid -0.239121 -0.264521)
							(end -0.2032 -0.2794)
						)
						(arc
							(start 0.2032 -0.2794)
							(mid 0.239121 -0.264521)
							(end 0.254 -0.2286)
						)
						(arc
							(start 0.254 0.2286)
							(mid 0.239121 0.264521)
							(end 0.2032 0.2794)
						)
					)
					(width 0)
					(fill yes)
				)
			)
		)
	)
	(footprint ""
		(layer "B.Cu")
		(at 88.9 -33.274)
		(property "Reference" "R485"
			(at 0 0 0)
			(layer "B.SilkS")
			(hide yes)
			(effects
				(font
					(size 1.27 1.27)
				)
				(justify mirror)
			)
		)
		(property "Value" "4K7R2F-GP"
			(at -1.7907 -1.1176 0)
			(unlocked yes)
			(layer "B.Fab")
			(hide yes)
			(effects
				(font
					(size 1.016 1.016)
					(thickness 0.1524)
				)
				(justify mirror)
			)
		)
		(property "Device Type" "R402H16"
			(at -1.7907 -2.6416 0)
			(unlocked yes)
			(layer "B.Fab")
			(hide yes)
			(effects
				(font
					(size 1.016 1.016)
					(thickness 0.1524)
				)
				(justify mirror)
			)
		)
		(duplicate_pad_numbers_are_jumpers no)
		(fp_rect
			(start 0.381 0.8382)
			(end -0.381 -0.8382)
			(stroke
				(width 0)
				(type default)
			)
			(fill no)
			(layer "B.CrtYd")
		)
		(fp_rect
			(start 0.381 0.8382)
			(end -0.381 -0.8382)
			(stroke
				(width 0)
				(type default)
			)
			(fill no)
			(layer "B.Fab")
		)
		(pad "1" smd custom
			(at 0 -0.4318 180)
			(size 0.127 0.127)
			(layers "B.Cu" "B.Mask" "B.Paste")
			(net "P3V3_CPU")
			(options
				(clearance outline)
				(anchor circle)
			)
			(primitives
				(gr_poly
					(pts
						(arc
							(start -0.2032 0.2794)
							(mid -0.239121 0.264521)
							(end -0.254 0.2286)
						)
						(arc
							(start -0.254 -0.2286)
							(mid -0.239121 -0.264521)
							(end -0.2032 -0.2794)
						)
						(arc
							(start 0.2032 -0.2794)
							(mid 0.239121 -0.264521)
							(end 0.254 -0.2286)
						)
						(arc
							(start 0.254 0.2286)
							(mid 0.239121 0.264521)
							(end 0.2032 0.2794)
						)
					)
					(width 0)
					(fill yes)
				)
			)
		)
		(pad "2" smd custom
			(at 0 0.4318 180)
			(size 0.127 0.127)
			(layers "B.Cu" "B.Mask" "B.Paste")
			(net "BD_REV_0")
			(options
				(clearance outline)
				(anchor circle)
			)
			(primitives
				(gr_poly
					(pts
						(arc
							(start -0.2032 0.2794)
							(mid -0.239121 0.264521)
							(end -0.254 0.2286)
						)
						(arc
							(start -0.254 -0.2286)
							(mid -0.239121 -0.264521)
							(end -0.2032 -0.2794)
						)
						(arc
							(start 0.2032 -0.2794)
							(mid 0.239121 -0.264521)
							(end 0.254 -0.2286)
						)
						(arc
							(start 0.254 0.2286)
							(mid 0.239121 0.264521)
							(end 0.2032 0.2794)
						)
					)
					(width 0)
					(fill yes)
				)
			)
		)
	)
	(footprint ""
		(layer "B.Cu")
		(at 185.039 -13.716 90)
		(property "Reference" "PC206"
			(at 0 0 90)
			(layer "B.SilkS")
			(hide yes)
			(effects
				(font
					(size 1.27 1.27)
				)
				(justify mirror)
			)
		)
		(property "Value" "SC10U6D3V3MX-GP"
			(at 0 -2.8194 90)
			(unlocked yes)
			(layer "B.Fab")
			(hide yes)
			(effects
				(font
					(size 1.016 1.016)
					(thickness 0.1524)
				)
				(justify mirror)
			)
		)
		(property "Device Type" "C603H38"
			(at 0 -4.3434 90)
			(unlocked yes)
			(layer "B.Fab")
			(hide yes)
			(effects
				(font
					(size 1.016 1.016)
					(thickness 0.1524)
				)
				(justify mirror)
			)
		)
		(duplicate_pad_numbers_are_jumpers no)
		(fp_line
			(start 0.4064 0)
			(end -0.4064 0)
			(stroke
				(width 0.2286)
				(type default)
			)
			(layer "B.SilkS")
		)
		(fp_rect
			(start 0.635 1.1811)
			(end -0.635 -1.1811)
			(stroke
				(width 0)
				(type default)
			)
			(fill no)
			(layer "B.CrtYd")
		)
		(fp_rect
			(start 0.635 1.1811)
			(end -0.635 -1.1811)
			(stroke
				(width 0)
				(type default)
			)
			(fill no)
			(layer "B.Fab")
		)
		(pad "1" smd custom
			(at 0 -0.6604 270)
			(size 0.19685 0.19685)
			(layers "B.Cu" "B.Mask" "B.Paste")
			(net "GND")
			(options
				(clearance outline)
				(anchor circle)
			)
			(primitives
				(gr_poly
					(pts
						(arc
							(start 0.508 0.2921)
							(mid 0.478242 0.363942)
							(end 0.4064 0.3937)
						)
						(arc
							(start -0.4064 0.3937)
							(mid -0.478242 0.363942)
							(end -0.508 0.2921)
						)
						(arc
							(start -0.508 -0.2921)
							(mid -0.478242 -0.363942)
							(end -0.4064 -0.3937)
						)
						(arc
							(start 0.4064 -0.3937)
							(mid 0.478242 -0.363942)
							(end 0.508 -0.2921)
						)
					)
					(width 0)
					(fill yes)
				)
			)
		)
		(pad "2" smd custom
			(at 0 0.6604 270)
			(size 0.19685 0.19685)
			(layers "B.Cu" "B.Mask" "B.Paste")
			(net "PV_VTT_DDR_B")
			(options
				(clearance outline)
				(anchor circle)
			)
			(primitives
				(gr_poly
					(pts
						(arc
							(start 0.508 0.2921)
							(mid 0.478242 0.363942)
							(end 0.4064 0.3937)
						)
						(arc
							(start -0.4064 0.3937)
							(mid -0.478242 0.363942)
							(end -0.508 0.2921)
						)
						(arc
							(start -0.508 -0.2921)
							(mid -0.478242 -0.363942)
							(end -0.4064 -0.3937)
						)
						(arc
							(start 0.4064 -0.3937)
							(mid 0.478242 -0.363942)
							(end 0.508 -0.2921)
						)
					)
					(width 0)
					(fill yes)
				)
			)
		)
	)
	(footprint ""
		(layer "B.Cu")
		(at 104.013 -51.451002 180)
		(property "Reference" "C123"
			(at 0 0 0)
			(layer "B.SilkS")
			(hide yes)
			(effects
				(font
					(size 1.27 1.27)
				)
				(justify mirror)
			)
		)
		(property "Value" "SC1U10V2KX-1GP"
			(at -1.1811 -2.7051 180)
			(unlocked yes)
			(layer "B.Fab")
			(hide yes)
			(effects
				(font
					(size 1.016 1.016)
					(thickness 0.1524)
				)
				(justify mirror)
			)
		)
		(property "Device Type" "C402H22"
			(at -1.1811 -4.2291 180)
			(unlocked yes)
			(layer "B.Fab")
			(hide yes)
			(effects
				(font
					(size 1.016 1.016)
					(thickness 0.1524)
				)
				(justify mirror)
			)
		)
		(duplicate_pad_numbers_are_jumpers no)
		(fp_rect
			(start 0.381 0.7366)
			(end -0.381 -0.7366)
			(stroke
				(width 0)
				(type default)
			)
			(fill no)
			(layer "B.CrtYd")
		)
		(fp_rect
			(start 0.381 0.7366)
			(end -0.381 -0.7366)
			(stroke
				(width 0)
				(type default)
			)
			(fill no)
			(layer "B.Fab")
		)
		(pad "1" smd custom
			(at 0 -0.4572)
			(size 0.1143 0.1143)
			(layers "B.Cu" "B.Mask" "B.Paste")
			(net "PV_VDDR")
			(options
				(clearance outline)
				(anchor circle)
			)
			(primitives
				(gr_poly
					(pts
						(arc
							(start -0.254 0.1778)
							(mid -0.239121 0.213721)
							(end -0.2032 0.2286)
						)
						(arc
							(start 0.2032 0.2286)
							(mid 0.239121 0.213721)
							(end 0.254 0.1778)
						)
						(arc
							(start 0.254 -0.1778)
							(mid 0.239121 -0.213721)
							(end 0.2032 -0.2286)
						)
						(arc
							(start -0.2032 -0.2286)
							(mid -0.239121 -0.213721)
							(end -0.254 -0.1778)
						)
					)
					(width 0)
					(fill yes)
				)
			)
		)
		(pad "2" smd custom
			(at 0 0.4572)
			(size 0.1143 0.1143)
			(layers "B.Cu" "B.Mask" "B.Paste")
			(net "GND")
			(options
				(clearance outline)
				(anchor circle)
			)
			(primitives
				(gr_poly
					(pts
						(arc
							(start -0.254 0.1778)
							(mid -0.239121 0.213721)
							(end -0.2032 0.2286)
						)
						(arc
							(start 0.2032 0.2286)
							(mid 0.239121 0.213721)
							(end 0.254 0.1778)
						)
						(arc
							(start 0.254 -0.1778)
							(mid 0.239121 -0.213721)
							(end 0.2032 -0.2286)
						)
						(arc
							(start -0.2032 -0.2286)
							(mid -0.239121 -0.213721)
							(end -0.254 -0.1778)
						)
					)
					(width 0)
					(fill yes)
				)
			)
		)
	)
	(footprint ""
		(layer "B.Cu")
		(at 132.715 -56.388 180)
		(property "Reference" "PC143"
			(at 0 0 0)
			(layer "B.SilkS")
			(hide yes)
			(effects
				(font
					(size 1.27 1.27)
				)
				(justify mirror)
			)
		)
		(property "Value" "SC10U6D3V3MX-GP"
			(at 0 -2.8194 180)
			(unlocked yes)
			(layer "B.Fab")
			(hide yes)
			(effects
				(font
					(size 1.016 1.016)
					(thickness 0.1524)
				)
				(justify mirror)
			)
		)
		(property "Device Type" "C603H38"
			(at 0 -4.3434 180)
			(unlocked yes)
			(layer "B.Fab")
			(hide yes)
			(effects
				(font
					(size 1.016 1.016)
					(thickness 0.1524)
				)
				(justify mirror)
			)
		)
		(duplicate_pad_numbers_are_jumpers no)
		(fp_line
			(start 0.4064 0)
			(end -0.4064 0)
			(stroke
				(width 0.2286)
				(type default)
			)
			(layer "B.SilkS")
		)
		(fp_rect
			(start 0.635 1.1811)
			(end -0.635 -1.1811)
			(stroke
				(width 0)
				(type default)
			)
			(fill no)
			(layer "B.CrtYd")
		)
		(fp_rect
			(start 0.635 1.1811)
			(end -0.635 -1.1811)
			(stroke
				(width 0)
				(type default)
			)
			(fill no)
			(layer "B.Fab")
		)
		(pad "1" smd custom
			(at 0 -0.6604)
			(size 0.19685 0.19685)
			(layers "B.Cu" "B.Mask" "B.Paste")
			(net "GND")
			(options
				(clearance outline)
				(anchor circle)
			)
			(primitives
				(gr_poly
					(pts
						(arc
							(start 0.508 0.2921)
							(mid 0.478242 0.363942)
							(end 0.4064 0.3937)
						)
						(arc
							(start -0.4064 0.3937)
							(mid -0.478242 0.363942)
							(end -0.508 0.2921)
						)
						(arc
							(start -0.508 -0.2921)
							(mid -0.478242 -0.363942)
							(end -0.4064 -0.3937)
						)
						(arc
							(start 0.4064 -0.3937)
							(mid 0.478242 -0.363942)
							(end 0.508 -0.2921)
						)
					)
					(width 0)
					(fill yes)
				)
			)
		)
		(pad "2" smd custom
			(at 0 0.6604)
			(size 0.19685 0.19685)
			(layers "B.Cu" "B.Mask" "B.Paste")
			(net "PV_VTT_DDR_A")
			(options
				(clearance outline)
				(anchor circle)
			)
			(primitives
				(gr_poly
					(pts
						(arc
							(start 0.508 0.2921)
							(mid 0.478242 0.363942)
							(end 0.4064 0.3937)
						)
						(arc
							(start -0.4064 0.3937)
							(mid -0.478242 0.363942)
							(end -0.508 0.2921)
						)
						(arc
							(start -0.508 -0.2921)
							(mid -0.478242 -0.363942)
							(end -0.4064 -0.3937)
						)
						(arc
							(start 0.4064 -0.3937)
							(mid 0.478242 -0.363942)
							(end 0.508 -0.2921)
						)
					)
					(width 0)
					(fill yes)
				)
			)
		)
	)
	(footprint ""
		(layer "B.Cu")
		(at 197.485 -31.115 -90)
		(property "Reference" "R149"
			(at 0 0 90)
			(layer "B.SilkS")
			(hide yes)
			(effects
				(font
					(size 1.27 1.27)
				)
				(justify mirror)
			)
		)
		(property "Value" "300R2F-GP"
			(at -1.7907 -1.1176 270)
			(unlocked yes)
			(layer "B.Fab")
			(hide yes)
			(effects
				(font
					(size 1.016 1.016)
					(thickness 0.1524)
				)
				(justify mirror)
			)
		)
		(property "Device Type" "R402H16"
			(at -1.7907 -2.6416 270)
			(unlocked yes)
			(layer "B.Fab")
			(hide yes)
			(effects
				(font
					(size 1.016 1.016)
					(thickness 0.1524)
				)
				(justify mirror)
			)
		)
		(duplicate_pad_numbers_are_jumpers no)
		(fp_rect
			(start 0.381 0.8382)
			(end -0.381 -0.8382)
			(stroke
				(width 0)
				(type default)
			)
			(fill no)
			(layer "B.CrtYd")
		)
		(fp_rect
			(start 0.381 0.8382)
			(end -0.381 -0.8382)
			(stroke
				(width 0)
				(type default)
			)
			(fill no)
			(layer "B.Fab")
		)
		(pad "1" smd custom
			(at 0 -0.4318 90)
			(size 0.127 0.127)
			(layers "B.Cu" "B.Mask" "B.Paste")
			(net "PORT80_R_BIT0")
			(options
				(clearance outline)
				(anchor circle)
			)
			(primitives
				(gr_poly
					(pts
						(arc
							(start -0.2032 0.2794)
							(mid -0.239121 0.264521)
							(end -0.254 0.2286)
						)
						(arc
							(start -0.254 -0.2286)
							(mid -0.239121 -0.264521)
							(end -0.2032 -0.2794)
						)
						(arc
							(start 0.2032 -0.2794)
							(mid 0.239121 -0.264521)
							(end 0.254 -0.2286)
						)
						(arc
							(start 0.254 0.2286)
							(mid 0.239121 0.264521)
							(end 0.2032 0.2794)
						)
					)
					(width 0)
					(fill yes)
				)
			)
		)
		(pad "2" smd custom
			(at 0 0.4318 90)
			(size 0.127 0.127)
			(layers "B.Cu" "B.Mask" "B.Paste")
			(net "P3V3_STBY")
			(options
				(clearance outline)
				(anchor circle)
			)
			(primitives
				(gr_poly
					(pts
						(arc
							(start -0.2032 0.2794)
							(mid -0.239121 0.264521)
							(end -0.254 0.2286)
						)
						(arc
							(start -0.254 -0.2286)
							(mid -0.239121 -0.264521)
							(end -0.2032 -0.2794)
						)
						(arc
							(start 0.2032 -0.2794)
							(mid 0.239121 -0.264521)
							(end 0.254 -0.2286)
						)
						(arc
							(start 0.254 0.2286)
							(mid 0.239121 0.264521)
							(end 0.2032 0.2794)
						)
					)
					(width 0)
					(fill yes)
				)
			)
		)
	)
	(footprint ""
		(layer "B.Cu")
		(at 102.372668 -42.957496 90)
		(property "Reference" "C166"
			(at 0 0 90)
			(layer "B.SilkS")
			(hide yes)
			(effects
				(font
					(size 1.27 1.27)
				)
				(justify mirror)
			)
		)
		(property "Value" "SC1U10V2KX-1GP"
			(at -1.1811 -2.7051 90)
			(unlocked yes)
			(layer "B.Fab")
			(hide yes)
			(effects
				(font
					(size 1.016 1.016)
					(thickness 0.1524)
				)
				(justify mirror)
			)
		)
		(property "Device Type" "C402H22"
			(at -1.1811 -4.2291 90)
			(unlocked yes)
			(layer "B.Fab")
			(hide yes)
			(effects
				(font
					(size 1.016 1.016)
					(thickness 0.1524)
				)
				(justify mirror)
			)
		)
		(duplicate_pad_numbers_are_jumpers no)
		(fp_rect
			(start 0.381 0.7366)
			(end -0.381 -0.7366)
			(stroke
				(width 0)
				(type default)
			)
			(fill no)
			(layer "B.CrtYd")
		)
		(fp_rect
			(start 0.381 0.7366)
			(end -0.381 -0.7366)
			(stroke
				(width 0)
				(type default)
			)
			(fill no)
			(layer "B.Fab")
		)
		(pad "1" smd custom
			(at 0 -0.4572 270)
			(size 0.1143 0.1143)
			(layers "B.Cu" "B.Mask" "B.Paste")
			(net "P1V0")
			(options
				(clearance outline)
				(anchor circle)
			)
			(primitives
				(gr_poly
					(pts
						(arc
							(start -0.254 0.1778)
							(mid -0.239121 0.213721)
							(end -0.2032 0.2286)
						)
						(arc
							(start 0.2032 0.2286)
							(mid 0.239121 0.213721)
							(end 0.254 0.1778)
						)
						(arc
							(start 0.254 -0.1778)
							(mid 0.239121 -0.213721)
							(end 0.2032 -0.2286)
						)
						(arc
							(start -0.2032 -0.2286)
							(mid -0.239121 -0.213721)
							(end -0.254 -0.1778)
						)
					)
					(width 0)
					(fill yes)
				)
			)
		)
		(pad "2" smd custom
			(at 0 0.4572 270)
			(size 0.1143 0.1143)
			(layers "B.Cu" "B.Mask" "B.Paste")
			(net "GND")
			(options
				(clearance outline)
				(anchor circle)
			)
			(primitives
				(gr_poly
					(pts
						(arc
							(start -0.254 0.1778)
							(mid -0.239121 0.213721)
							(end -0.2032 0.2286)
						)
						(arc
							(start 0.2032 0.2286)
							(mid 0.239121 0.213721)
							(end 0.254 0.1778)
						)
						(arc
							(start 0.254 -0.1778)
							(mid 0.239121 -0.213721)
							(end 0.2032 -0.2286)
						)
						(arc
							(start -0.2032 -0.2286)
							(mid -0.239121 -0.213721)
							(end -0.254 -0.1778)
						)
					)
					(width 0)
					(fill yes)
				)
			)
		)
	)
	(footprint ""
		(layer "B.Cu")
		(at 98.282252 -37.229288 -90)
		(property "Reference" "TP32"
			(at 0 0 90)
			(layer "B.SilkS")
			(hide yes)
			(effects
				(font
					(size 1.27 1.27)
				)
				(justify mirror)
			)
		)
		(property "Value" "TPAD24"
			(at 0 -2.9972 270)
			(unlocked yes)
			(layer "B.Fab")
			(hide yes)
			(effects
				(font
					(size 1.016 1.016)
					(thickness 0.1524)
				)
				(justify mirror)
			)
		)
		(property "Device Type" "TPAD24"
			(at 0 -4.5212 270)
			(unlocked yes)
			(layer "B.Fab")
			(hide yes)
			(effects
				(font
					(size 1.016 1.016)
					(thickness 0.1524)
				)
				(justify mirror)
			)
		)
		(duplicate_pad_numbers_are_jumpers no)
		(fp_poly
			(pts
				(arc
					(start 0 -0.3048)
					(mid 0 0.3048)
					(end 0 -0.3048)
				)
			)
			(stroke
				(width 0)
				(type default)
			)
			(fill no)
			(layer "B.CrtYd")
		)
		(fp_poly
			(pts
				(arc
					(start 0 -0.6096)
					(mid 0 0.6096)
					(end 0 -0.6096)
				)
			)
			(stroke
				(width 0)
				(type default)
			)
			(fill no)
			(layer "B.Fab")
		)
		(pad "1" smd circle
			(at 0 0 90)
			(size 0.6096 0.6096)
			(layers "B.Cu" "B.Mask" "B.Paste")
			(net "TP_CPU_RSVD11")
		)
	)
	(footprint ""
		(layer "B.Cu")
		(at 45.858684 -48.897286 90)
		(property "Reference" "U16"
			(at 0 0 90)
			(layer "B.SilkS")
			(hide yes)
			(effects
				(font
					(size 1.27 1.27)
				)
				(justify mirror)
			)
		)
		(property "Value" "9VRS4420DKLFT-GP"
			(at 0.381 -13.7668 90)
			(unlocked yes)
			(layer "B.Fab")
			(hide yes)
			(effects
				(font
					(size 1.016 1.016)
					(thickness 0.1524)
				)
				(justify mirror)
			)
		)
		(property "Device Type" "QFN48J6-G4D3-UH40"
			(at 0.381 -15.2908 90)
			(unlocked yes)
			(layer "B.Fab")
			(hide yes)
			(effects
				(font
					(size 1.016 1.016)
					(thickness 0.1524)
				)
				(justify mirror)
			)
		)
		(duplicate_pad_numbers_are_jumpers no)
		(fp_poly
			(pts
				(xy -3.3909 -3.3909) (xy -2.4638 -3.3909) (xy -3.3909 -2.4638)
			)
			(stroke
				(width 0)
				(type default)
			)
			(fill yes)
			(layer "B.SilkS")
		)
		(fp_rect
			(start 3.3909 3.3909)
			(end -3.3909 -3.3909)
			(stroke
				(width 0)
				(type default)
			)
			(fill no)
			(layer "B.CrtYd")
		)
		(fp_rect
			(start 3.3909 3.3909)
			(end -3.3909 -3.3909)
			(stroke
				(width 0)
				(type default)
			)
			(fill no)
			(layer "B.Fab")
		)
		(pad "1" smd rect
			(at -2.199894 -2.809494 270)
			(size 0.2032 0.6858)
			(drill
				(offset 0 0.1016)
			)
			(layers "B.Cu" "B.Mask" "B.Paste")
			(net "XTAL_CLK_GEN_OUT_R")
		)
		(pad "2" smd rect
			(at -1.800098 -2.809494 270)
			(size 0.2032 0.889)
			(layers "B.Cu" "B.Mask" "B.Paste")
			(net "XTAL_CLK_GEN_IN")
		)
		(pad "3" smd rect
			(at -1.400048 -2.809494 270)
			(size 0.2032 0.889)
			(layers "B.Cu" "B.Mask" "B.Paste")
			(net "P3V3_CLK_XTAL")
		)
		(pad "4" smd rect
			(at -0.999998 -2.809494 270)
			(size 0.2032 0.889)
			(layers "B.Cu" "B.Mask" "B.Paste")
			(net "CLK_14M_CPU_R")
		)
		(pad "5" smd rect
			(at -0.599948 -2.809494 270)
			(size 0.2032 0.889)
			(layers "B.Cu" "B.Mask" "B.Paste")
			(net "SMB_CLKGEN_R_DATA")
		)
		(pad "6" smd rect
			(at -0.199898 -2.809494 270)
			(size 0.2032 0.889)
			(layers "B.Cu" "B.Mask" "B.Paste")
			(net "SMB_CLKGEN_R_CLK")
		)
		(pad "7" smd rect
			(at 0.199898 -2.809494 270)
			(size 0.2032 0.889)
			(layers "B.Cu" "B.Mask" "B.Paste")
			(net "P3V3_CLK_PCI")
		)
		(pad "8" smd rect
			(at 0.599948 -2.809494 270)
			(size 0.2032 0.889)
			(layers "B.Cu" "B.Mask" "B.Paste")
			(net "Net_71")
		)
		(pad "9" smd rect
			(at 0.999998 -2.809494 270)
			(size 0.2032 0.889)
			(layers "B.Cu" "B.Mask" "B.Paste")
			(net "Net_70")
		)
		(pad "10" smd rect
			(at 1.400048 -2.809494 270)
			(size 0.2032 0.889)
			(layers "B.Cu" "B.Mask" "B.Paste")
			(net "Net_69")
		)
		(pad "11" smd rect
			(at 1.800098 -2.809494 270)
			(size 0.2032 0.889)
			(layers "B.Cu" "B.Mask" "B.Paste")
			(net "GND")
		)
		(pad "12" smd rect
			(at 2.199894 -2.809494 270)
			(size 0.2032 0.6858)
			(drill
				(offset 0 0.1016)
			)
			(layers "B.Cu" "B.Mask" "B.Paste")
			(net "GND")
		)
		(pad "13" smd rect
			(at 2.809494 -2.199894 270)
			(size 0.6858 0.2032)
			(drill
				(offset -0.1016 0)
			)
			(layers "B.Cu" "B.Mask" "B.Paste")
			(net "CLKGEN_VSEL_PCI")
		)
		(pad "14" smd rect
			(at 2.809494 -1.800098 270)
			(size 0.889 0.2032)
			(layers "B.Cu" "B.Mask" "B.Paste")
			(net "P3V3_CLK_VDD25")
		)
		(pad "15" smd rect
			(at 2.809494 -1.400048 270)
			(size 0.889 0.2032)
			(layers "B.Cu" "B.Mask" "B.Paste")
			(net "P3V3_CLK_VDD25")
		)
		(pad "16" smd rect
			(at 2.809494 -0.999998 270)
			(size 0.889 0.2032)
			(layers "B.Cu" "B.Mask" "B.Paste")
			(net "Net_72")
		)
		(pad "17" smd rect
			(at 2.809494 -0.599948 270)
			(size 0.889 0.2032)
			(layers "B.Cu" "B.Mask" "B.Paste")
			(net "GND")
		)
		(pad "18" smd rect
			(at 2.809494 -0.199898 270)
			(size 0.889 0.2032)
			(layers "B.Cu" "B.Mask" "B.Paste")
			(net "CLKREQB")
		)
		(pad "19" smd rect
			(at 2.809494 0.199898 270)
			(size 0.889 0.2032)
			(layers "B.Cu" "B.Mask" "B.Paste")
			(net "CLK_96M_CPU_USB_DP")
		)
		(pad "20" smd rect
			(at 2.809494 0.599948 270)
			(size 0.889 0.2032)
			(layers "B.Cu" "B.Mask" "B.Paste")
			(net "CLK_96M_CPU_USB_DN")
		)
		(pad "21" smd rect
			(at 2.809494 0.999998 270)
			(size 0.889 0.2032)
			(layers "B.Cu" "B.Mask" "B.Paste")
			(net "P1V5_CLK_VDD_CORE")
		)
		(pad "22" smd rect
			(at 2.809494 1.400048 270)
			(size 0.889 0.2032)
			(layers "B.Cu" "B.Mask" "B.Paste")
			(net "CLK_100M_CPU_SATA3_DP")
		)
		(pad "23" smd rect
			(at 2.809494 1.800098 270)
			(size 0.889 0.2032)
			(layers "B.Cu" "B.Mask" "B.Paste")
			(net "CLK_100M_CPU_SATA3_DN")
		)
		(pad "24" smd rect
			(at 2.809494 2.199894 270)
			(size 0.6858 0.2032)
			(drill
				(offset -0.1016 0)
			)
			(layers "B.Cu" "B.Mask" "B.Paste")
			(net "GND")
		)
		(pad "25" smd rect
			(at 2.199894 2.809494 270)
			(size 0.2032 0.6858)
			(drill
				(offset 0 -0.1016)
			)
			(layers "B.Cu" "B.Mask" "B.Paste")
			(net "GND")
		)
		(pad "26" smd rect
			(at 1.800098 2.809494 270)
			(size 0.2032 0.889)
			(layers "B.Cu" "B.Mask" "B.Paste")
			(net "CLK_100M_CLKBUFF_DN")
		)
		(pad "27" smd rect
			(at 1.400048 2.809494 270)
			(size 0.2032 0.889)
			(layers "B.Cu" "B.Mask" "B.Paste")
			(net "CLK_100M_CLKBUFF_DP")
		)
		(pad "28" smd rect
			(at 0.999998 2.809494 270)
			(size 0.2032 0.889)
			(layers "B.Cu" "B.Mask" "B.Paste")
			(net "CLK_100M_CPU_MPLL1_DN")
		)
		(pad "29" smd rect
			(at 0.599948 2.809494 270)
			(size 0.2032 0.889)
			(layers "B.Cu" "B.Mask" "B.Paste")
			(net "CLK_100M_CPU_MPLL1_DP")
		)
		(pad "30" smd rect
			(at 0.199898 2.809494 270)
			(size 0.2032 0.889)
			(layers "B.Cu" "B.Mask" "B.Paste")
			(net "P1V5_CLK_SCR_LVIO")
		)
		(pad "31" smd rect
			(at -0.199898 2.809494 270)
			(size 0.2032 0.889)
			(layers "B.Cu" "B.Mask" "B.Paste")
			(net "CLKGEN_PCI_STOP#")
		)
		(pad "32" smd rect
			(at -0.599948 2.809494 270)
			(size 0.2032 0.889)
			(layers "B.Cu" "B.Mask" "B.Paste")
			(net "CLK_100M_CPU_MPLL0_DN")
		)
		(pad "33" smd rect
			(at -0.999998 2.809494 270)
			(size 0.2032 0.889)
			(layers "B.Cu" "B.Mask" "B.Paste")
			(net "CLK_100M_CPU_MPLL0_DP")
		)
		(pad "34" smd rect
			(at -1.400048 2.809494 270)
			(size 0.2032 0.889)
			(layers "B.Cu" "B.Mask" "B.Paste")
			(net "GND")
		)
		(pad "35" smd rect
			(at -1.800098 2.809494 270)
			(size 0.2032 0.889)
			(layers "B.Cu" "B.Mask" "B.Paste")
			(net "CLK_100M_CPU_HFHPLL_DN")
		)
		(pad "36" smd rect
			(at -2.199894 2.809494 270)
			(size 0.2032 0.6858)
			(drill
				(offset 0 -0.1016)
			)
			(layers "B.Cu" "B.Mask" "B.Paste")
			(net "CLK_100M_CPU_HFHPLL_DP")
		)
		(pad "37" smd rect
			(at -2.809494 2.199894 270)
			(size 0.6858 0.2032)
			(drill
				(offset 0.1016 0)
			)
			(layers "B.Cu" "B.Mask" "B.Paste")
			(net "CLKGEN_DIF_STOP#")
		)
		(pad "38" smd rect
			(at -2.809494 1.800098 270)
			(size 0.889 0.2032)
			(layers "B.Cu" "B.Mask" "B.Paste")
			(net "CLK_100M_XDP_R_DN")
		)
		(pad "39" smd rect
			(at -2.809494 1.400048 270)
			(size 0.889 0.2032)
			(layers "B.Cu" "B.Mask" "B.Paste")
			(net "CLK_100M_XDP_R_DP")
		)
		(pad "40" smd rect
			(at -2.809494 0.999998 270)
			(size 0.889 0.2032)
			(layers "B.Cu" "B.Mask" "B.Paste")
			(net "P1V5_CLK_VDD_CORE")
		)
		(pad "41" smd rect
			(at -2.809494 0.599948 270)
			(size 0.889 0.2032)
			(layers "B.Cu" "B.Mask" "B.Paste")
			(net "P1V5_CLK_VDDDIF")
		)
		(pad "42" smd rect
			(at -2.809494 0.199898 270)
			(size 0.889 0.2032)
			(layers "B.Cu" "B.Mask" "B.Paste")
			(net "CLK_100M_SATA2_DN")
		)
		(pad "43" smd rect
			(at -2.809494 -0.199898 270)
			(size 0.889 0.2032)
			(layers "B.Cu" "B.Mask" "B.Paste")
			(net "CLK_100M_SATA2_DP")
		)
		(pad "44" smd rect
			(at -2.809494 -0.599948 270)
			(size 0.889 0.2032)
			(layers "B.Cu" "B.Mask" "B.Paste")
			(net "GND")
		)
		(pad "45" smd rect
			(at -2.809494 -0.999998 270)
			(size 0.889 0.2032)
			(layers "B.Cu" "B.Mask" "B.Paste")
			(net "CLK_100M_CPU_GBE_DN")
		)
		(pad "46" smd rect
			(at -2.809494 -1.400048 270)
			(size 0.889 0.2032)
			(layers "B.Cu" "B.Mask" "B.Paste")
			(net "CLK_100M_CPU_GBE_DP")
		)
		(pad "47" smd rect
			(at -2.809494 -1.800098 270)
			(size 0.889 0.2032)
			(layers "B.Cu" "B.Mask" "B.Paste")
			(net "CLK_GEN_R_PG")
		)
		(pad "48" smd rect
			(at -2.809494 -2.199894 270)
			(size 0.6858 0.2032)
			(drill
				(offset 0.1016 0)
			)
			(layers "B.Cu" "B.Mask" "B.Paste")
			(net "GND")
		)
		(pad "49" smd rect
			(at 0 0 270)
			(size 4.2926 4.2926)
			(layers "B.Cu" "B.Mask" "B.Paste")
			(net "GND")
		)
	)
	(footprint ""
		(layer "B.Cu")
		(at 203.4794 -58.2676 90)
		(property "Reference" "PC166"
			(at 0 0 90)
			(layer "B.SilkS")
			(hide yes)
			(effects
				(font
					(size 1.27 1.27)
				)
				(justify mirror)
			)
		)
		(property "Value" "SC22U6D3V5MX-2GP"
			(at 0 -4.9022 90)
			(unlocked yes)
			(layer "B.Fab")
			(hide yes)
			(effects
				(font
					(size 1.016 1.016)
					(thickness 0.1524)
				)
				(justify mirror)
			)
		)
		(property "Device Type" "C805H58"
			(at 0 -6.8072 90)
			(unlocked yes)
			(layer "B.Fab")
			(hide yes)
			(effects
				(font
					(size 1.016 1.016)
					(thickness 0.1524)
				)
				(justify mirror)
			)
		)
		(duplicate_pad_numbers_are_jumpers no)
		(fp_line
			(start -0.6096 0)
			(end 0.6096 0)
			(stroke
				(width 0.3048)
				(type default)
			)
			(layer "B.SilkS")
		)
		(fp_poly
			(pts
				(xy 0.9017 1.4351) (xy -0.9017 1.4351) (xy -0.9017 -1.4351) (xy 0.9017 -1.4351)
			)
			(stroke
				(width 0)
				(type default)
			)
			(fill no)
			(layer "B.CrtYd")
		)
		(fp_poly
			(pts
				(xy -0.9017 1.4351) (xy -0.9017 -1.4351) (xy 0.9017 -1.4351) (xy 0.9017 1.4351)
			)
			(stroke
				(width 0)
				(type default)
			)
			(fill no)
			(layer "B.Fab")
		)
		(pad "1" smd rect
			(at 0 -0.8382 270)
			(size 1.5494 0.9398)
			(layers "B.Cu" "B.Mask" "B.Paste")
			(net "PV_VDDR")
		)
		(pad "2" smd rect
			(at 0 0.8382 270)
			(size 1.5494 0.9398)
			(layers "B.Cu" "B.Mask" "B.Paste")
			(net "GND")
		)
	)
	(footprint ""
		(layer "B.Cu")
		(at 42.926 -15.5702 -90)
		(property "Reference" "R428"
			(at 0 0 90)
			(layer "B.SilkS")
			(hide yes)
			(effects
				(font
					(size 1.27 1.27)
				)
				(justify mirror)
			)
		)
		(property "Value" "43D2R2F-GP"
			(at -1.7907 -1.1176 270)
			(unlocked yes)
			(layer "B.Fab")
			(hide yes)
			(effects
				(font
					(size 1.016 1.016)
					(thickness 0.1524)
				)
				(justify mirror)
			)
		)
		(property "Device Type" "R402H16"
			(at -1.7907 -2.6416 270)
			(unlocked yes)
			(layer "B.Fab")
			(hide yes)
			(effects
				(font
					(size 1.016 1.016)
					(thickness 0.1524)
				)
				(justify mirror)
			)
		)
		(duplicate_pad_numbers_are_jumpers no)
		(fp_rect
			(start 0.381 0.8382)
			(end -0.381 -0.8382)
			(stroke
				(width 0)
				(type default)
			)
			(fill no)
			(layer "B.CrtYd")
		)
		(fp_rect
			(start 0.381 0.8382)
			(end -0.381 -0.8382)
			(stroke
				(width 0)
				(type default)
			)
			(fill no)
			(layer "B.Fab")
		)
		(pad "1" smd custom
			(at 0 -0.4318 90)
			(size 0.127 0.127)
			(layers "B.Cu" "B.Mask" "B.Paste")
			(net "CLK_100M_CLKBUFF_ENET_DN")
			(options
				(clearance outline)
				(anchor circle)
			)
			(primitives
				(gr_poly
					(pts
						(arc
							(start -0.2032 0.2794)
							(mid -0.239121 0.264521)
							(end -0.254 0.2286)
						)
						(arc
							(start -0.254 -0.2286)
							(mid -0.239121 -0.264521)
							(end -0.2032 -0.2794)
						)
						(arc
							(start 0.2032 -0.2794)
							(mid 0.239121 -0.264521)
							(end 0.254 -0.2286)
						)
						(arc
							(start 0.254 0.2286)
							(mid 0.239121 0.264521)
							(end 0.2032 0.2794)
						)
					)
					(width 0)
					(fill yes)
				)
			)
		)
		(pad "2" smd custom
			(at 0 0.4318 90)
			(size 0.127 0.127)
			(layers "B.Cu" "B.Mask" "B.Paste")
			(net "GND")
			(options
				(clearance outline)
				(anchor circle)
			)
			(primitives
				(gr_poly
					(pts
						(arc
							(start -0.2032 0.2794)
							(mid -0.239121 0.264521)
							(end -0.254 0.2286)
						)
						(arc
							(start -0.254 -0.2286)
							(mid -0.239121 -0.264521)
							(end -0.2032 -0.2794)
						)
						(arc
							(start 0.2032 -0.2794)
							(mid 0.239121 -0.264521)
							(end 0.254 -0.2286)
						)
						(arc
							(start 0.254 0.2286)
							(mid 0.239121 0.264521)
							(end 0.2032 0.2794)
						)
					)
					(width 0)
					(fill yes)
				)
			)
		)
	)
	(footprint ""
		(layer "B.Cu")
		(at 111.7346 -45.466 180)
		(property "Reference" "C188"
			(at 0 0 0)
			(layer "B.SilkS")
			(hide yes)
			(effects
				(font
					(size 1.27 1.27)
				)
				(justify mirror)
			)
		)
		(property "Value" "SC22U6D3V5MX-2GP"
			(at 0.0762 -6.1214 180)
			(unlocked yes)
			(layer "B.Fab")
			(hide yes)
			(effects
				(font
					(size 1.016 1.016)
					(thickness 0.1524)
				)
				(justify mirror)
			)
		)
		(property "Device Type" "C805H58"
			(at 0.0762 -8.1534 180)
			(unlocked yes)
			(layer "B.Fab")
			(hide yes)
			(effects
				(font
					(size 1.016 1.016)
					(thickness 0.1524)
				)
				(justify mirror)
			)
		)
		(duplicate_pad_numbers_are_jumpers no)
		(fp_line
			(start -0.6096 0)
			(end 0.6096 0)
			(stroke
				(width 0.3048)
				(type default)
			)
			(layer "B.SilkS")
		)
		(fp_poly
			(pts
				(xy 0.9017 1.4351) (xy -0.9017 1.4351) (xy -0.9017 -1.4351) (xy 0.9017 -1.4351)
			)
			(stroke
				(width 0)
				(type default)
			)
			(fill no)
			(layer "B.CrtYd")
		)
		(fp_poly
			(pts
				(xy -0.9017 1.4351) (xy -0.9017 -1.4351) (xy 0.9017 -1.4351) (xy 0.9017 1.4351)
			)
			(stroke
				(width 0)
				(type default)
			)
			(fill no)
			(layer "B.Fab")
		)
		(pad "1" smd rect
			(at 0 -0.8382)
			(size 1.5494 0.9398)
			(layers "B.Cu" "B.Mask" "B.Paste")
			(net "PVCCP")
		)
		(pad "2" smd rect
			(at 0 0.8382)
			(size 1.5494 0.9398)
			(layers "B.Cu" "B.Mask" "B.Paste")
			(net "GND")
		)
	)
	(footprint ""
		(layer "B.Cu")
		(at 77.343 -37.084)
		(property "Reference" "R332"
			(at 0 0 0)
			(layer "B.SilkS")
			(hide yes)
			(effects
				(font
					(size 1.27 1.27)
				)
				(justify mirror)
			)
		)
		(property "Value" "1KR2F-3-GP"
			(at -0.064008 -3.993896 0)
			(unlocked yes)
			(layer "B.Fab")
			(hide yes)
			(effects
				(font
					(size 1.016 1.016)
					(thickness 0.1524)
				)
				(justify mirror)
			)
		)
		(property "Device Type" "R402H16"
			(at -0.064008 -5.517896 0)
			(unlocked yes)
			(layer "B.Fab")
			(hide yes)
			(effects
				(font
					(size 1.016 1.016)
					(thickness 0.1524)
				)
				(justify mirror)
			)
		)
		(duplicate_pad_numbers_are_jumpers no)
		(fp_rect
			(start 0.381 0.8382)
			(end -0.381 -0.8382)
			(stroke
				(width 0)
				(type default)
			)
			(fill no)
			(layer "B.CrtYd")
		)
		(fp_rect
			(start 0.381 0.8382)
			(end -0.381 -0.8382)
			(stroke
				(width 0)
				(type default)
			)
			(fill no)
			(layer "B.Fab")
		)
		(pad "1" smd custom
			(at 0 -0.4318 180)
			(size 0.127 0.127)
			(layers "B.Cu" "B.Mask" "B.Paste")
			(net "PMU_SUS_CLK")
			(options
				(clearance outline)
				(anchor circle)
			)
			(primitives
				(gr_poly
					(pts
						(arc
							(start -0.2032 0.2794)
							(mid -0.239121 0.264521)
							(end -0.254 0.2286)
						)
						(arc
							(start -0.254 -0.2286)
							(mid -0.239121 -0.264521)
							(end -0.2032 -0.2794)
						)
						(arc
							(start 0.2032 -0.2794)
							(mid 0.239121 -0.264521)
							(end 0.254 -0.2286)
						)
						(arc
							(start 0.254 0.2286)
							(mid 0.239121 0.264521)
							(end 0.2032 0.2794)
						)
					)
					(width 0)
					(fill yes)
				)
			)
		)
		(pad "2" smd custom
			(at 0 0.4318 180)
			(size 0.127 0.127)
			(layers "B.Cu" "B.Mask" "B.Paste")
			(net "GND")
			(options
				(clearance outline)
				(anchor circle)
			)
			(primitives
				(gr_poly
					(pts
						(arc
							(start -0.2032 0.2794)
							(mid -0.239121 0.264521)
							(end -0.254 0.2286)
						)
						(arc
							(start -0.254 -0.2286)
							(mid -0.239121 -0.264521)
							(end -0.2032 -0.2794)
						)
						(arc
							(start 0.2032 -0.2794)
							(mid 0.239121 -0.264521)
							(end 0.254 -0.2286)
						)
						(arc
							(start 0.254 0.2286)
							(mid 0.239121 0.264521)
							(end 0.2032 0.2794)
						)
					)
					(width 0)
					(fill yes)
				)
			)
		)
	)
	(footprint ""
		(layer "B.Cu")
		(at 4.826 -45.085)
		(property "Reference" "LED15"
			(at 0 0 0)
			(layer "B.SilkS")
			(hide yes)
			(effects
				(font
					(size 1.27 1.27)
				)
				(justify mirror)
			)
		)
		(property "Value" "LED-YG-51-GP"
			(at 2.6924 -1.4224 0)
			(unlocked yes)
			(layer "B.Fab")
			(hide yes)
			(effects
				(font
					(size 1.016 1.016)
					(thickness 0.1524)
				)
				(justify mirror)
			)
		)
		(property "Device Type" "LED1608AKH40"
			(at 2.6924 -2.9464 0)
			(unlocked yes)
			(layer "B.Fab")
			(hide yes)
			(effects
				(font
					(size 1.016 1.016)
					(thickness 0.1524)
				)
				(justify mirror)
			)
		)
		(duplicate_pad_numbers_are_jumpers no)
		(fp_line
			(start 0.5334 1.3081)
			(end -0.5334 1.3081)
			(stroke
				(width 0.254)
				(type default)
			)
			(layer "B.SilkS")
		)
		(fp_rect
			(start 0.6604 1.1811)
			(end -0.6604 -1.1811)
			(stroke
				(width 0)
				(type default)
			)
			(fill no)
			(layer "B.CrtYd")
		)
		(fp_rect
			(start 0.6604 1.1811)
			(end -0.6604 -1.1811)
			(stroke
				(width 0)
				(type default)
			)
			(fill no)
			(layer "B.Fab")
		)
		(pad "A" smd rect
			(at 0 -0.652526 180)
			(size 1.0668 0.8128)
			(layers "B.Cu" "B.Mask" "B.Paste")
			(net "LED_NGFF_DAS_R")
		)
		(pad "K" smd rect
			(at 0 0.652526 180)
			(size 1.0668 0.8128)
			(layers "B.Cu" "B.Mask" "B.Paste")
			(net "LED_NGFF_DAS")
		)
	)
	(footprint ""
		(layer "B.Cu")
		(at 45.466 -12.7)
		(property "Reference" "C263"
			(at 0 0 0)
			(layer "B.SilkS")
			(hide yes)
			(effects
				(font
					(size 1.27 1.27)
				)
				(justify mirror)
			)
		)
		(property "Value" "SCD1U16V2KX-3GP"
			(at -1.1811 -2.7051 0)
			(unlocked yes)
			(layer "B.Fab")
			(hide yes)
			(effects
				(font
					(size 1.016 1.016)
					(thickness 0.1524)
				)
				(justify mirror)
			)
		)
		(property "Device Type" "C402H22"
			(at -1.1811 -4.2291 0)
			(unlocked yes)
			(layer "B.Fab")
			(hide yes)
			(effects
				(font
					(size 1.016 1.016)
					(thickness 0.1524)
				)
				(justify mirror)
			)
		)
		(duplicate_pad_numbers_are_jumpers no)
		(fp_rect
			(start 0.381 0.7366)
			(end -0.381 -0.7366)
			(stroke
				(width 0)
				(type default)
			)
			(fill no)
			(layer "B.CrtYd")
		)
		(fp_rect
			(start 0.381 0.7366)
			(end -0.381 -0.7366)
			(stroke
				(width 0)
				(type default)
			)
			(fill no)
			(layer "B.Fab")
		)
		(pad "1" smd custom
			(at 0 -0.4572 180)
			(size 0.1143 0.1143)
			(layers "B.Cu" "B.Mask" "B.Paste")
			(net "P2E_CPU_SAS_C_TX_DN4")
			(options
				(clearance outline)
				(anchor circle)
			)
			(primitives
				(gr_poly
					(pts
						(arc
							(start -0.254 0.1778)
							(mid -0.239121 0.213721)
							(end -0.2032 0.2286)
						)
						(arc
							(start 0.2032 0.2286)
							(mid 0.239121 0.213721)
							(end 0.254 0.1778)
						)
						(arc
							(start 0.254 -0.1778)
							(mid 0.239121 -0.213721)
							(end 0.2032 -0.2286)
						)
						(arc
							(start -0.2032 -0.2286)
							(mid -0.239121 -0.213721)
							(end -0.254 -0.1778)
						)
					)
					(width 0)
					(fill yes)
				)
			)
		)
		(pad "2" smd custom
			(at 0 0.4572 180)
			(size 0.1143 0.1143)
			(layers "B.Cu" "B.Mask" "B.Paste")
			(net "P2E_CPU_SAS_TX_DN4")
			(options
				(clearance outline)
				(anchor circle)
			)
			(primitives
				(gr_poly
					(pts
						(arc
							(start -0.254 0.1778)
							(mid -0.239121 0.213721)
							(end -0.2032 0.2286)
						)
						(arc
							(start 0.2032 0.2286)
							(mid 0.239121 0.213721)
							(end 0.254 0.1778)
						)
						(arc
							(start 0.254 -0.1778)
							(mid 0.239121 -0.213721)
							(end 0.2032 -0.2286)
						)
						(arc
							(start -0.2032 -0.2286)
							(mid -0.239121 -0.213721)
							(end -0.254 -0.1778)
						)
					)
					(width 0)
					(fill yes)
				)
			)
		)
	)
	(footprint ""
		(layer "B.Cu")
		(at 86.233 -63.246)
		(property "Reference" "R276"
			(at 0 0 0)
			(layer "B.SilkS")
			(hide yes)
			(effects
				(font
					(size 1.27 1.27)
				)
				(justify mirror)
			)
		)
		(property "Value" "1KR2F-3-GP"
			(at -0.064008 -3.993896 0)
			(unlocked yes)
			(layer "B.Fab")
			(hide yes)
			(effects
				(font
					(size 1.016 1.016)
					(thickness 0.1524)
				)
				(justify mirror)
			)
		)
		(property "Device Type" "R402H16"
			(at -0.064008 -5.517896 0)
			(unlocked yes)
			(layer "B.Fab")
			(hide yes)
			(effects
				(font
					(size 1.016 1.016)
					(thickness 0.1524)
				)
				(justify mirror)
			)
		)
		(duplicate_pad_numbers_are_jumpers no)
		(fp_rect
			(start 0.381 0.8382)
			(end -0.381 -0.8382)
			(stroke
				(width 0)
				(type default)
			)
			(fill no)
			(layer "B.CrtYd")
		)
		(fp_rect
			(start 0.381 0.8382)
			(end -0.381 -0.8382)
			(stroke
				(width 0)
				(type default)
			)
			(fill no)
			(layer "B.Fab")
		)
		(pad "1" smd custom
			(at 0 -0.4318 180)
			(size 0.127 0.127)
			(layers "B.Cu" "B.Mask" "B.Paste")
			(net "P3V3_STBY")
			(options
				(clearance outline)
				(anchor circle)
			)
			(primitives
				(gr_poly
					(pts
						(arc
							(start -0.2032 0.2794)
							(mid -0.239121 0.264521)
							(end -0.254 0.2286)
						)
						(arc
							(start -0.254 -0.2286)
							(mid -0.239121 -0.264521)
							(end -0.2032 -0.2794)
						)
						(arc
							(start 0.2032 -0.2794)
							(mid 0.239121 -0.264521)
							(end 0.254 -0.2286)
						)
						(arc
							(start 0.254 0.2286)
							(mid 0.239121 0.264521)
							(end 0.2032 0.2794)
						)
					)
					(width 0)
					(fill yes)
				)
			)
		)
		(pad "2" smd custom
			(at 0 0.4318 180)
			(size 0.127 0.127)
			(layers "B.Cu" "B.Mask" "B.Paste")
			(net "PROCESSOR_HOT_LVC#")
			(options
				(clearance outline)
				(anchor circle)
			)
			(primitives
				(gr_poly
					(pts
						(arc
							(start -0.2032 0.2794)
							(mid -0.239121 0.264521)
							(end -0.254 0.2286)
						)
						(arc
							(start -0.254 -0.2286)
							(mid -0.239121 -0.264521)
							(end -0.2032 -0.2794)
						)
						(arc
							(start 0.2032 -0.2794)
							(mid 0.239121 -0.264521)
							(end 0.254 -0.2286)
						)
						(arc
							(start 0.254 0.2286)
							(mid 0.239121 0.264521)
							(end 0.2032 0.2794)
						)
					)
					(width 0)
					(fill yes)
				)
			)
		)
	)
	(footprint ""
		(layer "B.Cu")
		(at 41.468802 -12.7)
		(property "Reference" "C265"
			(at 0 0 0)
			(layer "B.SilkS")
			(hide yes)
			(effects
				(font
					(size 1.27 1.27)
				)
				(justify mirror)
			)
		)
		(property "Value" "SCD1U16V2KX-3GP"
			(at -1.1811 -2.7051 0)
			(unlocked yes)
			(layer "B.Fab")
			(hide yes)
			(effects
				(font
					(size 1.016 1.016)
					(thickness 0.1524)
				)
				(justify mirror)
			)
		)
		(property "Device Type" "C402H22"
			(at -1.1811 -4.2291 0)
			(unlocked yes)
			(layer "B.Fab")
			(hide yes)
			(effects
				(font
					(size 1.016 1.016)
					(thickness 0.1524)
				)
				(justify mirror)
			)
		)
		(duplicate_pad_numbers_are_jumpers no)
		(fp_rect
			(start 0.381 0.7366)
			(end -0.381 -0.7366)
			(stroke
				(width 0)
				(type default)
			)
			(fill no)
			(layer "B.CrtYd")
		)
		(fp_rect
			(start 0.381 0.7366)
			(end -0.381 -0.7366)
			(stroke
				(width 0)
				(type default)
			)
			(fill no)
			(layer "B.Fab")
		)
		(pad "1" smd custom
			(at 0 -0.4572 180)
			(size 0.1143 0.1143)
			(layers "B.Cu" "B.Mask" "B.Paste")
			(net "P2E_CPU_SAS_C_TX_DN5")
			(options
				(clearance outline)
				(anchor circle)
			)
			(primitives
				(gr_poly
					(pts
						(arc
							(start -0.254 0.1778)
							(mid -0.239121 0.213721)
							(end -0.2032 0.2286)
						)
						(arc
							(start 0.2032 0.2286)
							(mid 0.239121 0.213721)
							(end 0.254 0.1778)
						)
						(arc
							(start 0.254 -0.1778)
							(mid 0.239121 -0.213721)
							(end 0.2032 -0.2286)
						)
						(arc
							(start -0.2032 -0.2286)
							(mid -0.239121 -0.213721)
							(end -0.254 -0.1778)
						)
					)
					(width 0)
					(fill yes)
				)
			)
		)
		(pad "2" smd custom
			(at 0 0.4572 180)
			(size 0.1143 0.1143)
			(layers "B.Cu" "B.Mask" "B.Paste")
			(net "P2E_CPU_SAS_TX_DN5")
			(options
				(clearance outline)
				(anchor circle)
			)
			(primitives
				(gr_poly
					(pts
						(arc
							(start -0.254 0.1778)
							(mid -0.239121 0.213721)
							(end -0.2032 0.2286)
						)
						(arc
							(start 0.2032 0.2286)
							(mid 0.239121 0.213721)
							(end 0.254 0.1778)
						)
						(arc
							(start 0.254 -0.1778)
							(mid 0.239121 -0.213721)
							(end 0.2032 -0.2286)
						)
						(arc
							(start -0.2032 -0.2286)
							(mid -0.239121 -0.213721)
							(end -0.254 -0.1778)
						)
					)
					(width 0)
					(fill yes)
				)
			)
		)
	)
	(footprint ""
		(layer "B.Cu")
		(at 42.230802 -12.7)
		(property "Reference" "C264"
			(at 0 0 0)
			(layer "B.SilkS")
			(hide yes)
			(effects
				(font
					(size 1.27 1.27)
				)
				(justify mirror)
			)
		)
		(property "Value" "SCD1U16V2KX-3GP"
			(at -1.1811 -2.7051 0)
			(unlocked yes)
			(layer "B.Fab")
			(hide yes)
			(effects
				(font
					(size 1.016 1.016)
					(thickness 0.1524)
				)
				(justify mirror)
			)
		)
		(property "Device Type" "C402H22"
			(at -1.1811 -4.2291 0)
			(unlocked yes)
			(layer "B.Fab")
			(hide yes)
			(effects
				(font
					(size 1.016 1.016)
					(thickness 0.1524)
				)
				(justify mirror)
			)
		)
		(duplicate_pad_numbers_are_jumpers no)
		(fp_rect
			(start 0.381 0.7366)
			(end -0.381 -0.7366)
			(stroke
				(width 0)
				(type default)
			)
			(fill no)
			(layer "B.CrtYd")
		)
		(fp_rect
			(start 0.381 0.7366)
			(end -0.381 -0.7366)
			(stroke
				(width 0)
				(type default)
			)
			(fill no)
			(layer "B.Fab")
		)
		(pad "1" smd custom
			(at 0 -0.4572 180)
			(size 0.1143 0.1143)
			(layers "B.Cu" "B.Mask" "B.Paste")
			(net "P2E_CPU_SAS_C_TX_DP5")
			(options
				(clearance outline)
				(anchor circle)
			)
			(primitives
				(gr_poly
					(pts
						(arc
							(start -0.254 0.1778)
							(mid -0.239121 0.213721)
							(end -0.2032 0.2286)
						)
						(arc
							(start 0.2032 0.2286)
							(mid 0.239121 0.213721)
							(end 0.254 0.1778)
						)
						(arc
							(start 0.254 -0.1778)
							(mid 0.239121 -0.213721)
							(end 0.2032 -0.2286)
						)
						(arc
							(start -0.2032 -0.2286)
							(mid -0.239121 -0.213721)
							(end -0.254 -0.1778)
						)
					)
					(width 0)
					(fill yes)
				)
			)
		)
		(pad "2" smd custom
			(at 0 0.4572 180)
			(size 0.1143 0.1143)
			(layers "B.Cu" "B.Mask" "B.Paste")
			(net "P2E_CPU_SAS_TX_DP5")
			(options
				(clearance outline)
				(anchor circle)
			)
			(primitives
				(gr_poly
					(pts
						(arc
							(start -0.254 0.1778)
							(mid -0.239121 0.213721)
							(end -0.2032 0.2286)
						)
						(arc
							(start 0.2032 0.2286)
							(mid 0.239121 0.213721)
							(end 0.254 0.1778)
						)
						(arc
							(start 0.254 -0.1778)
							(mid 0.239121 -0.213721)
							(end 0.2032 -0.2286)
						)
						(arc
							(start -0.2032 -0.2286)
							(mid -0.239121 -0.213721)
							(end -0.254 -0.1778)
						)
					)
					(width 0)
					(fill yes)
				)
			)
		)
	)
	(footprint ""
		(layer "B.Cu")
		(at 100.289868 -36.353496 -90)
		(property "Reference" "C199"
			(at 0 0 90)
			(layer "B.SilkS")
			(hide yes)
			(effects
				(font
					(size 1.27 1.27)
				)
				(justify mirror)
			)
		)
		(property "Value" "SC2D2U10V2KX-GP"
			(at -1.1811 -2.7051 270)
			(unlocked yes)
			(layer "B.Fab")
			(hide yes)
			(effects
				(font
					(size 1.016 1.016)
					(thickness 0.1524)
				)
				(justify mirror)
			)
		)
		(property "Device Type" "C402H22"
			(at -1.1811 -4.2291 270)
			(unlocked yes)
			(layer "B.Fab")
			(hide yes)
			(effects
				(font
					(size 1.016 1.016)
					(thickness 0.1524)
				)
				(justify mirror)
			)
		)
		(duplicate_pad_numbers_are_jumpers no)
		(fp_rect
			(start 0.381 0.7366)
			(end -0.381 -0.7366)
			(stroke
				(width 0)
				(type default)
			)
			(fill no)
			(layer "B.CrtYd")
		)
		(fp_rect
			(start 0.381 0.7366)
			(end -0.381 -0.7366)
			(stroke
				(width 0)
				(type default)
			)
			(fill no)
			(layer "B.Fab")
		)
		(pad "1" smd custom
			(at 0 -0.4572 90)
			(size 0.1143 0.1143)
			(layers "B.Cu" "B.Mask" "B.Paste")
			(net "P1V0")
			(options
				(clearance outline)
				(anchor circle)
			)
			(primitives
				(gr_poly
					(pts
						(arc
							(start -0.254 0.1778)
							(mid -0.239121 0.213721)
							(end -0.2032 0.2286)
						)
						(arc
							(start 0.2032 0.2286)
							(mid 0.239121 0.213721)
							(end 0.254 0.1778)
						)
						(arc
							(start 0.254 -0.1778)
							(mid 0.239121 -0.213721)
							(end 0.2032 -0.2286)
						)
						(arc
							(start -0.2032 -0.2286)
							(mid -0.239121 -0.213721)
							(end -0.254 -0.1778)
						)
					)
					(width 0)
					(fill yes)
				)
			)
		)
		(pad "2" smd custom
			(at 0 0.4572 90)
			(size 0.1143 0.1143)
			(layers "B.Cu" "B.Mask" "B.Paste")
			(net "GND")
			(options
				(clearance outline)
				(anchor circle)
			)
			(primitives
				(gr_poly
					(pts
						(arc
							(start -0.254 0.1778)
							(mid -0.239121 0.213721)
							(end -0.2032 0.2286)
						)
						(arc
							(start 0.2032 0.2286)
							(mid 0.239121 0.213721)
							(end 0.254 0.1778)
						)
						(arc
							(start 0.254 -0.1778)
							(mid 0.239121 -0.213721)
							(end 0.2032 -0.2286)
						)
						(arc
							(start -0.2032 -0.2286)
							(mid -0.239121 -0.213721)
							(end -0.254 -0.1778)
						)
					)
					(width 0)
					(fill yes)
				)
			)
		)
	)
	(footprint ""
		(layer "B.Cu")
		(at 204.0128 -44.7548)
		(property "Reference" "PR104"
			(at 0 0 0)
			(layer "B.SilkS")
			(hide yes)
			(effects
				(font
					(size 1.27 1.27)
				)
				(justify mirror)
			)
		)
		(property "Value" "2D2R5F-2-GP"
			(at 0 -4.9022 0)
			(unlocked yes)
			(layer "B.Fab")
			(hide yes)
			(effects
				(font
					(size 1.016 1.016)
					(thickness 0.1524)
				)
				(justify mirror)
			)
		)
		(property "Device Type" "R805H24"
			(at 0 -6.8072 0)
			(unlocked yes)
			(layer "B.Fab")
			(hide yes)
			(effects
				(font
					(size 1.016 1.016)
					(thickness 0.1524)
				)
				(justify mirror)
			)
		)
		(duplicate_pad_numbers_are_jumpers no)
		(fp_line
			(start -0.6096 0)
			(end -0.2794 0)
			(stroke
				(width 0.3048)
				(type default)
			)
			(layer "B.SilkS")
		)
		(fp_line
			(start 0.2794 0)
			(end 0.6096 0)
			(stroke
				(width 0.3048)
				(type default)
			)
			(layer "B.SilkS")
		)
		(fp_poly
			(pts
				(xy 0.9017 1.4351) (xy -0.9017 1.4351) (xy -0.9017 -1.4351) (xy 0.9017 -1.4351)
			)
			(stroke
				(width 0)
				(type default)
			)
			(fill no)
			(layer "B.CrtYd")
		)
		(fp_poly
			(pts
				(xy -0.9017 1.4351) (xy -0.9017 -1.4351) (xy 0.9017 -1.4351) (xy 0.9017 1.4351)
			)
			(stroke
				(width 0)
				(type default)
			)
			(fill no)
			(layer "B.Fab")
		)
		(pad "1" smd rect
			(at 0 -0.8382 180)
			(size 1.5494 0.9398)
			(layers "B.Cu" "B.Mask" "B.Paste")
			(net "VR_PVDDR_A_VSW_R")
		)
		(pad "2" smd rect
			(at 0 0.8382 180)
			(size 1.5494 0.9398)
			(layers "B.Cu" "B.Mask" "B.Paste")
			(net "GND")
		)
	)
	(footprint ""
		(layer "B.Cu")
		(at 102.073964 -41.529 180)
		(property "Reference" "C174"
			(at 0 0 0)
			(layer "B.SilkS")
			(hide yes)
			(effects
				(font
					(size 1.27 1.27)
				)
				(justify mirror)
			)
		)
		(property "Value" "SC1U10V2KX-1GP"
			(at -1.1811 -2.7051 180)
			(unlocked yes)
			(layer "B.Fab")
			(hide yes)
			(effects
				(font
					(size 1.016 1.016)
					(thickness 0.1524)
				)
				(justify mirror)
			)
		)
		(property "Device Type" "C402H22"
			(at -1.1811 -4.2291 180)
			(unlocked yes)
			(layer "B.Fab")
			(hide yes)
			(effects
				(font
					(size 1.016 1.016)
					(thickness 0.1524)
				)
				(justify mirror)
			)
		)
		(duplicate_pad_numbers_are_jumpers no)
		(fp_rect
			(start 0.381 0.7366)
			(end -0.381 -0.7366)
			(stroke
				(width 0)
				(type default)
			)
			(fill no)
			(layer "B.CrtYd")
		)
		(fp_rect
			(start 0.381 0.7366)
			(end -0.381 -0.7366)
			(stroke
				(width 0)
				(type default)
			)
			(fill no)
			(layer "B.Fab")
		)
		(pad "1" smd custom
			(at 0 -0.4572)
			(size 0.1143 0.1143)
			(layers "B.Cu" "B.Mask" "B.Paste")
			(net "PVCCP")
			(options
				(clearance outline)
				(anchor circle)
			)
			(primitives
				(gr_poly
					(pts
						(arc
							(start -0.254 0.1778)
							(mid -0.239121 0.213721)
							(end -0.2032 0.2286)
						)
						(arc
							(start 0.2032 0.2286)
							(mid 0.239121 0.213721)
							(end 0.254 0.1778)
						)
						(arc
							(start 0.254 -0.1778)
							(mid 0.239121 -0.213721)
							(end 0.2032 -0.2286)
						)
						(arc
							(start -0.2032 -0.2286)
							(mid -0.239121 -0.213721)
							(end -0.254 -0.1778)
						)
					)
					(width 0)
					(fill yes)
				)
			)
		)
		(pad "2" smd custom
			(at 0 0.4572)
			(size 0.1143 0.1143)
			(layers "B.Cu" "B.Mask" "B.Paste")
			(net "GND")
			(options
				(clearance outline)
				(anchor circle)
			)
			(primitives
				(gr_poly
					(pts
						(arc
							(start -0.254 0.1778)
							(mid -0.239121 0.213721)
							(end -0.2032 0.2286)
						)
						(arc
							(start 0.2032 0.2286)
							(mid 0.239121 0.213721)
							(end 0.254 0.1778)
						)
						(arc
							(start 0.254 -0.1778)
							(mid 0.239121 -0.213721)
							(end 0.2032 -0.2286)
						)
						(arc
							(start -0.2032 -0.2286)
							(mid -0.239121 -0.213721)
							(end -0.254 -0.1778)
						)
					)
					(width 0)
					(fill yes)
				)
			)
		)
	)
	(footprint ""
		(layer "B.Cu")
		(at 104.521 -33.401 180)
		(property "Reference" "C222"
			(at 0 0 0)
			(layer "B.SilkS")
			(hide yes)
			(effects
				(font
					(size 1.27 1.27)
				)
				(justify mirror)
			)
		)
		(property "Value" "SC33P50V2JN-3GP"
			(at -1.1811 -2.7051 180)
			(unlocked yes)
			(layer "B.Fab")
			(hide yes)
			(effects
				(font
					(size 1.016 1.016)
					(thickness 0.1524)
				)
				(justify mirror)
			)
		)
		(property "Device Type" "C402H22"
			(at -1.1811 -4.2291 180)
			(unlocked yes)
			(layer "B.Fab")
			(hide yes)
			(effects
				(font
					(size 1.016 1.016)
					(thickness 0.1524)
				)
				(justify mirror)
			)
		)
		(duplicate_pad_numbers_are_jumpers no)
		(fp_rect
			(start 0.381 0.7366)
			(end -0.381 -0.7366)
			(stroke
				(width 0)
				(type default)
			)
			(fill no)
			(layer "B.CrtYd")
		)
		(fp_rect
			(start 0.381 0.7366)
			(end -0.381 -0.7366)
			(stroke
				(width 0)
				(type default)
			)
			(fill no)
			(layer "B.Fab")
		)
		(pad "1" smd custom
			(at 0 -0.4572)
			(size 0.1143 0.1143)
			(layers "B.Cu" "B.Mask" "B.Paste")
			(net "PWRGD_DDR3_VCCA")
			(options
				(clearance outline)
				(anchor circle)
			)
			(primitives
				(gr_poly
					(pts
						(arc
							(start -0.254 0.1778)
							(mid -0.239121 0.213721)
							(end -0.2032 0.2286)
						)
						(arc
							(start 0.2032 0.2286)
							(mid 0.239121 0.213721)
							(end 0.254 0.1778)
						)
						(arc
							(start 0.254 -0.1778)
							(mid 0.239121 -0.213721)
							(end 0.2032 -0.2286)
						)
						(arc
							(start -0.2032 -0.2286)
							(mid -0.239121 -0.213721)
							(end -0.254 -0.1778)
						)
					)
					(width 0)
					(fill yes)
				)
			)
		)
		(pad "2" smd custom
			(at 0 0.4572)
			(size 0.1143 0.1143)
			(layers "B.Cu" "B.Mask" "B.Paste")
			(net "GND")
			(options
				(clearance outline)
				(anchor circle)
			)
			(primitives
				(gr_poly
					(pts
						(arc
							(start -0.254 0.1778)
							(mid -0.239121 0.213721)
							(end -0.2032 0.2286)
						)
						(arc
							(start 0.2032 0.2286)
							(mid 0.239121 0.213721)
							(end 0.254 0.1778)
						)
						(arc
							(start 0.254 -0.1778)
							(mid 0.239121 -0.213721)
							(end 0.2032 -0.2286)
						)
						(arc
							(start -0.2032 -0.2286)
							(mid -0.239121 -0.213721)
							(end -0.254 -0.1778)
						)
					)
					(width 0)
					(fill yes)
				)
			)
		)
	)
	(footprint ""
		(layer "B.Cu")
		(at 53.086 -12.7 180)
		(property "Reference" "R413"
			(at 0 0 0)
			(layer "B.SilkS")
			(hide yes)
			(effects
				(font
					(size 1.27 1.27)
				)
				(justify mirror)
			)
		)
		(property "Value" "0R2J-2-GP"
			(at -1.7907 -1.1176 180)
			(unlocked yes)
			(layer "B.Fab")
			(hide yes)
			(effects
				(font
					(size 1.016 1.016)
					(thickness 0.1524)
				)
				(justify mirror)
			)
		)
		(property "Device Type" "R402H16"
			(at -1.7907 -2.6416 180)
			(unlocked yes)
			(layer "B.Fab")
			(hide yes)
			(effects
				(font
					(size 1.016 1.016)
					(thickness 0.1524)
				)
				(justify mirror)
			)
		)
		(duplicate_pad_numbers_are_jumpers no)
		(fp_rect
			(start 0.381 0.8382)
			(end -0.381 -0.8382)
			(stroke
				(width 0)
				(type default)
			)
			(fill no)
			(layer "B.CrtYd")
		)
		(fp_rect
			(start 0.381 0.8382)
			(end -0.381 -0.8382)
			(stroke
				(width 0)
				(type default)
			)
			(fill no)
			(layer "B.Fab")
		)
		(pad "1" smd custom
			(at 0 -0.4318)
			(size 0.127 0.127)
			(layers "B.Cu" "B.Mask" "B.Paste")
			(net "GBE_R_SMDATA")
			(options
				(clearance outline)
				(anchor circle)
			)
			(primitives
				(gr_poly
					(pts
						(arc
							(start -0.2032 0.2794)
							(mid -0.239121 0.264521)
							(end -0.254 0.2286)
						)
						(arc
							(start -0.254 -0.2286)
							(mid -0.239121 -0.264521)
							(end -0.2032 -0.2794)
						)
						(arc
							(start 0.2032 -0.2794)
							(mid 0.239121 -0.264521)
							(end 0.254 -0.2286)
						)
						(arc
							(start 0.254 0.2286)
							(mid 0.239121 0.264521)
							(end 0.2032 0.2794)
						)
					)
					(width 0)
					(fill yes)
				)
			)
		)
		(pad "2" smd custom
			(at 0 0.4318)
			(size 0.127 0.127)
			(layers "B.Cu" "B.Mask" "B.Paste")
			(net "GF_GBE_SMBDATA")
			(options
				(clearance outline)
				(anchor circle)
			)
			(primitives
				(gr_poly
					(pts
						(arc
							(start -0.2032 0.2794)
							(mid -0.239121 0.264521)
							(end -0.254 0.2286)
						)
						(arc
							(start -0.254 -0.2286)
							(mid -0.239121 -0.264521)
							(end -0.2032 -0.2794)
						)
						(arc
							(start 0.2032 -0.2794)
							(mid 0.239121 -0.264521)
							(end 0.254 -0.2286)
						)
						(arc
							(start 0.254 0.2286)
							(mid 0.239121 0.264521)
							(end 0.2032 0.2794)
						)
					)
					(width 0)
					(fill yes)
				)
			)
		)
	)
	(footprint ""
		(layer "B.Cu")
		(at 161.671 -72.39 90)
		(property "Reference" "R233"
			(at 0 0 90)
			(layer "B.SilkS")
			(hide yes)
			(effects
				(font
					(size 1.27 1.27)
				)
				(justify mirror)
			)
		)
		(property "Value" "100R2F-L1-GP-U"
			(at -0.064008 -3.993896 90)
			(unlocked yes)
			(layer "B.Fab")
			(hide yes)
			(effects
				(font
					(size 1.016 1.016)
					(thickness 0.1524)
				)
				(justify mirror)
			)
		)
		(property "Device Type" "R402H14"
			(at -0.064008 -5.517896 90)
			(unlocked yes)
			(layer "B.Fab")
			(hide yes)
			(effects
				(font
					(size 1.016 1.016)
					(thickness 0.1524)
				)
				(justify mirror)
			)
		)
		(duplicate_pad_numbers_are_jumpers no)
		(fp_rect
			(start 0.381 0.8382)
			(end -0.381 -0.8382)
			(stroke
				(width 0)
				(type default)
			)
			(fill no)
			(layer "B.CrtYd")
		)
		(fp_rect
			(start 0.381 0.8382)
			(end -0.381 -0.8382)
			(stroke
				(width 0)
				(type default)
			)
			(fill no)
			(layer "B.Fab")
		)
		(pad "1" smd custom
			(at 0 -0.4318 270)
			(size 0.127 0.127)
			(layers "B.Cu" "B.Mask" "B.Paste")
			(net "PV_VDDR")
			(options
				(clearance outline)
				(anchor circle)
			)
			(primitives
				(gr_poly
					(pts
						(arc
							(start -0.2032 0.2794)
							(mid -0.239121 0.264521)
							(end -0.254 0.2286)
						)
						(arc
							(start -0.254 -0.2286)
							(mid -0.239121 -0.264521)
							(end -0.2032 -0.2794)
						)
						(arc
							(start 0.2032 -0.2794)
							(mid 0.239121 -0.264521)
							(end 0.254 -0.2286)
						)
						(arc
							(start 0.254 0.2286)
							(mid 0.239121 0.264521)
							(end 0.2032 0.2794)
						)
					)
					(width 0)
					(fill yes)
				)
			)
		)
		(pad "2" smd custom
			(at 0 0.4318 270)
			(size 0.127 0.127)
			(layers "B.Cu" "B.Mask" "B.Paste")
			(net "DDR3_M_A_VREF_CA")
			(options
				(clearance outline)
				(anchor circle)
			)
			(primitives
				(gr_poly
					(pts
						(arc
							(start -0.2032 0.2794)
							(mid -0.239121 0.264521)
							(end -0.254 0.2286)
						)
						(arc
							(start -0.254 -0.2286)
							(mid -0.239121 -0.264521)
							(end -0.2032 -0.2794)
						)
						(arc
							(start 0.2032 -0.2794)
							(mid 0.239121 -0.264521)
							(end 0.254 -0.2286)
						)
						(arc
							(start 0.254 0.2286)
							(mid 0.239121 0.264521)
							(end 0.2032 0.2794)
						)
					)
					(width 0)
					(fill yes)
				)
			)
		)
	)
	(footprint ""
		(layer "B.Cu")
		(at 96.52 -65.659 180)
		(property "Reference" "PU1"
			(at 0 0 0)
			(layer "B.SilkS")
			(hide yes)
			(effects
				(font
					(size 1.27 1.27)
				)
				(justify mirror)
			)
		)
		(property "Value" "EN6337QI-GP-U"
			(at 3.6576 -5.2832 180)
			(unlocked yes)
			(layer "B.Fab")
			(hide yes)
			(effects
				(font
					(size 1.016 1.016)
					(thickness 0.1524)
				)
				(justify mirror)
			)
		)
		(property "Device Type" "QFN38G4070-G260193-UH75"
			(at 3.6576 -6.8072 180)
			(unlocked yes)
			(layer "B.Fab")
			(hide yes)
			(effects
				(font
					(size 1.016 1.016)
					(thickness 0.1524)
				)
				(justify mirror)
			)
		)
		(duplicate_pad_numbers_are_jumpers no)
		(fp_poly
			(pts
				(xy -2.263902 -3.89636) (xy -2.898902 -4.53136) (xy -1.628902 -4.53136)
			)
			(stroke
				(width 0)
				(type default)
			)
			(fill yes)
			(layer "B.SilkS")
		)
		(fp_rect
			(start 2.3876 3.8862)
			(end -2.3876 -3.8862)
			(stroke
				(width 0)
				(type default)
			)
			(fill no)
			(layer "B.CrtYd")
		)
		(fp_rect
			(start 2.3876 3.8862)
			(end -2.3876 -3.8862)
			(stroke
				(width 0)
				(type default)
			)
			(fill no)
			(layer "B.Fab")
		)
		(pad "1" smd rect
			(at -1.249934 -3.42392)
			(size 0.3048 0.6604)
			(layers "B.Cu" "B.Mask" "B.Paste")
			(net "Net_411")
		)
		(pad "2" smd rect
			(at -0.750062 -3.42392)
			(size 0.3048 0.6604)
			(layers "B.Cu" "B.Mask" "B.Paste")
			(net "Net_417")
		)
		(pad "3" smd rect
			(at -0.249936 -3.42392)
			(size 0.3048 0.6604)
			(layers "B.Cu" "B.Mask" "B.Paste")
			(net "Net_416")
		)
		(pad "4" smd rect
			(at 0.249936 -3.42392)
			(size 0.3048 0.6604)
			(layers "B.Cu" "B.Mask" "B.Paste")
			(net "Net_419")
		)
		(pad "5" smd rect
			(at 0.750062 -3.42392)
			(size 0.3048 0.6604)
			(layers "B.Cu" "B.Mask" "B.Paste")
			(net "P1V1")
		)
		(pad "6" smd rect
			(at 1.249934 -3.42392)
			(size 0.3048 0.6604)
			(layers "B.Cu" "B.Mask" "B.Paste")
			(net "P1V1")
		)
		(pad "7" smd rect
			(at 1.923796 -2.999994)
			(size 0.635 0.3048)
			(drill
				(offset -0.0127 0)
			)
			(layers "B.Cu" "B.Mask" "B.Paste")
			(net "P1V1")
		)
		(pad "8" smd rect
			(at 1.923796 -2.500122)
			(size 0.6604 0.3048)
			(layers "B.Cu" "B.Mask" "B.Paste")
			(net "P1V1")
		)
		(pad "9" smd rect
			(at 1.923796 -1.999996)
			(size 0.6604 0.3048)
			(layers "B.Cu" "B.Mask" "B.Paste")
			(net "P1V1")
		)
		(pad "10" smd rect
			(at 1.923796 -1.500124)
			(size 0.6604 0.3048)
			(layers "B.Cu" "B.Mask" "B.Paste")
			(net "P1V1")
		)
		(pad "11" smd rect
			(at 1.923796 -0.999998)
			(size 0.6604 0.3048)
			(layers "B.Cu" "B.Mask" "B.Paste")
			(net "P1V1")
		)
		(pad "12" smd rect
			(at 1.923796 -0.500126)
			(size 0.6604 0.3048)
			(layers "B.Cu" "B.Mask" "B.Paste")
			(net "Net_418")
		)
		(pad "13" smd rect
			(at 1.923796 0)
			(size 0.6604 0.3048)
			(layers "B.Cu" "B.Mask" "B.Paste")
			(net "GND")
		)
		(pad "14" smd rect
			(at 1.923796 0.500126)
			(size 0.6604 0.3048)
			(layers "B.Cu" "B.Mask" "B.Paste")
			(net "GND")
		)
		(pad "15" smd rect
			(at 1.923796 0.999998)
			(size 0.6604 0.3048)
			(layers "B.Cu" "B.Mask" "B.Paste")
			(net "GND")
		)
		(pad "16" smd rect
			(at 1.923796 1.500124)
			(size 0.6604 0.3048)
			(layers "B.Cu" "B.Mask" "B.Paste")
			(net "GND")
		)
		(pad "17" smd rect
			(at 1.923796 1.999996)
			(size 0.6604 0.3048)
			(layers "B.Cu" "B.Mask" "B.Paste")
			(net "GND")
		)
		(pad "18" smd rect
			(at 1.923796 2.500122)
			(size 0.6604 0.3048)
			(layers "B.Cu" "B.Mask" "B.Paste")
			(net "GND")
		)
		(pad "19" smd rect
			(at 1.923796 2.999994)
			(size 0.635 0.3048)
			(drill
				(offset -0.0127 0)
			)
			(layers "B.Cu" "B.Mask" "B.Paste")
			(net "VR_P1V1_PVIN")
		)
		(pad "20" smd rect
			(at 1.249934 3.42392)
			(size 0.3048 0.6604)
			(layers "B.Cu" "B.Mask" "B.Paste")
			(net "VR_P1V1_PVIN")
		)
		(pad "21" smd rect
			(at 0.750062 3.42392)
			(size 0.3048 0.6604)
			(layers "B.Cu" "B.Mask" "B.Paste")
			(net "VR_P1V1_PVIN")
		)
		(pad "22" smd rect
			(at 0.249936 3.42392)
			(size 0.3048 0.6604)
			(layers "B.Cu" "B.Mask" "B.Paste")
			(net "Net_421")
		)
		(pad "23" smd rect
			(at -0.249936 3.42392)
			(size 0.3048 0.6604)
			(layers "B.Cu" "B.Mask" "B.Paste")
			(net "Net_420")
		)
		(pad "24" smd rect
			(at -0.750062 3.42392)
			(size 0.3048 0.6604)
			(layers "B.Cu" "B.Mask" "B.Paste")
			(net "TP_VDDB")
		)
		(pad "25" smd rect
			(at -1.249934 3.42392)
			(size 0.3048 0.6604)
			(layers "B.Cu" "B.Mask" "B.Paste")
			(net "TP_BGND")
		)
		(pad "26" smd rect
			(at -1.923796 2.999994)
			(size 0.635 0.3048)
			(drill
				(offset 0.0127 0)
			)
			(layers "B.Cu" "B.Mask" "B.Paste")
			(net "GND")
		)
		(pad "27" smd rect
			(at -1.923796 2.500122)
			(size 0.6604 0.3048)
			(layers "B.Cu" "B.Mask" "B.Paste")
			(net "VR_P1V1_EN")
		)
		(pad "28" smd rect
			(at -1.923796 1.999996)
			(size 0.6604 0.3048)
			(layers "B.Cu" "B.Mask" "B.Paste")
			(net "PWRGD_P1V1_PG")
		)
		(pad "29" smd rect
			(at -1.923796 1.500124)
			(size 0.6604 0.3048)
			(layers "B.Cu" "B.Mask" "B.Paste")
			(net "Net_90")
		)
		(pad "30" smd rect
			(at -1.923796 0.999998)
			(size 0.6604 0.3048)
			(layers "B.Cu" "B.Mask" "B.Paste")
			(net "VR_P1V1_SS")
		)
		(pad "31" smd rect
			(at -1.923796 0.500126)
			(size 0.6604 0.3048)
			(layers "B.Cu" "B.Mask" "B.Paste")
			(net "VR_P1V1_VFB")
		)
		(pad "32" smd rect
			(at -1.923796 0)
			(size 0.6604 0.3048)
			(layers "B.Cu" "B.Mask" "B.Paste")
			(net "AGND_P1V1")
		)
		(pad "33" smd rect
			(at -1.923796 -0.500126)
			(size 0.6604 0.3048)
			(layers "B.Cu" "B.Mask" "B.Paste")
			(net "VR_P1V1_AVIN")
		)
		(pad "34" smd rect
			(at -1.923796 -0.999998)
			(size 0.6604 0.3048)
			(layers "B.Cu" "B.Mask" "B.Paste")
			(net "Net_415")
		)
		(pad "35" smd rect
			(at -1.923796 -1.500124)
			(size 0.6604 0.3048)
			(layers "B.Cu" "B.Mask" "B.Paste")
			(net "Net_414")
		)
		(pad "36" smd rect
			(at -1.923796 -1.999996)
			(size 0.6604 0.3048)
			(layers "B.Cu" "B.Mask" "B.Paste")
			(net "Net_413")
		)
		(pad "37" smd rect
			(at -1.923796 -2.500122)
			(size 0.6604 0.3048)
			(layers "B.Cu" "B.Mask" "B.Paste")
			(net "Net_412")
		)
		(pad "38" smd rect
			(at -1.923796 -2.999994)
			(size 0.635 0.3048)
			(drill
				(offset 0.0127 0)
			)
			(layers "B.Cu" "B.Mask" "B.Paste")
			(net "Net_410")
		)
		(pad "39" smd rect
			(at 0 1.260094)
			(size 2.5908 1.9304)
			(layers "B.Cu" "B.Mask" "B.Paste")
			(net "GND")
		)
		(zone
			(layer "B.Cu")
			(hatch none 0.5)
			(connect_pads
				(clearance 0)
			)
			(min_thickness 0.25)
			(keepout
				(tracks allowed)
				(vias not_allowed)
				(pads allowed)
				(copperpour not_allowed)
				(footprints allowed)
			)
			(placement
				(enabled no)
				(sheetname "")
			)
			(fill
				(thermal_gap 0.5)
				(thermal_bridge_width 0.5)
				(island_removal_mode 0)
			)
			(polygon
				(pts
					(xy 94.926404 -68.75272) (xy 94.926404 -67.884294) (xy 97.8154 -67.884294) (xy 97.8154 -65.953894)
					(xy 94.926404 -65.953894) (xy 94.926404 -62.56528) (xy 98.113596 -62.56528) (xy 98.113596 -68.75272)
				)
			)
		)
		(zone
			(layer "B.Cu")
			(hatch none 0.5)
			(connect_pads
				(clearance 0)
			)
			(min_thickness 0.25)
			(keepout
				(tracks not_allowed)
				(vias allowed)
				(pads allowed)
				(copperpour not_allowed)
				(footprints allowed)
			)
			(placement
				(enabled no)
				(sheetname "")
			)
			(fill
				(thermal_gap 0.5)
				(thermal_bridge_width 0.5)
				(island_removal_mode 0)
			)
			(polygon
				(pts
					(xy 94.926404 -68.75272) (xy 94.926404 -67.884294) (xy 97.8154 -67.884294) (xy 97.8154 -65.953894)
					(xy 94.926404 -65.953894) (xy 94.926404 -62.56528) (xy 98.113596 -62.56528) (xy 98.113596 -68.75272)
				)
			)
		)
	)
	(footprint ""
		(layer "B.Cu")
		(at 38.227 -45.339 180)
		(property "Reference" "C66"
			(at 0 0 0)
			(layer "B.SilkS")
			(hide yes)
			(effects
				(font
					(size 1.27 1.27)
				)
				(justify mirror)
			)
		)
		(property "Value" "SC27P50V2GN-GP"
			(at -1.8923 -1.2065 180)
			(unlocked yes)
			(layer "B.Fab")
			(hide yes)
			(effects
				(font
					(size 1.016 1.016)
					(thickness 0.1524)
				)
				(justify mirror)
			)
		)
		(property "Device Type" "C402H22"
			(at -1.8923 -2.7305 180)
			(unlocked yes)
			(layer "B.Fab")
			(hide yes)
			(effects
				(font
					(size 1.016 1.016)
					(thickness 0.1524)
				)
				(justify mirror)
			)
		)
		(duplicate_pad_numbers_are_jumpers no)
		(fp_rect
			(start 0.381 0.7366)
			(end -0.381 -0.7366)
			(stroke
				(width 0)
				(type default)
			)
			(fill no)
			(layer "B.CrtYd")
		)
		(fp_rect
			(start 0.381 0.7366)
			(end -0.381 -0.7366)
			(stroke
				(width 0)
				(type default)
			)
			(fill no)
			(layer "B.Fab")
		)
		(pad "1" smd custom
			(at 0 -0.4572)
			(size 0.1143 0.1143)
			(layers "B.Cu" "B.Mask" "B.Paste")
			(net "XTAL_CLK_GEN_IN")
			(options
				(clearance outline)
				(anchor circle)
			)
			(primitives
				(gr_poly
					(pts
						(arc
							(start -0.254 0.1778)
							(mid -0.239121 0.213721)
							(end -0.2032 0.2286)
						)
						(arc
							(start 0.2032 0.2286)
							(mid 0.239121 0.213721)
							(end 0.254 0.1778)
						)
						(arc
							(start 0.254 -0.1778)
							(mid 0.239121 -0.213721)
							(end 0.2032 -0.2286)
						)
						(arc
							(start -0.2032 -0.2286)
							(mid -0.239121 -0.213721)
							(end -0.254 -0.1778)
						)
					)
					(width 0)
					(fill yes)
				)
			)
		)
		(pad "2" smd custom
			(at 0 0.4572)
			(size 0.1143 0.1143)
			(layers "B.Cu" "B.Mask" "B.Paste")
			(net "GND")
			(options
				(clearance outline)
				(anchor circle)
			)
			(primitives
				(gr_poly
					(pts
						(arc
							(start -0.254 0.1778)
							(mid -0.239121 0.213721)
							(end -0.2032 0.2286)
						)
						(arc
							(start 0.2032 0.2286)
							(mid 0.239121 0.213721)
							(end 0.254 0.1778)
						)
						(arc
							(start 0.254 -0.1778)
							(mid 0.239121 -0.213721)
							(end 0.2032 -0.2286)
						)
						(arc
							(start -0.2032 -0.2286)
							(mid -0.239121 -0.213721)
							(end -0.254 -0.1778)
						)
					)
					(width 0)
					(fill yes)
				)
			)
		)
	)
	(footprint ""
		(layer "B.Cu")
		(at 130.429 -32.004 90)
		(property "Reference" "C139"
			(at 0 0 90)
			(layer "B.SilkS")
			(hide yes)
			(effects
				(font
					(size 1.27 1.27)
				)
				(justify mirror)
			)
		)
		(property "Value" "SCD1U10V2KX-5GP"
			(at -1.1811 -2.7051 90)
			(unlocked yes)
			(layer "B.Fab")
			(hide yes)
			(effects
				(font
					(size 1.016 1.016)
					(thickness 0.1524)
				)
				(justify mirror)
			)
		)
		(property "Device Type" "C402H22"
			(at -1.1811 -4.2291 90)
			(unlocked yes)
			(layer "B.Fab")
			(hide yes)
			(effects
				(font
					(size 1.016 1.016)
					(thickness 0.1524)
				)
				(justify mirror)
			)
		)
		(duplicate_pad_numbers_are_jumpers no)
		(fp_rect
			(start 0.381 0.7366)
			(end -0.381 -0.7366)
			(stroke
				(width 0)
				(type default)
			)
			(fill no)
			(layer "B.CrtYd")
		)
		(fp_rect
			(start 0.381 0.7366)
			(end -0.381 -0.7366)
			(stroke
				(width 0)
				(type default)
			)
			(fill no)
			(layer "B.Fab")
		)
		(pad "1" smd custom
			(at 0 -0.4572 270)
			(size 0.1143 0.1143)
			(layers "B.Cu" "B.Mask" "B.Paste")
			(net "P3V3_STBY")
			(options
				(clearance outline)
				(anchor circle)
			)
			(primitives
				(gr_poly
					(pts
						(arc
							(start -0.254 0.1778)
							(mid -0.239121 0.213721)
							(end -0.2032 0.2286)
						)
						(arc
							(start 0.2032 0.2286)
							(mid 0.239121 0.213721)
							(end 0.254 0.1778)
						)
						(arc
							(start 0.254 -0.1778)
							(mid 0.239121 -0.213721)
							(end 0.2032 -0.2286)
						)
						(arc
							(start -0.2032 -0.2286)
							(mid -0.239121 -0.213721)
							(end -0.254 -0.1778)
						)
					)
					(width 0)
					(fill yes)
				)
			)
		)
		(pad "2" smd custom
			(at 0 0.4572 270)
			(size 0.1143 0.1143)
			(layers "B.Cu" "B.Mask" "B.Paste")
			(net "GND")
			(options
				(clearance outline)
				(anchor circle)
			)
			(primitives
				(gr_poly
					(pts
						(arc
							(start -0.254 0.1778)
							(mid -0.239121 0.213721)
							(end -0.2032 0.2286)
						)
						(arc
							(start 0.2032 0.2286)
							(mid 0.239121 0.213721)
							(end 0.254 0.1778)
						)
						(arc
							(start 0.254 -0.1778)
							(mid 0.239121 -0.213721)
							(end 0.2032 -0.2286)
						)
						(arc
							(start -0.2032 -0.2286)
							(mid -0.239121 -0.213721)
							(end -0.254 -0.1778)
						)
					)
					(width 0)
					(fill yes)
				)
			)
		)
	)
	(footprint ""
		(layer "B.Cu")
		(at 76.835 -16.3576 -90)
		(property "Reference" "PC200"
			(at 0 0 90)
			(layer "B.SilkS")
			(hide yes)
			(effects
				(font
					(size 1.27 1.27)
				)
				(justify mirror)
			)
		)
		(property "Value" "SC10U6D3V5KX-4GP"
			(at 0.0762 -6.1214 270)
			(unlocked yes)
			(layer "B.Fab")
			(hide yes)
			(effects
				(font
					(size 1.016 1.016)
					(thickness 0.1524)
				)
				(justify mirror)
			)
		)
		(property "Device Type" "C805H58"
			(at 0.0762 -8.1534 270)
			(unlocked yes)
			(layer "B.Fab")
			(hide yes)
			(effects
				(font
					(size 1.016 1.016)
					(thickness 0.1524)
				)
				(justify mirror)
			)
		)
		(duplicate_pad_numbers_are_jumpers no)
		(fp_line
			(start -0.6096 0)
			(end 0.6096 0)
			(stroke
				(width 0.3048)
				(type default)
			)
			(layer "B.SilkS")
		)
		(fp_poly
			(pts
				(xy 0.9017 1.4351) (xy -0.9017 1.4351) (xy -0.9017 -1.4351) (xy 0.9017 -1.4351)
			)
			(stroke
				(width 0)
				(type default)
			)
			(fill no)
			(layer "B.CrtYd")
		)
		(fp_poly
			(pts
				(xy -0.9017 1.4351) (xy -0.9017 -1.4351) (xy 0.9017 -1.4351) (xy 0.9017 1.4351)
			)
			(stroke
				(width 0)
				(type default)
			)
			(fill no)
			(layer "B.Fab")
		)
		(pad "1" smd rect
			(at 0 -0.8382 90)
			(size 1.5494 0.9398)
			(layers "B.Cu" "B.Mask" "B.Paste")
			(net "TPS74801_P1V35_IN")
		)
		(pad "2" smd rect
			(at 0 0.8382 90)
			(size 1.5494 0.9398)
			(layers "B.Cu" "B.Mask" "B.Paste")
			(net "GND")
		)
	)
	(footprint ""
		(layer "B.Cu")
		(at 27.686 -32.385 180)
		(property "Reference" "PC42"
			(at 0 0 0)
			(layer "B.SilkS")
			(hide yes)
			(effects
				(font
					(size 1.27 1.27)
				)
				(justify mirror)
			)
		)
		(property "Value" "SC22U6D3V3MX-1-GP"
			(at 0.0254 -2.0193 180)
			(unlocked yes)
			(layer "B.Fab")
			(hide yes)
			(effects
				(font
					(size 1.016 1.016)
					(thickness 0.1524)
				)
				(justify mirror)
			)
		)
		(property "Device Type" "C603H40"
			(at 0.0254 -3.5433 180)
			(unlocked yes)
			(layer "B.Fab")
			(hide yes)
			(effects
				(font
					(size 1.016 1.016)
					(thickness 0.1524)
				)
				(justify mirror)
			)
		)
		(duplicate_pad_numbers_are_jumpers no)
		(fp_line
			(start 0.4064 0)
			(end -0.4064 0)
			(stroke
				(width 0.2286)
				(type default)
			)
			(layer "B.SilkS")
		)
		(fp_rect
			(start 0.635 1.1811)
			(end -0.635 -1.1811)
			(stroke
				(width 0)
				(type default)
			)
			(fill no)
			(layer "B.CrtYd")
		)
		(fp_rect
			(start 0.635 1.1811)
			(end -0.635 -1.1811)
			(stroke
				(width 0)
				(type default)
			)
			(fill no)
			(layer "B.Fab")
		)
		(pad "1" smd custom
			(at 0 -0.6604)
			(size 0.19685 0.19685)
			(layers "B.Cu" "B.Mask" "B.Paste")
			(net "P1V0")
			(options
				(clearance outline)
				(anchor circle)
			)
			(primitives
				(gr_poly
					(pts
						(arc
							(start 0.508 0.2921)
							(mid 0.478242 0.363942)
							(end 0.4064 0.3937)
						)
						(arc
							(start -0.4064 0.3937)
							(mid -0.478242 0.363942)
							(end -0.508 0.2921)
						)
						(arc
							(start -0.508 -0.2921)
							(mid -0.478242 -0.363942)
							(end -0.4064 -0.3937)
						)
						(arc
							(start 0.4064 -0.3937)
							(mid 0.478242 -0.363942)
							(end 0.508 -0.2921)
						)
					)
					(width 0)
					(fill yes)
				)
			)
		)
		(pad "2" smd custom
			(at 0 0.6604)
			(size 0.19685 0.19685)
			(layers "B.Cu" "B.Mask" "B.Paste")
			(net "GND")
			(options
				(clearance outline)
				(anchor circle)
			)
			(primitives
				(gr_poly
					(pts
						(arc
							(start 0.508 0.2921)
							(mid 0.478242 0.363942)
							(end 0.4064 0.3937)
						)
						(arc
							(start -0.4064 0.3937)
							(mid -0.478242 0.363942)
							(end -0.508 0.2921)
						)
						(arc
							(start -0.508 -0.2921)
							(mid -0.478242 -0.363942)
							(end -0.4064 -0.3937)
						)
						(arc
							(start 0.4064 -0.3937)
							(mid 0.478242 -0.363942)
							(end 0.508 -0.2921)
						)
					)
					(width 0)
					(fill yes)
				)
			)
		)
	)
	(footprint ""
		(layer "B.Cu")
		(at 129.54 -59.944)
		(property "Reference" "R228"
			(at 0 0 0)
			(layer "B.SilkS")
			(hide yes)
			(effects
				(font
					(size 1.27 1.27)
				)
				(justify mirror)
			)
		)
		(property "Value" "4K7R2F-GP"
			(at -0.064008 -3.993896 0)
			(unlocked yes)
			(layer "B.Fab")
			(hide yes)
			(effects
				(font
					(size 1.016 1.016)
					(thickness 0.1524)
				)
				(justify mirror)
			)
		)
		(property "Device Type" "R402H16"
			(at -0.064008 -5.517896 0)
			(unlocked yes)
			(layer "B.Fab")
			(hide yes)
			(effects
				(font
					(size 1.016 1.016)
					(thickness 0.1524)
				)
				(justify mirror)
			)
		)
		(duplicate_pad_numbers_are_jumpers no)
		(fp_rect
			(start 0.381 0.8382)
			(end -0.381 -0.8382)
			(stroke
				(width 0)
				(type default)
			)
			(fill no)
			(layer "B.CrtYd")
		)
		(fp_rect
			(start 0.381 0.8382)
			(end -0.381 -0.8382)
			(stroke
				(width 0)
				(type default)
			)
			(fill no)
			(layer "B.Fab")
		)
		(pad "1" smd custom
			(at 0 -0.4318 180)
			(size 0.127 0.127)
			(layers "B.Cu" "B.Mask" "B.Paste")
			(net "CHA_0_SA1")
			(options
				(clearance outline)
				(anchor circle)
			)
			(primitives
				(gr_poly
					(pts
						(arc
							(start -0.2032 0.2794)
							(mid -0.239121 0.264521)
							(end -0.254 0.2286)
						)
						(arc
							(start -0.254 -0.2286)
							(mid -0.239121 -0.264521)
							(end -0.2032 -0.2794)
						)
						(arc
							(start 0.2032 -0.2794)
							(mid 0.239121 -0.264521)
							(end 0.254 -0.2286)
						)
						(arc
							(start 0.254 0.2286)
							(mid 0.239121 0.264521)
							(end 0.2032 0.2794)
						)
					)
					(width 0)
					(fill yes)
				)
			)
		)
		(pad "2" smd custom
			(at 0 0.4318 180)
			(size 0.127 0.127)
			(layers "B.Cu" "B.Mask" "B.Paste")
			(net "GND")
			(options
				(clearance outline)
				(anchor circle)
			)
			(primitives
				(gr_poly
					(pts
						(arc
							(start -0.2032 0.2794)
							(mid -0.239121 0.264521)
							(end -0.254 0.2286)
						)
						(arc
							(start -0.254 -0.2286)
							(mid -0.239121 -0.264521)
							(end -0.2032 -0.2794)
						)
						(arc
							(start 0.2032 -0.2794)
							(mid 0.239121 -0.264521)
							(end 0.254 -0.2286)
						)
						(arc
							(start 0.254 0.2286)
							(mid 0.239121 0.264521)
							(end 0.2032 0.2794)
						)
					)
					(width 0)
					(fill yes)
				)
			)
		)
	)
	(footprint ""
		(layer "B.Cu")
		(at 36.957 -49.403 90)
		(property "Reference" "R137"
			(at 0 0 90)
			(layer "B.SilkS")
			(hide yes)
			(effects
				(font
					(size 1.27 1.27)
				)
				(justify mirror)
			)
		)
		(property "Value" "10KR2F-2-GP"
			(at -1.7907 -1.1176 90)
			(unlocked yes)
			(layer "B.Fab")
			(hide yes)
			(effects
				(font
					(size 1.016 1.016)
					(thickness 0.1524)
				)
				(justify mirror)
			)
		)
		(property "Device Type" "R402H16"
			(at -1.7907 -2.6416 90)
			(unlocked yes)
			(layer "B.Fab")
			(hide yes)
			(effects
				(font
					(size 1.016 1.016)
					(thickness 0.1524)
				)
				(justify mirror)
			)
		)
		(duplicate_pad_numbers_are_jumpers no)
		(fp_rect
			(start 0.381 0.8382)
			(end -0.381 -0.8382)
			(stroke
				(width 0)
				(type default)
			)
			(fill no)
			(layer "B.CrtYd")
		)
		(fp_rect
			(start 0.381 0.8382)
			(end -0.381 -0.8382)
			(stroke
				(width 0)
				(type default)
			)
			(fill no)
			(layer "B.Fab")
		)
		(pad "1" smd custom
			(at 0 -0.4318 270)
			(size 0.127 0.127)
			(layers "B.Cu" "B.Mask" "B.Paste")
			(net "P3V3_STBY")
			(options
				(clearance outline)
				(anchor circle)
			)
			(primitives
				(gr_poly
					(pts
						(arc
							(start -0.2032 0.2794)
							(mid -0.239121 0.264521)
							(end -0.254 0.2286)
						)
						(arc
							(start -0.254 -0.2286)
							(mid -0.239121 -0.264521)
							(end -0.2032 -0.2794)
						)
						(arc
							(start 0.2032 -0.2794)
							(mid 0.239121 -0.264521)
							(end 0.254 -0.2286)
						)
						(arc
							(start 0.254 0.2286)
							(mid 0.239121 0.264521)
							(end 0.2032 0.2794)
						)
					)
					(width 0)
					(fill yes)
				)
			)
		)
		(pad "2" smd custom
			(at 0 0.4318 270)
			(size 0.127 0.127)
			(layers "B.Cu" "B.Mask" "B.Paste")
			(net "CLK_14M_CPU")
			(options
				(clearance outline)
				(anchor circle)
			)
			(primitives
				(gr_poly
					(pts
						(arc
							(start -0.2032 0.2794)
							(mid -0.239121 0.264521)
							(end -0.254 0.2286)
						)
						(arc
							(start -0.254 -0.2286)
							(mid -0.239121 -0.264521)
							(end -0.2032 -0.2794)
						)
						(arc
							(start 0.2032 -0.2794)
							(mid 0.239121 -0.264521)
							(end 0.254 -0.2286)
						)
						(arc
							(start 0.254 0.2286)
							(mid 0.239121 0.264521)
							(end 0.2032 0.2794)
						)
					)
					(width 0)
					(fill yes)
				)
			)
		)
	)
	(footprint ""
		(layer "B.Cu")
		(at 82.5754 -27.4828 180)
		(property "Reference" "R406"
			(at 0 0 0)
			(layer "B.SilkS")
			(hide yes)
			(effects
				(font
					(size 1.27 1.27)
				)
				(justify mirror)
			)
		)
		(property "Value" "1KR2F-3-GP"
			(at -1.7907 -1.1176 180)
			(unlocked yes)
			(layer "B.Fab")
			(hide yes)
			(effects
				(font
					(size 1.016 1.016)
					(thickness 0.1524)
				)
				(justify mirror)
			)
		)
		(property "Device Type" "R402H16"
			(at -1.7907 -2.6416 180)
			(unlocked yes)
			(layer "B.Fab")
			(hide yes)
			(effects
				(font
					(size 1.016 1.016)
					(thickness 0.1524)
				)
				(justify mirror)
			)
		)
		(duplicate_pad_numbers_are_jumpers no)
		(fp_rect
			(start 0.381 0.8382)
			(end -0.381 -0.8382)
			(stroke
				(width 0)
				(type default)
			)
			(fill no)
			(layer "B.CrtYd")
		)
		(fp_rect
			(start 0.381 0.8382)
			(end -0.381 -0.8382)
			(stroke
				(width 0)
				(type default)
			)
			(fill no)
			(layer "B.Fab")
		)
		(pad "1" smd custom
			(at 0 -0.4318)
			(size 0.127 0.127)
			(layers "B.Cu" "B.Mask" "B.Paste")
			(net "BD_REV_2")
			(options
				(clearance outline)
				(anchor circle)
			)
			(primitives
				(gr_poly
					(pts
						(arc
							(start -0.2032 0.2794)
							(mid -0.239121 0.264521)
							(end -0.254 0.2286)
						)
						(arc
							(start -0.254 -0.2286)
							(mid -0.239121 -0.264521)
							(end -0.2032 -0.2794)
						)
						(arc
							(start 0.2032 -0.2794)
							(mid 0.239121 -0.264521)
							(end 0.254 -0.2286)
						)
						(arc
							(start 0.254 0.2286)
							(mid 0.239121 0.264521)
							(end 0.2032 0.2794)
						)
					)
					(width 0)
					(fill yes)
				)
			)
		)
		(pad "2" smd custom
			(at 0 0.4318)
			(size 0.127 0.127)
			(layers "B.Cu" "B.Mask" "B.Paste")
			(net "GND")
			(options
				(clearance outline)
				(anchor circle)
			)
			(primitives
				(gr_poly
					(pts
						(arc
							(start -0.2032 0.2794)
							(mid -0.239121 0.264521)
							(end -0.254 0.2286)
						)
						(arc
							(start -0.254 -0.2286)
							(mid -0.239121 -0.264521)
							(end -0.2032 -0.2794)
						)
						(arc
							(start 0.2032 -0.2794)
							(mid 0.239121 -0.264521)
							(end 0.254 -0.2286)
						)
						(arc
							(start 0.254 0.2286)
							(mid 0.239121 0.264521)
							(end 0.2032 0.2794)
						)
					)
					(width 0)
					(fill yes)
				)
			)
		)
	)
	(footprint ""
		(layer "B.Cu")
		(at 53.467 -18.034 -90)
		(property "Reference" "C302"
			(at 0 0 90)
			(layer "B.SilkS")
			(hide yes)
			(effects
				(font
					(size 1.27 1.27)
				)
				(justify mirror)
			)
		)
		(property "Value" "SC1U6D3V2KX-GP"
			(at -1.8923 -1.2065 270)
			(unlocked yes)
			(layer "B.Fab")
			(hide yes)
			(effects
				(font
					(size 1.016 1.016)
					(thickness 0.1524)
				)
				(justify mirror)
			)
		)
		(property "Device Type" "C402H22"
			(at -1.8923 -2.7305 270)
			(unlocked yes)
			(layer "B.Fab")
			(hide yes)
			(effects
				(font
					(size 1.016 1.016)
					(thickness 0.1524)
				)
				(justify mirror)
			)
		)
		(duplicate_pad_numbers_are_jumpers no)
		(fp_rect
			(start 0.381 0.7366)
			(end -0.381 -0.7366)
			(stroke
				(width 0)
				(type default)
			)
			(fill no)
			(layer "B.CrtYd")
		)
		(fp_rect
			(start 0.381 0.7366)
			(end -0.381 -0.7366)
			(stroke
				(width 0)
				(type default)
			)
			(fill no)
			(layer "B.Fab")
		)
		(pad "1" smd custom
			(at 0 -0.4572 90)
			(size 0.1143 0.1143)
			(layers "B.Cu" "B.Mask" "B.Paste")
			(net "P3V3")
			(options
				(clearance outline)
				(anchor circle)
			)
			(primitives
				(gr_poly
					(pts
						(arc
							(start -0.254 0.1778)
							(mid -0.239121 0.213721)
							(end -0.2032 0.2286)
						)
						(arc
							(start 0.2032 0.2286)
							(mid 0.239121 0.213721)
							(end 0.254 0.1778)
						)
						(arc
							(start 0.254 -0.1778)
							(mid 0.239121 -0.213721)
							(end 0.2032 -0.2286)
						)
						(arc
							(start -0.2032 -0.2286)
							(mid -0.239121 -0.213721)
							(end -0.254 -0.1778)
						)
					)
					(width 0)
					(fill yes)
				)
			)
		)
		(pad "2" smd custom
			(at 0 0.4572 90)
			(size 0.1143 0.1143)
			(layers "B.Cu" "B.Mask" "B.Paste")
			(net "GND")
			(options
				(clearance outline)
				(anchor circle)
			)
			(primitives
				(gr_poly
					(pts
						(arc
							(start -0.254 0.1778)
							(mid -0.239121 0.213721)
							(end -0.2032 0.2286)
						)
						(arc
							(start 0.2032 0.2286)
							(mid 0.239121 0.213721)
							(end 0.254 0.1778)
						)
						(arc
							(start 0.254 -0.1778)
							(mid 0.239121 -0.213721)
							(end 0.2032 -0.2286)
						)
						(arc
							(start -0.2032 -0.2286)
							(mid -0.239121 -0.213721)
							(end -0.254 -0.1778)
						)
					)
					(width 0)
					(fill yes)
				)
			)
		)
	)
	(footprint ""
		(layer "B.Cu")
		(at 201.295 -41.3258 90)
		(property "Reference" "LED11"
			(at 0 0 90)
			(layer "B.SilkS")
			(hide yes)
			(effects
				(font
					(size 1.27 1.27)
				)
				(justify mirror)
			)
		)
		(property "Value" "LED-YG-51-GP"
			(at 0.0381 -2.6162 90)
			(unlocked yes)
			(layer "B.Fab")
			(hide yes)
			(effects
				(font
					(size 1.016 1.016)
					(thickness 0.1524)
				)
				(justify mirror)
			)
		)
		(property "Device Type" "LED1608AKH40"
			(at 0.0381 -4.1402 90)
			(unlocked yes)
			(layer "B.Fab")
			(hide yes)
			(effects
				(font
					(size 1.016 1.016)
					(thickness 0.1524)
				)
				(justify mirror)
			)
		)
		(duplicate_pad_numbers_are_jumpers no)
		(fp_line
			(start 0.5334 1.3081)
			(end -0.5334 1.3081)
			(stroke
				(width 0.254)
				(type default)
			)
			(layer "B.SilkS")
		)
		(fp_rect
			(start 0.6604 1.1811)
			(end -0.6604 -1.1811)
			(stroke
				(width 0)
				(type default)
			)
			(fill no)
			(layer "B.CrtYd")
		)
		(fp_rect
			(start 0.6604 1.1811)
			(end -0.6604 -1.1811)
			(stroke
				(width 0)
				(type default)
			)
			(fill no)
			(layer "B.Fab")
		)
		(pad "A" smd rect
			(at 0 -0.652526 270)
			(size 1.0668 0.8128)
			(layers "B.Cu" "B.Mask" "B.Paste")
			(net "PORT80_R_BIT6")
		)
		(pad "K" smd rect
			(at 0 0.652526 270)
			(size 1.0668 0.8128)
			(layers "B.Cu" "B.Mask" "B.Paste")
			(net "PORT80_BIT6")
		)
	)
	(footprint ""
		(layer "B.Cu")
		(at 184.2008 -30.0228 180)
		(property "Reference" "PR214"
			(at 0 0 0)
			(layer "B.SilkS")
			(hide yes)
			(effects
				(font
					(size 1.27 1.27)
				)
				(justify mirror)
			)
		)
		(property "Value" "100R2F-L1-GP-U"
			(at -1.7907 -1.1176 180)
			(unlocked yes)
			(layer "B.Fab")
			(hide yes)
			(effects
				(font
					(size 1.016 1.016)
					(thickness 0.1524)
				)
				(justify mirror)
			)
		)
		(property "Device Type" "R402H14"
			(at -1.7907 -2.6416 180)
			(unlocked yes)
			(layer "B.Fab")
			(hide yes)
			(effects
				(font
					(size 1.016 1.016)
					(thickness 0.1524)
				)
				(justify mirror)
			)
		)
		(duplicate_pad_numbers_are_jumpers no)
		(fp_rect
			(start 0.381 0.8382)
			(end -0.381 -0.8382)
			(stroke
				(width 0)
				(type default)
			)
			(fill no)
			(layer "B.CrtYd")
		)
		(fp_rect
			(start 0.381 0.8382)
			(end -0.381 -0.8382)
			(stroke
				(width 0)
				(type default)
			)
			(fill no)
			(layer "B.Fab")
		)
		(pad "1" smd custom
			(at 0 -0.4318)
			(size 0.127 0.127)
			(layers "B.Cu" "B.Mask" "B.Paste")
			(net "VR_PVDDR_A_VSEN")
			(options
				(clearance outline)
				(anchor circle)
			)
			(primitives
				(gr_poly
					(pts
						(arc
							(start -0.2032 0.2794)
							(mid -0.239121 0.264521)
							(end -0.254 0.2286)
						)
						(arc
							(start -0.254 -0.2286)
							(mid -0.239121 -0.264521)
							(end -0.2032 -0.2794)
						)
						(arc
							(start 0.2032 -0.2794)
							(mid 0.239121 -0.264521)
							(end 0.254 -0.2286)
						)
						(arc
							(start 0.254 0.2286)
							(mid 0.239121 0.264521)
							(end 0.2032 0.2794)
						)
					)
					(width 0)
					(fill yes)
				)
			)
		)
		(pad "2" smd custom
			(at 0 0.4318)
			(size 0.127 0.127)
			(layers "B.Cu" "B.Mask" "B.Paste")
			(net "VR_PVDDR_A_FB")
			(options
				(clearance outline)
				(anchor circle)
			)
			(primitives
				(gr_poly
					(pts
						(arc
							(start -0.2032 0.2794)
							(mid -0.239121 0.264521)
							(end -0.254 0.2286)
						)
						(arc
							(start -0.254 -0.2286)
							(mid -0.239121 -0.264521)
							(end -0.2032 -0.2794)
						)
						(arc
							(start 0.2032 -0.2794)
							(mid 0.239121 -0.264521)
							(end 0.254 -0.2286)
						)
						(arc
							(start 0.254 0.2286)
							(mid 0.239121 0.264521)
							(end 0.2032 0.2794)
						)
					)
					(width 0)
					(fill yes)
				)
			)
		)
	)
	(footprint ""
		(layer "B.Cu")
		(at 129.921 -11.812778 90)
		(property "Reference" "C354"
			(at 0 0 90)
			(layer "B.SilkS")
			(hide yes)
			(effects
				(font
					(size 1.27 1.27)
				)
				(justify mirror)
			)
		)
		(property "Value" "SC1U6D3V3KX-2GP"
			(at 0.0254 -2.0193 90)
			(unlocked yes)
			(layer "B.Fab")
			(hide yes)
			(effects
				(font
					(size 1.016 1.016)
					(thickness 0.1524)
				)
				(justify mirror)
			)
		)
		(property "Device Type" "C603H36"
			(at 0.0254 -3.5433 90)
			(unlocked yes)
			(layer "B.Fab")
			(hide yes)
			(effects
				(font
					(size 1.016 1.016)
					(thickness 0.1524)
				)
				(justify mirror)
			)
		)
		(duplicate_pad_numbers_are_jumpers no)
		(fp_rect
			(start 0.635 1.1811)
			(end -0.635 -1.1811)
			(stroke
				(width 0)
				(type default)
			)
			(fill no)
			(layer "B.CrtYd")
		)
		(fp_rect
			(start 0.635 1.1811)
			(end -0.635 -1.1811)
			(stroke
				(width 0)
				(type default)
			)
			(fill no)
			(layer "B.Fab")
		)
		(pad "1" smd custom
			(at 0 -0.6604 270)
			(size 0.19685 0.19685)
			(layers "B.Cu" "B.Mask" "B.Paste")
			(net "DDR3_M_B_VREF_DQ0")
			(options
				(clearance outline)
				(anchor circle)
			)
			(primitives
				(gr_poly
					(pts
						(arc
							(start 0.508 0.2921)
							(mid 0.478242 0.363942)
							(end 0.4064 0.3937)
						)
						(arc
							(start -0.4064 0.3937)
							(mid -0.478242 0.363942)
							(end -0.508 0.2921)
						)
						(arc
							(start -0.508 -0.2921)
							(mid -0.478242 -0.363942)
							(end -0.4064 -0.3937)
						)
						(arc
							(start 0.4064 -0.3937)
							(mid 0.478242 -0.363942)
							(end 0.508 -0.2921)
						)
					)
					(width 0)
					(fill yes)
				)
			)
		)
		(pad "2" smd custom
			(at 0 0.6604 270)
			(size 0.19685 0.19685)
			(layers "B.Cu" "B.Mask" "B.Paste")
			(net "GND")
			(options
				(clearance outline)
				(anchor circle)
			)
			(primitives
				(gr_poly
					(pts
						(arc
							(start 0.508 0.2921)
							(mid 0.478242 0.363942)
							(end 0.4064 0.3937)
						)
						(arc
							(start -0.4064 0.3937)
							(mid -0.478242 0.363942)
							(end -0.508 0.2921)
						)
						(arc
							(start -0.508 -0.2921)
							(mid -0.478242 -0.363942)
							(end -0.4064 -0.3937)
						)
						(arc
							(start 0.4064 -0.3937)
							(mid 0.478242 -0.363942)
							(end 0.508 -0.2921)
						)
					)
					(width 0)
					(fill yes)
				)
			)
		)
	)
	(footprint ""
		(layer "B.Cu")
		(at 100.709984 -27.321002)
		(property "Reference" "R374"
			(at 0 0 0)
			(layer "B.SilkS")
			(hide yes)
			(effects
				(font
					(size 1.27 1.27)
				)
				(justify mirror)
			)
		)
		(property "Value" "100R2F-L1-GP-U"
			(at -0.064008 -3.993896 0)
			(unlocked yes)
			(layer "B.Fab")
			(hide yes)
			(effects
				(font
					(size 1.016 1.016)
					(thickness 0.1524)
				)
				(justify mirror)
			)
		)
		(property "Device Type" "R402H14"
			(at -0.064008 -5.517896 0)
			(unlocked yes)
			(layer "B.Fab")
			(hide yes)
			(effects
				(font
					(size 1.016 1.016)
					(thickness 0.1524)
				)
				(justify mirror)
			)
		)
		(duplicate_pad_numbers_are_jumpers no)
		(fp_rect
			(start 0.381 0.8382)
			(end -0.381 -0.8382)
			(stroke
				(width 0)
				(type default)
			)
			(fill no)
			(layer "B.CrtYd")
		)
		(fp_rect
			(start 0.381 0.8382)
			(end -0.381 -0.8382)
			(stroke
				(width 0)
				(type default)
			)
			(fill no)
			(layer "B.Fab")
		)
		(pad "1" smd custom
			(at 0 -0.4318 180)
			(size 0.127 0.127)
			(layers "B.Cu" "B.Mask" "B.Paste")
			(net "M_B_VREF")
			(options
				(clearance outline)
				(anchor circle)
			)
			(primitives
				(gr_poly
					(pts
						(arc
							(start -0.2032 0.2794)
							(mid -0.239121 0.264521)
							(end -0.254 0.2286)
						)
						(arc
							(start -0.254 -0.2286)
							(mid -0.239121 -0.264521)
							(end -0.2032 -0.2794)
						)
						(arc
							(start 0.2032 -0.2794)
							(mid 0.239121 -0.264521)
							(end 0.254 -0.2286)
						)
						(arc
							(start 0.254 0.2286)
							(mid 0.239121 0.264521)
							(end 0.2032 0.2794)
						)
					)
					(width 0)
					(fill yes)
				)
			)
		)
		(pad "2" smd custom
			(at 0 0.4318 180)
			(size 0.127 0.127)
			(layers "B.Cu" "B.Mask" "B.Paste")
			(net "GND")
			(options
				(clearance outline)
				(anchor circle)
			)
			(primitives
				(gr_poly
					(pts
						(arc
							(start -0.2032 0.2794)
							(mid -0.239121 0.264521)
							(end -0.254 0.2286)
						)
						(arc
							(start -0.254 -0.2286)
							(mid -0.239121 -0.264521)
							(end -0.2032 -0.2794)
						)
						(arc
							(start 0.2032 -0.2794)
							(mid 0.239121 -0.264521)
							(end 0.254 -0.2286)
						)
						(arc
							(start 0.254 0.2286)
							(mid 0.239121 0.264521)
							(end 0.2032 0.2794)
						)
					)
					(width 0)
					(fill yes)
				)
			)
		)
	)
	(footprint ""
		(layer "B.Cu")
		(at 25.4635 -12.7)
		(property "Reference" "C273"
			(at 0 0 0)
			(layer "B.SilkS")
			(hide yes)
			(effects
				(font
					(size 1.27 1.27)
				)
				(justify mirror)
			)
		)
		(property "Value" "SCD1U16V2KX-3GP"
			(at -1.1811 -2.7051 0)
			(unlocked yes)
			(layer "B.Fab")
			(hide yes)
			(effects
				(font
					(size 1.016 1.016)
					(thickness 0.1524)
				)
				(justify mirror)
			)
		)
		(property "Device Type" "C402H22"
			(at -1.1811 -4.2291 0)
			(unlocked yes)
			(layer "B.Fab")
			(hide yes)
			(effects
				(font
					(size 1.016 1.016)
					(thickness 0.1524)
				)
				(justify mirror)
			)
		)
		(duplicate_pad_numbers_are_jumpers no)
		(fp_rect
			(start 0.381 0.7366)
			(end -0.381 -0.7366)
			(stroke
				(width 0)
				(type default)
			)
			(fill no)
			(layer "B.CrtYd")
		)
		(fp_rect
			(start 0.381 0.7366)
			(end -0.381 -0.7366)
			(stroke
				(width 0)
				(type default)
			)
			(fill no)
			(layer "B.Fab")
		)
		(pad "1" smd custom
			(at 0 -0.4572 180)
			(size 0.1143 0.1143)
			(layers "B.Cu" "B.Mask" "B.Paste")
			(net "P2E_CPU_ETH10G_C_TX_DN9")
			(options
				(clearance outline)
				(anchor circle)
			)
			(primitives
				(gr_poly
					(pts
						(arc
							(start -0.254 0.1778)
							(mid -0.239121 0.213721)
							(end -0.2032 0.2286)
						)
						(arc
							(start 0.2032 0.2286)
							(mid 0.239121 0.213721)
							(end 0.254 0.1778)
						)
						(arc
							(start 0.254 -0.1778)
							(mid 0.239121 -0.213721)
							(end 0.2032 -0.2286)
						)
						(arc
							(start -0.2032 -0.2286)
							(mid -0.239121 -0.213721)
							(end -0.254 -0.1778)
						)
					)
					(width 0)
					(fill yes)
				)
			)
		)
		(pad "2" smd custom
			(at 0 0.4572 180)
			(size 0.1143 0.1143)
			(layers "B.Cu" "B.Mask" "B.Paste")
			(net "P2E_CPU_ETH10G_TX_DN9")
			(options
				(clearance outline)
				(anchor circle)
			)
			(primitives
				(gr_poly
					(pts
						(arc
							(start -0.254 0.1778)
							(mid -0.239121 0.213721)
							(end -0.2032 0.2286)
						)
						(arc
							(start 0.2032 0.2286)
							(mid 0.239121 0.213721)
							(end 0.254 0.1778)
						)
						(arc
							(start 0.254 -0.1778)
							(mid 0.239121 -0.213721)
							(end 0.2032 -0.2286)
						)
						(arc
							(start -0.2032 -0.2286)
							(mid -0.239121 -0.213721)
							(end -0.254 -0.1778)
						)
					)
					(width 0)
					(fill yes)
				)
			)
		)
	)
	(footprint ""
		(layer "B.Cu")
		(at 129.921 -12.828778 90)
		(property "Reference" "C294"
			(at 0 0 90)
			(layer "B.SilkS")
			(hide yes)
			(effects
				(font
					(size 1.27 1.27)
				)
				(justify mirror)
			)
		)
		(property "Value" "SCD1U16V2KX-3GP"
			(at -1.1811 -2.7051 90)
			(unlocked yes)
			(layer "B.Fab")
			(hide yes)
			(effects
				(font
					(size 1.016 1.016)
					(thickness 0.1524)
				)
				(justify mirror)
			)
		)
		(property "Device Type" "C402H22"
			(at -1.1811 -4.2291 90)
			(unlocked yes)
			(layer "B.Fab")
			(hide yes)
			(effects
				(font
					(size 1.016 1.016)
					(thickness 0.1524)
				)
				(justify mirror)
			)
		)
		(duplicate_pad_numbers_are_jumpers no)
		(fp_rect
			(start 0.381 0.7366)
			(end -0.381 -0.7366)
			(stroke
				(width 0)
				(type default)
			)
			(fill no)
			(layer "B.CrtYd")
		)
		(fp_rect
			(start 0.381 0.7366)
			(end -0.381 -0.7366)
			(stroke
				(width 0)
				(type default)
			)
			(fill no)
			(layer "B.Fab")
		)
		(pad "1" smd custom
			(at 0 -0.4572 270)
			(size 0.1143 0.1143)
			(layers "B.Cu" "B.Mask" "B.Paste")
			(net "DDR3_M_B_VREF_DQ0")
			(options
				(clearance outline)
				(anchor circle)
			)
			(primitives
				(gr_poly
					(pts
						(arc
							(start -0.254 0.1778)
							(mid -0.239121 0.213721)
							(end -0.2032 0.2286)
						)
						(arc
							(start 0.2032 0.2286)
							(mid 0.239121 0.213721)
							(end 0.254 0.1778)
						)
						(arc
							(start 0.254 -0.1778)
							(mid 0.239121 -0.213721)
							(end 0.2032 -0.2286)
						)
						(arc
							(start -0.2032 -0.2286)
							(mid -0.239121 -0.213721)
							(end -0.254 -0.1778)
						)
					)
					(width 0)
					(fill yes)
				)
			)
		)
		(pad "2" smd custom
			(at 0 0.4572 270)
			(size 0.1143 0.1143)
			(layers "B.Cu" "B.Mask" "B.Paste")
			(net "GND")
			(options
				(clearance outline)
				(anchor circle)
			)
			(primitives
				(gr_poly
					(pts
						(arc
							(start -0.254 0.1778)
							(mid -0.239121 0.213721)
							(end -0.2032 0.2286)
						)
						(arc
							(start 0.2032 0.2286)
							(mid 0.239121 0.213721)
							(end 0.254 0.1778)
						)
						(arc
							(start 0.254 -0.1778)
							(mid 0.239121 -0.213721)
							(end 0.2032 -0.2286)
						)
						(arc
							(start -0.2032 -0.2286)
							(mid -0.239121 -0.213721)
							(end -0.254 -0.1778)
						)
					)
					(width 0)
					(fill yes)
				)
			)
		)
	)
	(footprint ""
		(layer "B.Cu")
		(at 103.254048 -35.620452 90)
		(property "Reference" "C205"
			(at 0 0 90)
			(layer "B.SilkS")
			(hide yes)
			(effects
				(font
					(size 1.27 1.27)
				)
				(justify mirror)
			)
		)
		(property "Value" "SC2D2U10V2KX-GP"
			(at -1.1811 -2.7051 90)
			(unlocked yes)
			(layer "B.Fab")
			(hide yes)
			(effects
				(font
					(size 1.016 1.016)
					(thickness 0.1524)
				)
				(justify mirror)
			)
		)
		(property "Device Type" "C402H22"
			(at -1.1811 -4.2291 90)
			(unlocked yes)
			(layer "B.Fab")
			(hide yes)
			(effects
				(font
					(size 1.016 1.016)
					(thickness 0.1524)
				)
				(justify mirror)
			)
		)
		(duplicate_pad_numbers_are_jumpers no)
		(fp_rect
			(start 0.381 0.7366)
			(end -0.381 -0.7366)
			(stroke
				(width 0)
				(type default)
			)
			(fill no)
			(layer "B.CrtYd")
		)
		(fp_rect
			(start 0.381 0.7366)
			(end -0.381 -0.7366)
			(stroke
				(width 0)
				(type default)
			)
			(fill no)
			(layer "B.Fab")
		)
		(pad "1" smd custom
			(at 0 -0.4572 270)
			(size 0.1143 0.1143)
			(layers "B.Cu" "B.Mask" "B.Paste")
			(net "P1V0")
			(options
				(clearance outline)
				(anchor circle)
			)
			(primitives
				(gr_poly
					(pts
						(arc
							(start -0.254 0.1778)
							(mid -0.239121 0.213721)
							(end -0.2032 0.2286)
						)
						(arc
							(start 0.2032 0.2286)
							(mid 0.239121 0.213721)
							(end 0.254 0.1778)
						)
						(arc
							(start 0.254 -0.1778)
							(mid 0.239121 -0.213721)
							(end 0.2032 -0.2286)
						)
						(arc
							(start -0.2032 -0.2286)
							(mid -0.239121 -0.213721)
							(end -0.254 -0.1778)
						)
					)
					(width 0)
					(fill yes)
				)
			)
		)
		(pad "2" smd custom
			(at 0 0.4572 270)
			(size 0.1143 0.1143)
			(layers "B.Cu" "B.Mask" "B.Paste")
			(net "GND")
			(options
				(clearance outline)
				(anchor circle)
			)
			(primitives
				(gr_poly
					(pts
						(arc
							(start -0.254 0.1778)
							(mid -0.239121 0.213721)
							(end -0.2032 0.2286)
						)
						(arc
							(start 0.2032 0.2286)
							(mid 0.239121 0.213721)
							(end 0.254 0.1778)
						)
						(arc
							(start 0.254 -0.1778)
							(mid 0.239121 -0.213721)
							(end 0.2032 -0.2286)
						)
						(arc
							(start -0.2032 -0.2286)
							(mid -0.239121 -0.213721)
							(end -0.254 -0.1778)
						)
					)
					(width 0)
					(fill yes)
				)
			)
		)
	)
	(footprint ""
		(layer "B.Cu")
		(at 204.089 -31.75 90)
		(property "Reference" "C350"
			(at 0 0 90)
			(layer "B.SilkS")
			(hide yes)
			(effects
				(font
					(size 1.27 1.27)
				)
				(justify mirror)
			)
		)
		(property "Value" "SCD1U16V2KX-3GP"
			(at -1.8923 -1.2065 90)
			(unlocked yes)
			(layer "B.Fab")
			(hide yes)
			(effects
				(font
					(size 1.016 1.016)
					(thickness 0.1524)
				)
				(justify mirror)
			)
		)
		(property "Device Type" "C402H22"
			(at -1.8923 -2.7305 90)
			(unlocked yes)
			(layer "B.Fab")
			(hide yes)
			(effects
				(font
					(size 1.016 1.016)
					(thickness 0.1524)
				)
				(justify mirror)
			)
		)
		(duplicate_pad_numbers_are_jumpers no)
		(fp_rect
			(start 0.381 0.7366)
			(end -0.381 -0.7366)
			(stroke
				(width 0)
				(type default)
			)
			(fill no)
			(layer "B.CrtYd")
		)
		(fp_rect
			(start 0.381 0.7366)
			(end -0.381 -0.7366)
			(stroke
				(width 0)
				(type default)
			)
			(fill no)
			(layer "B.Fab")
		)
		(pad "1" smd custom
			(at 0 -0.4572 270)
			(size 0.1143 0.1143)
			(layers "B.Cu" "B.Mask" "B.Paste")
			(net "PV_VDDR")
			(options
				(clearance outline)
				(anchor circle)
			)
			(primitives
				(gr_poly
					(pts
						(arc
							(start -0.254 0.1778)
							(mid -0.239121 0.213721)
							(end -0.2032 0.2286)
						)
						(arc
							(start 0.2032 0.2286)
							(mid 0.239121 0.213721)
							(end 0.254 0.1778)
						)
						(arc
							(start 0.254 -0.1778)
							(mid 0.239121 -0.213721)
							(end 0.2032 -0.2286)
						)
						(arc
							(start -0.2032 -0.2286)
							(mid -0.239121 -0.213721)
							(end -0.254 -0.1778)
						)
					)
					(width 0)
					(fill yes)
				)
			)
		)
		(pad "2" smd custom
			(at 0 0.4572 270)
			(size 0.1143 0.1143)
			(layers "B.Cu" "B.Mask" "B.Paste")
			(net "GND")
			(options
				(clearance outline)
				(anchor circle)
			)
			(primitives
				(gr_poly
					(pts
						(arc
							(start -0.254 0.1778)
							(mid -0.239121 0.213721)
							(end -0.2032 0.2286)
						)
						(arc
							(start 0.2032 0.2286)
							(mid 0.239121 0.213721)
							(end 0.254 0.1778)
						)
						(arc
							(start 0.254 -0.1778)
							(mid 0.239121 -0.213721)
							(end 0.2032 -0.2286)
						)
						(arc
							(start -0.2032 -0.2286)
							(mid -0.239121 -0.213721)
							(end -0.254 -0.1778)
						)
					)
					(width 0)
					(fill yes)
				)
			)
		)
	)
	(footprint ""
		(layer "B.Cu")
		(at 167.259 -12.600178 180)
		(property "Reference" "C340"
			(at 0 0 0)
			(layer "B.SilkS")
			(hide yes)
			(effects
				(font
					(size 1.27 1.27)
				)
				(justify mirror)
			)
		)
		(property "Value" "SCD1U16V2KX-3GP"
			(at -1.8923 -1.2065 180)
			(unlocked yes)
			(layer "B.Fab")
			(hide yes)
			(effects
				(font
					(size 1.016 1.016)
					(thickness 0.1524)
				)
				(justify mirror)
			)
		)
		(property "Device Type" "C402H22"
			(at -1.8923 -2.7305 180)
			(unlocked yes)
			(layer "B.Fab")
			(hide yes)
			(effects
				(font
					(size 1.016 1.016)
					(thickness 0.1524)
				)
				(justify mirror)
			)
		)
		(duplicate_pad_numbers_are_jumpers no)
		(fp_rect
			(start 0.381 0.7366)
			(end -0.381 -0.7366)
			(stroke
				(width 0)
				(type default)
			)
			(fill no)
			(layer "B.CrtYd")
		)
		(fp_rect
			(start 0.381 0.7366)
			(end -0.381 -0.7366)
			(stroke
				(width 0)
				(type default)
			)
			(fill no)
			(layer "B.Fab")
		)
		(pad "1" smd custom
			(at 0 -0.4572)
			(size 0.1143 0.1143)
			(layers "B.Cu" "B.Mask" "B.Paste")
			(net "PV_VDDR")
			(options
				(clearance outline)
				(anchor circle)
			)
			(primitives
				(gr_poly
					(pts
						(arc
							(start -0.254 0.1778)
							(mid -0.239121 0.213721)
							(end -0.2032 0.2286)
						)
						(arc
							(start 0.2032 0.2286)
							(mid 0.239121 0.213721)
							(end 0.254 0.1778)
						)
						(arc
							(start 0.254 -0.1778)
							(mid 0.239121 -0.213721)
							(end 0.2032 -0.2286)
						)
						(arc
							(start -0.2032 -0.2286)
							(mid -0.239121 -0.213721)
							(end -0.254 -0.1778)
						)
					)
					(width 0)
					(fill yes)
				)
			)
		)
		(pad "2" smd custom
			(at 0 0.4572)
			(size 0.1143 0.1143)
			(layers "B.Cu" "B.Mask" "B.Paste")
			(net "GND")
			(options
				(clearance outline)
				(anchor circle)
			)
			(primitives
				(gr_poly
					(pts
						(arc
							(start -0.254 0.1778)
							(mid -0.239121 0.213721)
							(end -0.2032 0.2286)
						)
						(arc
							(start 0.2032 0.2286)
							(mid 0.239121 0.213721)
							(end 0.254 0.1778)
						)
						(arc
							(start 0.254 -0.1778)
							(mid 0.239121 -0.213721)
							(end 0.2032 -0.2286)
						)
						(arc
							(start -0.2032 -0.2286)
							(mid -0.239121 -0.213721)
							(end -0.254 -0.1778)
						)
					)
					(width 0)
					(fill yes)
				)
			)
		)
	)
	(footprint ""
		(layer "B.Cu")
		(at 80.137 -63.246 180)
		(property "Reference" "R291"
			(at 0 0 0)
			(layer "B.SilkS")
			(hide yes)
			(effects
				(font
					(size 1.27 1.27)
				)
				(justify mirror)
			)
		)
		(property "Value" "220R2F-GP"
			(at -0.064008 -3.993896 180)
			(unlocked yes)
			(layer "B.Fab")
			(hide yes)
			(effects
				(font
					(size 1.016 1.016)
					(thickness 0.1524)
				)
				(justify mirror)
			)
		)
		(property "Device Type" "R402H16"
			(at -0.064008 -5.517896 180)
			(unlocked yes)
			(layer "B.Fab")
			(hide yes)
			(effects
				(font
					(size 1.016 1.016)
					(thickness 0.1524)
				)
				(justify mirror)
			)
		)
		(duplicate_pad_numbers_are_jumpers no)
		(fp_rect
			(start 0.381 0.8382)
			(end -0.381 -0.8382)
			(stroke
				(width 0)
				(type default)
			)
			(fill no)
			(layer "B.CrtYd")
		)
		(fp_rect
			(start 0.381 0.8382)
			(end -0.381 -0.8382)
			(stroke
				(width 0)
				(type default)
			)
			(fill no)
			(layer "B.Fab")
		)
		(pad "1" smd custom
			(at 0 -0.4318)
			(size 0.127 0.127)
			(layers "B.Cu" "B.Mask" "B.Paste")
			(net "SVID_ALERT#")
			(options
				(clearance outline)
				(anchor circle)
			)
			(primitives
				(gr_poly
					(pts
						(arc
							(start -0.2032 0.2794)
							(mid -0.239121 0.264521)
							(end -0.254 0.2286)
						)
						(arc
							(start -0.254 -0.2286)
							(mid -0.239121 -0.264521)
							(end -0.2032 -0.2794)
						)
						(arc
							(start 0.2032 -0.2794)
							(mid 0.239121 -0.264521)
							(end 0.254 -0.2286)
						)
						(arc
							(start 0.254 0.2286)
							(mid 0.239121 0.264521)
							(end 0.2032 0.2794)
						)
					)
					(width 0)
					(fill yes)
				)
			)
		)
		(pad "2" smd custom
			(at 0 0.4318)
			(size 0.127 0.127)
			(layers "B.Cu" "B.Mask" "B.Paste")
			(net "SVID_CPU_ALERT#")
			(options
				(clearance outline)
				(anchor circle)
			)
			(primitives
				(gr_poly
					(pts
						(arc
							(start -0.2032 0.2794)
							(mid -0.239121 0.264521)
							(end -0.254 0.2286)
						)
						(arc
							(start -0.254 -0.2286)
							(mid -0.239121 -0.264521)
							(end -0.2032 -0.2794)
						)
						(arc
							(start 0.2032 -0.2794)
							(mid 0.239121 -0.264521)
							(end 0.254 -0.2286)
						)
						(arc
							(start 0.254 0.2286)
							(mid 0.239121 0.264521)
							(end 0.2032 0.2794)
						)
					)
					(width 0)
					(fill yes)
				)
			)
		)
	)
	(footprint ""
		(layer "B.Cu")
		(at 189.103 -60.325)
		(property "Reference" "C107"
			(at 0 0 0)
			(layer "B.SilkS")
			(hide yes)
			(effects
				(font
					(size 1.27 1.27)
				)
				(justify mirror)
			)
		)
		(property "Value" "SCD1U16V2KX-3GP"
			(at -1.1811 -2.7051 0)
			(unlocked yes)
			(layer "B.Fab")
			(hide yes)
			(effects
				(font
					(size 1.016 1.016)
					(thickness 0.1524)
				)
				(justify mirror)
			)
		)
		(property "Device Type" "C402H22"
			(at -1.1811 -4.2291 0)
			(unlocked yes)
			(layer "B.Fab")
			(hide yes)
			(effects
				(font
					(size 1.016 1.016)
					(thickness 0.1524)
				)
				(justify mirror)
			)
		)
		(duplicate_pad_numbers_are_jumpers no)
		(fp_rect
			(start 0.381 0.7366)
			(end -0.381 -0.7366)
			(stroke
				(width 0)
				(type default)
			)
			(fill no)
			(layer "B.CrtYd")
		)
		(fp_rect
			(start 0.381 0.7366)
			(end -0.381 -0.7366)
			(stroke
				(width 0)
				(type default)
			)
			(fill no)
			(layer "B.Fab")
		)
		(pad "1" smd custom
			(at 0 -0.4572 180)
			(size 0.1143 0.1143)
			(layers "B.Cu" "B.Mask" "B.Paste")
			(net "DDR3_M_A_VREF_DQ0")
			(options
				(clearance outline)
				(anchor circle)
			)
			(primitives
				(gr_poly
					(pts
						(arc
							(start -0.254 0.1778)
							(mid -0.239121 0.213721)
							(end -0.2032 0.2286)
						)
						(arc
							(start 0.2032 0.2286)
							(mid 0.239121 0.213721)
							(end 0.254 0.1778)
						)
						(arc
							(start 0.254 -0.1778)
							(mid 0.239121 -0.213721)
							(end 0.2032 -0.2286)
						)
						(arc
							(start -0.2032 -0.2286)
							(mid -0.239121 -0.213721)
							(end -0.254 -0.1778)
						)
					)
					(width 0)
					(fill yes)
				)
			)
		)
		(pad "2" smd custom
			(at 0 0.4572 180)
			(size 0.1143 0.1143)
			(layers "B.Cu" "B.Mask" "B.Paste")
			(net "GND")
			(options
				(clearance outline)
				(anchor circle)
			)
			(primitives
				(gr_poly
					(pts
						(arc
							(start -0.254 0.1778)
							(mid -0.239121 0.213721)
							(end -0.2032 0.2286)
						)
						(arc
							(start 0.2032 0.2286)
							(mid 0.239121 0.213721)
							(end 0.254 0.1778)
						)
						(arc
							(start 0.254 -0.1778)
							(mid 0.239121 -0.213721)
							(end 0.2032 -0.2286)
						)
						(arc
							(start -0.2032 -0.2286)
							(mid -0.239121 -0.213721)
							(end -0.254 -0.1778)
						)
					)
					(width 0)
					(fill yes)
				)
			)
		)
	)
	(footprint ""
		(layer "B.Cu")
		(at 197.485 -32.893 -90)
		(property "Reference" "R151"
			(at 0 0 90)
			(layer "B.SilkS")
			(hide yes)
			(effects
				(font
					(size 1.27 1.27)
				)
				(justify mirror)
			)
		)
		(property "Value" "300R2F-GP"
			(at -1.7907 -1.1176 270)
			(unlocked yes)
			(layer "B.Fab")
			(hide yes)
			(effects
				(font
					(size 1.016 1.016)
					(thickness 0.1524)
				)
				(justify mirror)
			)
		)
		(property "Device Type" "R402H16"
			(at -1.7907 -2.6416 270)
			(unlocked yes)
			(layer "B.Fab")
			(hide yes)
			(effects
				(font
					(size 1.016 1.016)
					(thickness 0.1524)
				)
				(justify mirror)
			)
		)
		(duplicate_pad_numbers_are_jumpers no)
		(fp_rect
			(start 0.381 0.8382)
			(end -0.381 -0.8382)
			(stroke
				(width 0)
				(type default)
			)
			(fill no)
			(layer "B.CrtYd")
		)
		(fp_rect
			(start 0.381 0.8382)
			(end -0.381 -0.8382)
			(stroke
				(width 0)
				(type default)
			)
			(fill no)
			(layer "B.Fab")
		)
		(pad "1" smd custom
			(at 0 -0.4318 90)
			(size 0.127 0.127)
			(layers "B.Cu" "B.Mask" "B.Paste")
			(net "PORT80_R_BIT2")
			(options
				(clearance outline)
				(anchor circle)
			)
			(primitives
				(gr_poly
					(pts
						(arc
							(start -0.2032 0.2794)
							(mid -0.239121 0.264521)
							(end -0.254 0.2286)
						)
						(arc
							(start -0.254 -0.2286)
							(mid -0.239121 -0.264521)
							(end -0.2032 -0.2794)
						)
						(arc
							(start 0.2032 -0.2794)
							(mid 0.239121 -0.264521)
							(end 0.254 -0.2286)
						)
						(arc
							(start 0.254 0.2286)
							(mid 0.239121 0.264521)
							(end 0.2032 0.2794)
						)
					)
					(width 0)
					(fill yes)
				)
			)
		)
		(pad "2" smd custom
			(at 0 0.4318 90)
			(size 0.127 0.127)
			(layers "B.Cu" "B.Mask" "B.Paste")
			(net "P3V3_STBY")
			(options
				(clearance outline)
				(anchor circle)
			)
			(primitives
				(gr_poly
					(pts
						(arc
							(start -0.2032 0.2794)
							(mid -0.239121 0.264521)
							(end -0.254 0.2286)
						)
						(arc
							(start -0.254 -0.2286)
							(mid -0.239121 -0.264521)
							(end -0.2032 -0.2794)
						)
						(arc
							(start 0.2032 -0.2794)
							(mid 0.239121 -0.264521)
							(end 0.254 -0.2286)
						)
						(arc
							(start 0.254 0.2286)
							(mid 0.239121 0.264521)
							(end 0.2032 0.2794)
						)
					)
					(width 0)
					(fill yes)
				)
			)
		)
	)
	(footprint ""
		(layer "B.Cu")
		(at 68.453 -61.595)
		(property "Reference" "R495"
			(at 0 0 0)
			(layer "B.SilkS")
			(hide yes)
			(effects
				(font
					(size 1.27 1.27)
				)
				(justify mirror)
			)
		)
		(property "Value" "2K2R2F-GP"
			(at -1.7907 -1.1176 0)
			(unlocked yes)
			(layer "B.Fab")
			(hide yes)
			(effects
				(font
					(size 1.016 1.016)
					(thickness 0.1524)
				)
				(justify mirror)
			)
		)
		(property "Device Type" "R402H16"
			(at -1.7907 -2.6416 0)
			(unlocked yes)
			(layer "B.Fab")
			(hide yes)
			(effects
				(font
					(size 1.016 1.016)
					(thickness 0.1524)
				)
				(justify mirror)
			)
		)
		(duplicate_pad_numbers_are_jumpers no)
		(fp_rect
			(start 0.381 0.8382)
			(end -0.381 -0.8382)
			(stroke
				(width 0)
				(type default)
			)
			(fill no)
			(layer "B.CrtYd")
		)
		(fp_rect
			(start 0.381 0.8382)
			(end -0.381 -0.8382)
			(stroke
				(width 0)
				(type default)
			)
			(fill no)
			(layer "B.Fab")
		)
		(pad "1" smd custom
			(at 0 -0.4318 180)
			(size 0.127 0.127)
			(layers "B.Cu" "B.Mask" "B.Paste")
			(net "P12V_SENSE")
			(options
				(clearance outline)
				(anchor circle)
			)
			(primitives
				(gr_poly
					(pts
						(arc
							(start -0.2032 0.2794)
							(mid -0.239121 0.264521)
							(end -0.254 0.2286)
						)
						(arc
							(start -0.254 -0.2286)
							(mid -0.239121 -0.264521)
							(end -0.2032 -0.2794)
						)
						(arc
							(start 0.2032 -0.2794)
							(mid 0.239121 -0.264521)
							(end 0.254 -0.2286)
						)
						(arc
							(start 0.254 0.2286)
							(mid 0.239121 0.264521)
							(end 0.2032 0.2794)
						)
					)
					(width 0)
					(fill yes)
				)
			)
		)
		(pad "2" smd custom
			(at 0 0.4318 180)
			(size 0.127 0.127)
			(layers "B.Cu" "B.Mask" "B.Paste")
			(net "GND")
			(options
				(clearance outline)
				(anchor circle)
			)
			(primitives
				(gr_poly
					(pts
						(arc
							(start -0.2032 0.2794)
							(mid -0.239121 0.264521)
							(end -0.254 0.2286)
						)
						(arc
							(start -0.254 -0.2286)
							(mid -0.239121 -0.264521)
							(end -0.2032 -0.2794)
						)
						(arc
							(start 0.2032 -0.2794)
							(mid 0.239121 -0.264521)
							(end 0.254 -0.2286)
						)
						(arc
							(start 0.254 0.2286)
							(mid 0.239121 0.264521)
							(end 0.2032 0.2794)
						)
					)
					(width 0)
					(fill yes)
				)
			)
		)
	)
	(footprint ""
		(layer "B.Cu")
		(at 75.565 -57.912 -90)
		(property "Reference" "R136"
			(at 0 0 90)
			(layer "B.SilkS")
			(hide yes)
			(effects
				(font
					(size 1.27 1.27)
				)
				(justify mirror)
			)
		)
		(property "Value" "0R2J-2-GP"
			(at -0.064008 -3.993896 270)
			(unlocked yes)
			(layer "B.Fab")
			(hide yes)
			(effects
				(font
					(size 1.016 1.016)
					(thickness 0.1524)
				)
				(justify mirror)
			)
		)
		(property "Device Type" "R402H16"
			(at -0.064008 -5.517896 270)
			(unlocked yes)
			(layer "B.Fab")
			(hide yes)
			(effects
				(font
					(size 1.016 1.016)
					(thickness 0.1524)
				)
				(justify mirror)
			)
		)
		(duplicate_pad_numbers_are_jumpers no)
		(fp_rect
			(start 0.381 0.8382)
			(end -0.381 -0.8382)
			(stroke
				(width 0)
				(type default)
			)
			(fill no)
			(layer "B.CrtYd")
		)
		(fp_rect
			(start 0.381 0.8382)
			(end -0.381 -0.8382)
			(stroke
				(width 0)
				(type default)
			)
			(fill no)
			(layer "B.Fab")
		)
		(pad "1" smd custom
			(at 0 -0.4318 90)
			(size 0.127 0.127)
			(layers "B.Cu" "B.Mask" "B.Paste")
			(net "VOL1_SEN_CLK")
			(options
				(clearance outline)
				(anchor circle)
			)
			(primitives
				(gr_poly
					(pts
						(arc
							(start -0.2032 0.2794)
							(mid -0.239121 0.264521)
							(end -0.254 0.2286)
						)
						(arc
							(start -0.254 -0.2286)
							(mid -0.239121 -0.264521)
							(end -0.2032 -0.2794)
						)
						(arc
							(start 0.2032 -0.2794)
							(mid 0.239121 -0.264521)
							(end 0.254 -0.2286)
						)
						(arc
							(start 0.254 0.2286)
							(mid 0.239121 0.264521)
							(end 0.2032 0.2794)
						)
					)
					(width 0)
					(fill yes)
				)
			)
		)
		(pad "2" smd custom
			(at 0 0.4318 90)
			(size 0.127 0.127)
			(layers "B.Cu" "B.Mask" "B.Paste")
			(net "SMB_HOST_LV_CLK")
			(options
				(clearance outline)
				(anchor circle)
			)
			(primitives
				(gr_poly
					(pts
						(arc
							(start -0.2032 0.2794)
							(mid -0.239121 0.264521)
							(end -0.254 0.2286)
						)
						(arc
							(start -0.254 -0.2286)
							(mid -0.239121 -0.264521)
							(end -0.2032 -0.2794)
						)
						(arc
							(start 0.2032 -0.2794)
							(mid 0.239121 -0.264521)
							(end 0.254 -0.2286)
						)
						(arc
							(start 0.254 0.2286)
							(mid 0.239121 0.264521)
							(end 0.2032 0.2794)
						)
					)
					(width 0)
					(fill yes)
				)
			)
		)
	)
	(footprint ""
		(layer "B.Cu")
		(at 204.1398 -39.4462 90)
		(property "Reference" "C351"
			(at 0 0 90)
			(layer "B.SilkS")
			(hide yes)
			(effects
				(font
					(size 1.27 1.27)
				)
				(justify mirror)
			)
		)
		(property "Value" "SCD1U16V2KX-3GP"
			(at -1.8923 -1.2065 90)
			(unlocked yes)
			(layer "B.Fab")
			(hide yes)
			(effects
				(font
					(size 1.016 1.016)
					(thickness 0.1524)
				)
				(justify mirror)
			)
		)
		(property "Device Type" "C402H22"
			(at -1.8923 -2.7305 90)
			(unlocked yes)
			(layer "B.Fab")
			(hide yes)
			(effects
				(font
					(size 1.016 1.016)
					(thickness 0.1524)
				)
				(justify mirror)
			)
		)
		(duplicate_pad_numbers_are_jumpers no)
		(fp_rect
			(start 0.381 0.7366)
			(end -0.381 -0.7366)
			(stroke
				(width 0)
				(type default)
			)
			(fill no)
			(layer "B.CrtYd")
		)
		(fp_rect
			(start 0.381 0.7366)
			(end -0.381 -0.7366)
			(stroke
				(width 0)
				(type default)
			)
			(fill no)
			(layer "B.Fab")
		)
		(pad "1" smd custom
			(at 0 -0.4572 270)
			(size 0.1143 0.1143)
			(layers "B.Cu" "B.Mask" "B.Paste")
			(net "PV_VDDR")
			(options
				(clearance outline)
				(anchor circle)
			)
			(primitives
				(gr_poly
					(pts
						(arc
							(start -0.254 0.1778)
							(mid -0.239121 0.213721)
							(end -0.2032 0.2286)
						)
						(arc
							(start 0.2032 0.2286)
							(mid 0.239121 0.213721)
							(end 0.254 0.1778)
						)
						(arc
							(start 0.254 -0.1778)
							(mid 0.239121 -0.213721)
							(end 0.2032 -0.2286)
						)
						(arc
							(start -0.2032 -0.2286)
							(mid -0.239121 -0.213721)
							(end -0.254 -0.1778)
						)
					)
					(width 0)
					(fill yes)
				)
			)
		)
		(pad "2" smd custom
			(at 0 0.4572 270)
			(size 0.1143 0.1143)
			(layers "B.Cu" "B.Mask" "B.Paste")
			(net "GND")
			(options
				(clearance outline)
				(anchor circle)
			)
			(primitives
				(gr_poly
					(pts
						(arc
							(start -0.254 0.1778)
							(mid -0.239121 0.213721)
							(end -0.2032 0.2286)
						)
						(arc
							(start 0.2032 0.2286)
							(mid 0.239121 0.213721)
							(end 0.254 0.1778)
						)
						(arc
							(start 0.254 -0.1778)
							(mid 0.239121 -0.213721)
							(end 0.2032 -0.2286)
						)
						(arc
							(start -0.2032 -0.2286)
							(mid -0.239121 -0.213721)
							(end -0.254 -0.1778)
						)
					)
					(width 0)
					(fill yes)
				)
			)
		)
	)
	(footprint ""
		(layer "B.Cu")
		(at 95.123 -33.782)
		(property "Reference" "C216"
			(at 0 0 0)
			(layer "B.SilkS")
			(hide yes)
			(effects
				(font
					(size 1.27 1.27)
				)
				(justify mirror)
			)
		)
		(property "Value" "SC1U10V2KX-1GP"
			(at -1.1811 -2.7051 0)
			(unlocked yes)
			(layer "B.Fab")
			(hide yes)
			(effects
				(font
					(size 1.016 1.016)
					(thickness 0.1524)
				)
				(justify mirror)
			)
		)
		(property "Device Type" "C402H22"
			(at -1.1811 -4.2291 0)
			(unlocked yes)
			(layer "B.Fab")
			(hide yes)
			(effects
				(font
					(size 1.016 1.016)
					(thickness 0.1524)
				)
				(justify mirror)
			)
		)
		(duplicate_pad_numbers_are_jumpers no)
		(fp_rect
			(start 0.381 0.7366)
			(end -0.381 -0.7366)
			(stroke
				(width 0)
				(type default)
			)
			(fill no)
			(layer "B.CrtYd")
		)
		(fp_rect
			(start 0.381 0.7366)
			(end -0.381 -0.7366)
			(stroke
				(width 0)
				(type default)
			)
			(fill no)
			(layer "B.Fab")
		)
		(pad "1" smd custom
			(at 0 -0.4572 180)
			(size 0.1143 0.1143)
			(layers "B.Cu" "B.Mask" "B.Paste")
			(net "P1V35")
			(options
				(clearance outline)
				(anchor circle)
			)
			(primitives
				(gr_poly
					(pts
						(arc
							(start -0.254 0.1778)
							(mid -0.239121 0.213721)
							(end -0.2032 0.2286)
						)
						(arc
							(start 0.2032 0.2286)
							(mid 0.239121 0.213721)
							(end 0.254 0.1778)
						)
						(arc
							(start 0.254 -0.1778)
							(mid 0.239121 -0.213721)
							(end 0.2032 -0.2286)
						)
						(arc
							(start -0.2032 -0.2286)
							(mid -0.239121 -0.213721)
							(end -0.254 -0.1778)
						)
					)
					(width 0)
					(fill yes)
				)
			)
		)
		(pad "2" smd custom
			(at 0 0.4572 180)
			(size 0.1143 0.1143)
			(layers "B.Cu" "B.Mask" "B.Paste")
			(net "GND")
			(options
				(clearance outline)
				(anchor circle)
			)
			(primitives
				(gr_poly
					(pts
						(arc
							(start -0.254 0.1778)
							(mid -0.239121 0.213721)
							(end -0.2032 0.2286)
						)
						(arc
							(start 0.2032 0.2286)
							(mid 0.239121 0.213721)
							(end 0.254 0.1778)
						)
						(arc
							(start 0.254 -0.1778)
							(mid 0.239121 -0.213721)
							(end 0.2032 -0.2286)
						)
						(arc
							(start -0.2032 -0.2286)
							(mid -0.239121 -0.213721)
							(end -0.254 -0.1778)
						)
					)
					(width 0)
					(fill yes)
				)
			)
		)
	)
	(footprint ""
		(layer "B.Cu")
		(at 67.183 -29.7688 -90)
		(property "Reference" "C283"
			(at 0 0 90)
			(layer "B.SilkS")
			(hide yes)
			(effects
				(font
					(size 1.27 1.27)
				)
				(justify mirror)
			)
		)
		(property "Value" "SCD01U16V2KX-3GP"
			(at -1.1811 -2.7051 270)
			(unlocked yes)
			(layer "B.Fab")
			(hide yes)
			(effects
				(font
					(size 1.016 1.016)
					(thickness 0.1524)
				)
				(justify mirror)
			)
		)
		(property "Device Type" "C402H22"
			(at -1.1811 -4.2291 270)
			(unlocked yes)
			(layer "B.Fab")
			(hide yes)
			(effects
				(font
					(size 1.016 1.016)
					(thickness 0.1524)
				)
				(justify mirror)
			)
		)
		(duplicate_pad_numbers_are_jumpers no)
		(fp_rect
			(start 0.381 0.7366)
			(end -0.381 -0.7366)
			(stroke
				(width 0)
				(type default)
			)
			(fill no)
			(layer "B.CrtYd")
		)
		(fp_rect
			(start 0.381 0.7366)
			(end -0.381 -0.7366)
			(stroke
				(width 0)
				(type default)
			)
			(fill no)
			(layer "B.Fab")
		)
		(pad "1" smd custom
			(at 0 -0.4572 90)
			(size 0.1143 0.1143)
			(layers "B.Cu" "B.Mask" "B.Paste")
			(net "SATA3_RX_DN0")
			(options
				(clearance outline)
				(anchor circle)
			)
			(primitives
				(gr_poly
					(pts
						(arc
							(start -0.254 0.1778)
							(mid -0.239121 0.213721)
							(end -0.2032 0.2286)
						)
						(arc
							(start 0.2032 0.2286)
							(mid 0.239121 0.213721)
							(end 0.254 0.1778)
						)
						(arc
							(start 0.254 -0.1778)
							(mid 0.239121 -0.213721)
							(end 0.2032 -0.2286)
						)
						(arc
							(start -0.2032 -0.2286)
							(mid -0.239121 -0.213721)
							(end -0.254 -0.1778)
						)
					)
					(width 0)
					(fill yes)
				)
			)
		)
		(pad "2" smd custom
			(at 0 0.4572 90)
			(size 0.1143 0.1143)
			(layers "B.Cu" "B.Mask" "B.Paste")
			(net "SATA3_RX_C_DN0")
			(options
				(clearance outline)
				(anchor circle)
			)
			(primitives
				(gr_poly
					(pts
						(arc
							(start -0.254 0.1778)
							(mid -0.239121 0.213721)
							(end -0.2032 0.2286)
						)
						(arc
							(start 0.2032 0.2286)
							(mid 0.239121 0.213721)
							(end 0.254 0.1778)
						)
						(arc
							(start 0.254 -0.1778)
							(mid 0.239121 -0.213721)
							(end 0.2032 -0.2286)
						)
						(arc
							(start -0.2032 -0.2286)
							(mid -0.239121 -0.213721)
							(end -0.254 -0.1778)
						)
					)
					(width 0)
					(fill yes)
				)
			)
		)
	)
	(footprint ""
		(layer "B.Cu")
		(at 21.717 -12.7)
		(property "Reference" "C285"
			(at 0 0 0)
			(layer "B.SilkS")
			(hide yes)
			(effects
				(font
					(size 1.27 1.27)
				)
				(justify mirror)
			)
		)
		(property "Value" "SCD1U16V2KX-3GP"
			(at -1.1811 -2.7051 0)
			(unlocked yes)
			(layer "B.Fab")
			(hide yes)
			(effects
				(font
					(size 1.016 1.016)
					(thickness 0.1524)
				)
				(justify mirror)
			)
		)
		(property "Device Type" "C402H22"
			(at -1.1811 -4.2291 0)
			(unlocked yes)
			(layer "B.Fab")
			(hide yes)
			(effects
				(font
					(size 1.016 1.016)
					(thickness 0.1524)
				)
				(justify mirror)
			)
		)
		(duplicate_pad_numbers_are_jumpers no)
		(fp_rect
			(start 0.381 0.7366)
			(end -0.381 -0.7366)
			(stroke
				(width 0)
				(type default)
			)
			(fill no)
			(layer "B.CrtYd")
		)
		(fp_rect
			(start 0.381 0.7366)
			(end -0.381 -0.7366)
			(stroke
				(width 0)
				(type default)
			)
			(fill no)
			(layer "B.Fab")
		)
		(pad "1" smd custom
			(at 0 -0.4572 180)
			(size 0.1143 0.1143)
			(layers "B.Cu" "B.Mask" "B.Paste")
			(net "P2E_CPU_ETH10G_C_TX_DN10")
			(options
				(clearance outline)
				(anchor circle)
			)
			(primitives
				(gr_poly
					(pts
						(arc
							(start -0.254 0.1778)
							(mid -0.239121 0.213721)
							(end -0.2032 0.2286)
						)
						(arc
							(start 0.2032 0.2286)
							(mid 0.239121 0.213721)
							(end 0.254 0.1778)
						)
						(arc
							(start 0.254 -0.1778)
							(mid 0.239121 -0.213721)
							(end 0.2032 -0.2286)
						)
						(arc
							(start -0.2032 -0.2286)
							(mid -0.239121 -0.213721)
							(end -0.254 -0.1778)
						)
					)
					(width 0)
					(fill yes)
				)
			)
		)
		(pad "2" smd custom
			(at 0 0.4572 180)
			(size 0.1143 0.1143)
			(layers "B.Cu" "B.Mask" "B.Paste")
			(net "P2E_CPU_ETH10G_TX_DN10")
			(options
				(clearance outline)
				(anchor circle)
			)
			(primitives
				(gr_poly
					(pts
						(arc
							(start -0.254 0.1778)
							(mid -0.239121 0.213721)
							(end -0.2032 0.2286)
						)
						(arc
							(start 0.2032 0.2286)
							(mid 0.239121 0.213721)
							(end 0.254 0.1778)
						)
						(arc
							(start 0.254 -0.1778)
							(mid 0.239121 -0.213721)
							(end 0.2032 -0.2286)
						)
						(arc
							(start -0.2032 -0.2286)
							(mid -0.239121 -0.213721)
							(end -0.254 -0.1778)
						)
					)
					(width 0)
					(fill yes)
				)
			)
		)
	)
	(footprint ""
		(layer "B.Cu")
		(at 94.869 -28.972002 -90)
		(property "Reference" "TP51"
			(at 0 0 90)
			(layer "B.SilkS")
			(hide yes)
			(effects
				(font
					(size 1.27 1.27)
				)
				(justify mirror)
			)
		)
		(property "Value" "TPAD24"
			(at 0 -2.9972 270)
			(unlocked yes)
			(layer "B.Fab")
			(hide yes)
			(effects
				(font
					(size 1.016 1.016)
					(thickness 0.1524)
				)
				(justify mirror)
			)
		)
		(property "Device Type" "TPAD24"
			(at 0 -4.5212 270)
			(unlocked yes)
			(layer "B.Fab")
			(hide yes)
			(effects
				(font
					(size 1.016 1.016)
					(thickness 0.1524)
				)
				(justify mirror)
			)
		)
		(duplicate_pad_numbers_are_jumpers no)
		(fp_poly
			(pts
				(arc
					(start 0 -0.3048)
					(mid 0 0.3048)
					(end 0 -0.3048)
				)
			)
			(stroke
				(width 0)
				(type default)
			)
			(fill no)
			(layer "B.CrtYd")
		)
		(fp_poly
			(pts
				(arc
					(start 0 -0.6096)
					(mid 0 0.6096)
					(end 0 -0.6096)
				)
			)
			(stroke
				(width 0)
				(type default)
			)
			(fill no)
			(layer "B.Fab")
		)
		(pad "1" smd circle
			(at 0 0 90)
			(size 0.6096 0.6096)
			(layers "B.Cu" "B.Mask" "B.Paste")
			(net "TP_CPU_RSVD17")
		)
	)
	(footprint ""
		(layer "B.Cu")
		(at 141.097 -45.466 90)
		(property "Reference" "R338"
			(at 0 0 90)
			(layer "B.SilkS")
			(hide yes)
			(effects
				(font
					(size 1.27 1.27)
				)
				(justify mirror)
			)
		)
		(property "Value" "1KR2F-3-GP"
			(at -0.064008 -3.993896 90)
			(unlocked yes)
			(layer "B.Fab")
			(hide yes)
			(effects
				(font
					(size 1.016 1.016)
					(thickness 0.1524)
				)
				(justify mirror)
			)
		)
		(property "Device Type" "R402H16"
			(at -0.064008 -5.517896 90)
			(unlocked yes)
			(layer "B.Fab")
			(hide yes)
			(effects
				(font
					(size 1.016 1.016)
					(thickness 0.1524)
				)
				(justify mirror)
			)
		)
		(duplicate_pad_numbers_are_jumpers no)
		(fp_rect
			(start 0.381 0.8382)
			(end -0.381 -0.8382)
			(stroke
				(width 0)
				(type default)
			)
			(fill no)
			(layer "B.CrtYd")
		)
		(fp_rect
			(start 0.381 0.8382)
			(end -0.381 -0.8382)
			(stroke
				(width 0)
				(type default)
			)
			(fill no)
			(layer "B.Fab")
		)
		(pad "1" smd custom
			(at 0 -0.4318 270)
			(size 0.127 0.127)
			(layers "B.Cu" "B.Mask" "B.Paste")
			(net "C_NCE#")
			(options
				(clearance outline)
				(anchor circle)
			)
			(primitives
				(gr_poly
					(pts
						(arc
							(start -0.2032 0.2794)
							(mid -0.239121 0.264521)
							(end -0.254 0.2286)
						)
						(arc
							(start -0.254 -0.2286)
							(mid -0.239121 -0.264521)
							(end -0.2032 -0.2794)
						)
						(arc
							(start 0.2032 -0.2794)
							(mid 0.239121 -0.264521)
							(end 0.254 -0.2286)
						)
						(arc
							(start 0.254 0.2286)
							(mid 0.239121 0.264521)
							(end 0.2032 0.2794)
						)
					)
					(width 0)
					(fill yes)
				)
			)
		)
		(pad "2" smd custom
			(at 0 0.4318 270)
			(size 0.127 0.127)
			(layers "B.Cu" "B.Mask" "B.Paste")
			(net "GND")
			(options
				(clearance outline)
				(anchor circle)
			)
			(primitives
				(gr_poly
					(pts
						(arc
							(start -0.2032 0.2794)
							(mid -0.239121 0.264521)
							(end -0.254 0.2286)
						)
						(arc
							(start -0.254 -0.2286)
							(mid -0.239121 -0.264521)
							(end -0.2032 -0.2794)
						)
						(arc
							(start 0.2032 -0.2794)
							(mid 0.239121 -0.264521)
							(end 0.254 -0.2286)
						)
						(arc
							(start 0.254 0.2286)
							(mid 0.239121 0.264521)
							(end 0.2032 0.2794)
						)
					)
					(width 0)
					(fill yes)
				)
			)
		)
	)
	(footprint ""
		(layer "B.Cu")
		(at 30.6832 -33.1724)
		(property "Reference" "R490"
			(at 0 0 0)
			(layer "B.SilkS")
			(hide yes)
			(effects
				(font
					(size 1.27 1.27)
				)
				(justify mirror)
			)
		)
		(property "Value" "51R2F-2-GP"
			(at -1.7907 -1.1176 0)
			(unlocked yes)
			(layer "B.Fab")
			(hide yes)
			(effects
				(font
					(size 1.016 1.016)
					(thickness 0.1524)
				)
				(justify mirror)
			)
		)
		(property "Device Type" "R402H16"
			(at -1.7907 -2.6416 0)
			(unlocked yes)
			(layer "B.Fab")
			(hide yes)
			(effects
				(font
					(size 1.016 1.016)
					(thickness 0.1524)
				)
				(justify mirror)
			)
		)
		(duplicate_pad_numbers_are_jumpers no)
		(fp_rect
			(start 0.381 0.8382)
			(end -0.381 -0.8382)
			(stroke
				(width 0)
				(type default)
			)
			(fill no)
			(layer "B.CrtYd")
		)
		(fp_rect
			(start 0.381 0.8382)
			(end -0.381 -0.8382)
			(stroke
				(width 0)
				(type default)
			)
			(fill no)
			(layer "B.Fab")
		)
		(pad "1" smd custom
			(at 0 -0.4318 180)
			(size 0.127 0.127)
			(layers "B.Cu" "B.Mask" "B.Paste")
			(net "P1V0_STBY")
			(options
				(clearance outline)
				(anchor circle)
			)
			(primitives
				(gr_poly
					(pts
						(arc
							(start -0.2032 0.2794)
							(mid -0.239121 0.264521)
							(end -0.254 0.2286)
						)
						(arc
							(start -0.254 -0.2286)
							(mid -0.239121 -0.264521)
							(end -0.2032 -0.2794)
						)
						(arc
							(start 0.2032 -0.2794)
							(mid 0.239121 -0.264521)
							(end 0.254 -0.2286)
						)
						(arc
							(start 0.254 0.2286)
							(mid 0.239121 0.264521)
							(end 0.2032 0.2794)
						)
					)
					(width 0)
					(fill yes)
				)
			)
		)
		(pad "2" smd custom
			(at 0 0.4318 180)
			(size 0.127 0.127)
			(layers "B.Cu" "B.Mask" "B.Paste")
			(net "XDP_SOC_CPU_TRST#")
			(options
				(clearance outline)
				(anchor circle)
			)
			(primitives
				(gr_poly
					(pts
						(arc
							(start -0.2032 0.2794)
							(mid -0.239121 0.264521)
							(end -0.254 0.2286)
						)
						(arc
							(start -0.254 -0.2286)
							(mid -0.239121 -0.264521)
							(end -0.2032 -0.2794)
						)
						(arc
							(start 0.2032 -0.2794)
							(mid 0.239121 -0.264521)
							(end 0.254 -0.2286)
						)
						(arc
							(start 0.254 0.2286)
							(mid 0.239121 0.264521)
							(end 0.2032 0.2794)
						)
					)
					(width 0)
					(fill yes)
				)
			)
		)
	)
	(footprint ""
		(layer "B.Cu")
		(at 72.009 -24.13 90)
		(property "Reference" "PR176"
			(at 0 0 90)
			(layer "B.SilkS")
			(hide yes)
			(effects
				(font
					(size 1.27 1.27)
				)
				(justify mirror)
			)
		)
		(property "Value" "10R2F-L-GP"
			(at -1.7907 -1.1176 90)
			(unlocked yes)
			(layer "B.Fab")
			(hide yes)
			(effects
				(font
					(size 1.016 1.016)
					(thickness 0.1524)
				)
				(justify mirror)
			)
		)
		(property "Device Type" "R402H14"
			(at -1.7907 -2.6416 90)
			(unlocked yes)
			(layer "B.Fab")
			(hide yes)
			(effects
				(font
					(size 1.016 1.016)
					(thickness 0.1524)
				)
				(justify mirror)
			)
		)
		(duplicate_pad_numbers_are_jumpers no)
		(fp_rect
			(start 0.381 0.8382)
			(end -0.381 -0.8382)
			(stroke
				(width 0)
				(type default)
			)
			(fill no)
			(layer "B.CrtYd")
		)
		(fp_rect
			(start 0.381 0.8382)
			(end -0.381 -0.8382)
			(stroke
				(width 0)
				(type default)
			)
			(fill no)
			(layer "B.Fab")
		)
		(pad "1" smd custom
			(at 0 -0.4318 270)
			(size 0.127 0.127)
			(layers "B.Cu" "B.Mask" "B.Paste")
			(net "VR_AVIN_P1V8_STBY")
			(options
				(clearance outline)
				(anchor circle)
			)
			(primitives
				(gr_poly
					(pts
						(arc
							(start -0.2032 0.2794)
							(mid -0.239121 0.264521)
							(end -0.254 0.2286)
						)
						(arc
							(start -0.254 -0.2286)
							(mid -0.239121 -0.264521)
							(end -0.2032 -0.2794)
						)
						(arc
							(start 0.2032 -0.2794)
							(mid 0.239121 -0.264521)
							(end 0.254 -0.2286)
						)
						(arc
							(start 0.254 0.2286)
							(mid 0.239121 0.264521)
							(end 0.2032 0.2794)
						)
					)
					(width 0)
					(fill yes)
				)
			)
		)
		(pad "2" smd custom
			(at 0 0.4318 270)
			(size 0.127 0.127)
			(layers "B.Cu" "B.Mask" "B.Paste")
			(net "VR_PVIN_P1V8_STBY")
			(options
				(clearance outline)
				(anchor circle)
			)
			(primitives
				(gr_poly
					(pts
						(arc
							(start -0.2032 0.2794)
							(mid -0.239121 0.264521)
							(end -0.254 0.2286)
						)
						(arc
							(start -0.254 -0.2286)
							(mid -0.239121 -0.264521)
							(end -0.2032 -0.2794)
						)
						(arc
							(start 0.2032 -0.2794)
							(mid 0.239121 -0.264521)
							(end 0.254 -0.2286)
						)
						(arc
							(start 0.254 0.2286)
							(mid 0.239121 0.264521)
							(end 0.2032 0.2794)
						)
					)
					(width 0)
					(fill yes)
				)
			)
		)
	)
	(footprint ""
		(layer "B.Cu")
		(at 31.496 -44.45 90)
		(property "Reference" "PC138"
			(at 0 0 90)
			(layer "B.SilkS")
			(hide yes)
			(effects
				(font
					(size 1.27 1.27)
				)
				(justify mirror)
			)
		)
		(property "Value" "SCD1U10V2KX-5GP"
			(at -1.8923 -1.2065 90)
			(unlocked yes)
			(layer "B.Fab")
			(hide yes)
			(effects
				(font
					(size 1.016 1.016)
					(thickness 0.1524)
				)
				(justify mirror)
			)
		)
		(property "Device Type" "C402H22"
			(at -1.8923 -2.7305 90)
			(unlocked yes)
			(layer "B.Fab")
			(hide yes)
			(effects
				(font
					(size 1.016 1.016)
					(thickness 0.1524)
				)
				(justify mirror)
			)
		)
		(duplicate_pad_numbers_are_jumpers no)
		(fp_rect
			(start 0.381 0.7366)
			(end -0.381 -0.7366)
			(stroke
				(width 0)
				(type default)
			)
			(fill no)
			(layer "B.CrtYd")
		)
		(fp_rect
			(start 0.381 0.7366)
			(end -0.381 -0.7366)
			(stroke
				(width 0)
				(type default)
			)
			(fill no)
			(layer "B.Fab")
		)
		(pad "1" smd custom
			(at 0 -0.4572 270)
			(size 0.1143 0.1143)
			(layers "B.Cu" "B.Mask" "B.Paste")
			(net "P1V5_STBY_OUT")
			(options
				(clearance outline)
				(anchor circle)
			)
			(primitives
				(gr_poly
					(pts
						(arc
							(start -0.254 0.1778)
							(mid -0.239121 0.213721)
							(end -0.2032 0.2286)
						)
						(arc
							(start 0.2032 0.2286)
							(mid 0.239121 0.213721)
							(end 0.254 0.1778)
						)
						(arc
							(start 0.254 -0.1778)
							(mid 0.239121 -0.213721)
							(end 0.2032 -0.2286)
						)
						(arc
							(start -0.2032 -0.2286)
							(mid -0.239121 -0.213721)
							(end -0.254 -0.1778)
						)
					)
					(width 0)
					(fill yes)
				)
			)
		)
		(pad "2" smd custom
			(at 0 0.4572 270)
			(size 0.1143 0.1143)
			(layers "B.Cu" "B.Mask" "B.Paste")
			(net "GND")
			(options
				(clearance outline)
				(anchor circle)
			)
			(primitives
				(gr_poly
					(pts
						(arc
							(start -0.254 0.1778)
							(mid -0.239121 0.213721)
							(end -0.2032 0.2286)
						)
						(arc
							(start 0.2032 0.2286)
							(mid 0.239121 0.213721)
							(end 0.254 0.1778)
						)
						(arc
							(start 0.254 -0.1778)
							(mid 0.239121 -0.213721)
							(end 0.2032 -0.2286)
						)
						(arc
							(start -0.2032 -0.2286)
							(mid -0.239121 -0.213721)
							(end -0.254 -0.1778)
						)
					)
					(width 0)
					(fill yes)
				)
			)
		)
	)
	(footprint ""
		(layer "B.Cu")
		(at 69.6214 -23.4188 -90)
		(property "Reference" "PC127"
			(at 0 0 90)
			(layer "B.SilkS")
			(hide yes)
			(effects
				(font
					(size 1.27 1.27)
				)
				(justify mirror)
			)
		)
		(property "Value" "SC1U16V3KX-5GP"
			(at 0.0254 -2.0193 270)
			(unlocked yes)
			(layer "B.Fab")
			(hide yes)
			(effects
				(font
					(size 1.016 1.016)
					(thickness 0.1524)
				)
				(justify mirror)
			)
		)
		(property "Device Type" "C603H36"
			(at 0.0254 -3.5433 270)
			(unlocked yes)
			(layer "B.Fab")
			(hide yes)
			(effects
				(font
					(size 1.016 1.016)
					(thickness 0.1524)
				)
				(justify mirror)
			)
		)
		(duplicate_pad_numbers_are_jumpers no)
		(fp_line
			(start 0.4064 0)
			(end -0.4064 0)
			(stroke
				(width 0.2286)
				(type default)
			)
			(layer "B.SilkS")
		)
		(fp_rect
			(start 0.635 1.1811)
			(end -0.635 -1.1811)
			(stroke
				(width 0)
				(type default)
			)
			(fill no)
			(layer "B.CrtYd")
		)
		(fp_rect
			(start 0.635 1.1811)
			(end -0.635 -1.1811)
			(stroke
				(width 0)
				(type default)
			)
			(fill no)
			(layer "B.Fab")
		)
		(pad "1" smd custom
			(at 0 -0.6604 90)
			(size 0.19685 0.19685)
			(layers "B.Cu" "B.Mask" "B.Paste")
			(net "VR_AVIN_P1V8_STBY")
			(options
				(clearance outline)
				(anchor circle)
			)
			(primitives
				(gr_poly
					(pts
						(arc
							(start 0.508 0.2921)
							(mid 0.478242 0.363942)
							(end 0.4064 0.3937)
						)
						(arc
							(start -0.4064 0.3937)
							(mid -0.478242 0.363942)
							(end -0.508 0.2921)
						)
						(arc
							(start -0.508 -0.2921)
							(mid -0.478242 -0.363942)
							(end -0.4064 -0.3937)
						)
						(arc
							(start 0.4064 -0.3937)
							(mid 0.478242 -0.363942)
							(end 0.508 -0.2921)
						)
					)
					(width 0)
					(fill yes)
				)
			)
		)
		(pad "2" smd custom
			(at 0 0.6604 90)
			(size 0.19685 0.19685)
			(layers "B.Cu" "B.Mask" "B.Paste")
			(net "AGND_P1V8_STBY")
			(options
				(clearance outline)
				(anchor circle)
			)
			(primitives
				(gr_poly
					(pts
						(arc
							(start 0.508 0.2921)
							(mid 0.478242 0.363942)
							(end 0.4064 0.3937)
						)
						(arc
							(start -0.4064 0.3937)
							(mid -0.478242 0.363942)
							(end -0.508 0.2921)
						)
						(arc
							(start -0.508 -0.2921)
							(mid -0.478242 -0.363942)
							(end -0.4064 -0.3937)
						)
						(arc
							(start 0.4064 -0.3937)
							(mid 0.478242 -0.363942)
							(end 0.508 -0.2921)
						)
					)
					(width 0)
					(fill yes)
				)
			)
		)
	)
	(footprint ""
		(layer "B.Cu")
		(at 134.366 -48.641 90)
		(property "Reference" "R397"
			(at 0 0 90)
			(layer "B.SilkS")
			(hide yes)
			(effects
				(font
					(size 1.27 1.27)
				)
				(justify mirror)
			)
		)
		(property "Value" "0R2J-2-GP"
			(at -1.7907 -1.1176 90)
			(unlocked yes)
			(layer "B.Fab")
			(hide yes)
			(effects
				(font
					(size 1.016 1.016)
					(thickness 0.1524)
				)
				(justify mirror)
			)
		)
		(property "Device Type" "R402H16"
			(at -1.7907 -2.6416 90)
			(unlocked yes)
			(layer "B.Fab")
			(hide yes)
			(effects
				(font
					(size 1.016 1.016)
					(thickness 0.1524)
				)
				(justify mirror)
			)
		)
		(duplicate_pad_numbers_are_jumpers no)
		(fp_rect
			(start 0.381 0.8382)
			(end -0.381 -0.8382)
			(stroke
				(width 0)
				(type default)
			)
			(fill no)
			(layer "B.CrtYd")
		)
		(fp_rect
			(start 0.381 0.8382)
			(end -0.381 -0.8382)
			(stroke
				(width 0)
				(type default)
			)
			(fill no)
			(layer "B.Fab")
		)
		(pad "1" smd custom
			(at 0 -0.4318 270)
			(size 0.127 0.127)
			(layers "B.Cu" "B.Mask" "B.Paste")
			(net "REV_CPU_FPGA_IO0")
			(options
				(clearance outline)
				(anchor circle)
			)
			(primitives
				(gr_poly
					(pts
						(arc
							(start -0.2032 0.2794)
							(mid -0.239121 0.264521)
							(end -0.254 0.2286)
						)
						(arc
							(start -0.254 -0.2286)
							(mid -0.239121 -0.264521)
							(end -0.2032 -0.2794)
						)
						(arc
							(start 0.2032 -0.2794)
							(mid 0.239121 -0.264521)
							(end 0.254 -0.2286)
						)
						(arc
							(start 0.254 0.2286)
							(mid 0.239121 0.264521)
							(end 0.2032 0.2794)
						)
					)
					(width 0)
					(fill yes)
				)
			)
		)
		(pad "2" smd custom
			(at 0 0.4318 270)
			(size 0.127 0.127)
			(layers "B.Cu" "B.Mask" "B.Paste")
			(net "REV_CPU_FPGA_R_IO0")
			(options
				(clearance outline)
				(anchor circle)
			)
			(primitives
				(gr_poly
					(pts
						(arc
							(start -0.2032 0.2794)
							(mid -0.239121 0.264521)
							(end -0.254 0.2286)
						)
						(arc
							(start -0.254 -0.2286)
							(mid -0.239121 -0.264521)
							(end -0.2032 -0.2794)
						)
						(arc
							(start 0.2032 -0.2794)
							(mid 0.239121 -0.264521)
							(end 0.254 -0.2286)
						)
						(arc
							(start 0.254 0.2286)
							(mid 0.239121 0.264521)
							(end 0.2032 0.2794)
						)
					)
					(width 0)
					(fill yes)
				)
			)
		)
	)
	(footprint ""
		(layer "B.Cu")
		(at 168.783 -12.600178 180)
		(property "Reference" "C332"
			(at 0 0 0)
			(layer "B.SilkS")
			(hide yes)
			(effects
				(font
					(size 1.27 1.27)
				)
				(justify mirror)
			)
		)
		(property "Value" "SCD1U16V2KX-3GP"
			(at -1.8923 -1.2065 180)
			(unlocked yes)
			(layer "B.Fab")
			(hide yes)
			(effects
				(font
					(size 1.016 1.016)
					(thickness 0.1524)
				)
				(justify mirror)
			)
		)
		(property "Device Type" "C402H22"
			(at -1.8923 -2.7305 180)
			(unlocked yes)
			(layer "B.Fab")
			(hide yes)
			(effects
				(font
					(size 1.016 1.016)
					(thickness 0.1524)
				)
				(justify mirror)
			)
		)
		(duplicate_pad_numbers_are_jumpers no)
		(fp_rect
			(start 0.381 0.7366)
			(end -0.381 -0.7366)
			(stroke
				(width 0)
				(type default)
			)
			(fill no)
			(layer "B.CrtYd")
		)
		(fp_rect
			(start 0.381 0.7366)
			(end -0.381 -0.7366)
			(stroke
				(width 0)
				(type default)
			)
			(fill no)
			(layer "B.Fab")
		)
		(pad "1" smd custom
			(at 0 -0.4572)
			(size 0.1143 0.1143)
			(layers "B.Cu" "B.Mask" "B.Paste")
			(net "PV_VDDR")
			(options
				(clearance outline)
				(anchor circle)
			)
			(primitives
				(gr_poly
					(pts
						(arc
							(start -0.254 0.1778)
							(mid -0.239121 0.213721)
							(end -0.2032 0.2286)
						)
						(arc
							(start 0.2032 0.2286)
							(mid 0.239121 0.213721)
							(end 0.254 0.1778)
						)
						(arc
							(start 0.254 -0.1778)
							(mid 0.239121 -0.213721)
							(end 0.2032 -0.2286)
						)
						(arc
							(start -0.2032 -0.2286)
							(mid -0.239121 -0.213721)
							(end -0.254 -0.1778)
						)
					)
					(width 0)
					(fill yes)
				)
			)
		)
		(pad "2" smd custom
			(at 0 0.4572)
			(size 0.1143 0.1143)
			(layers "B.Cu" "B.Mask" "B.Paste")
			(net "GND")
			(options
				(clearance outline)
				(anchor circle)
			)
			(primitives
				(gr_poly
					(pts
						(arc
							(start -0.254 0.1778)
							(mid -0.239121 0.213721)
							(end -0.2032 0.2286)
						)
						(arc
							(start 0.2032 0.2286)
							(mid 0.239121 0.213721)
							(end 0.254 0.1778)
						)
						(arc
							(start 0.254 -0.1778)
							(mid 0.239121 -0.213721)
							(end 0.2032 -0.2286)
						)
						(arc
							(start -0.2032 -0.2286)
							(mid -0.239121 -0.213721)
							(end -0.254 -0.1778)
						)
					)
					(width 0)
					(fill yes)
				)
			)
		)
	)
	(footprint ""
		(layer "B.Cu")
		(at 35.941 -44.577)
		(property "Reference" "X2"
			(at 0 0 0)
			(layer "B.SilkS")
			(hide yes)
			(effects
				(font
					(size 1.27 1.27)
				)
				(justify mirror)
			)
		)
		(property "Value" "XTAL-14D31818MHZ-1-GP"
			(at 2.794 1.4478 0)
			(unlocked yes)
			(layer "B.Fab")
			(hide yes)
			(effects
				(font
					(size 1.016 1.016)
					(thickness 0.1524)
				)
				(justify mirror)
			)
		)
		(property "Device Type" "SMD49-5032H54"
			(at 2.794 -0.0762 0)
			(unlocked yes)
			(layer "B.Fab")
			(hide yes)
			(effects
				(font
					(size 1.016 1.016)
					(thickness 0.1524)
				)
				(justify mirror)
			)
		)
		(duplicate_pad_numbers_are_jumpers no)
		(fp_rect
			(start 1.8542 2.9972)
			(end -1.8542 -2.9972)
			(stroke
				(width 0)
				(type default)
			)
			(fill no)
			(layer "B.CrtYd")
		)
		(fp_rect
			(start 1.8542 2.9972)
			(end -1.8542 -2.9972)
			(stroke
				(width 0)
				(type default)
			)
			(fill no)
			(layer "B.Fab")
		)
		(pad "1" smd rect
			(at 0 -1.911096 180)
			(size 2.2606 1.9304)
			(layers "B.Cu" "B.Mask" "B.Paste")
			(net "XTAL_CLK_GEN_IN")
		)
		(pad "2" smd rect
			(at 0 1.911096 180)
			(size 2.2606 1.9304)
			(layers "B.Cu" "B.Mask" "B.Paste")
			(net "XTAL_CLK_GEN_OUT")
		)
		(zone
			(layer "B.Cu")
			(hatch none 0.5)
			(connect_pads
				(clearance 0)
			)
			(min_thickness 0.25)
			(keepout
				(tracks not_allowed)
				(vias allowed)
				(pads allowed)
				(copperpour not_allowed)
				(footprints allowed)
			)
			(placement
				(enabled no)
				(sheetname "")
			)
			(fill
				(thermal_gap 0.5)
				(thermal_bridge_width 0.5)
				(island_removal_mode 0)
			)
			(polygon
				(pts
					(xy 34.8107 -45.522896) (xy 34.3408 -45.522896) (xy 34.3408 -47.453296) (xy 34.8107 -47.453296)
				)
			)
		)
		(zone
			(layer "B.Cu")
			(hatch none 0.5)
			(connect_pads
				(clearance 0)
			)
			(min_thickness 0.25)
			(keepout
				(tracks allowed)
				(vias not_allowed)
				(pads allowed)
				(copperpour not_allowed)
				(footprints allowed)
			)
			(placement
				(enabled no)
				(sheetname "")
			)
			(fill
				(thermal_gap 0.5)
				(thermal_bridge_width 0.5)
				(island_removal_mode 0)
			)
			(polygon
				(pts
					(xy 34.8107 -45.522896) (xy 34.3408 -45.522896) (xy 34.3408 -47.453296) (xy 34.8107 -47.453296)
				)
			)
		)
		(zone
			(layer "B.Cu")
			(hatch none 0.5)
			(connect_pads
				(clearance 0)
			)
			(min_thickness 0.25)
			(keepout
				(tracks not_allowed)
				(vias allowed)
				(pads allowed)
				(copperpour not_allowed)
				(footprints allowed)
			)
			(placement
				(enabled no)
				(sheetname "")
			)
			(fill
				(thermal_gap 0.5)
				(thermal_bridge_width 0.5)
				(island_removal_mode 0)
			)
			(polygon
				(pts
					(xy 34.8107 -41.700704) (xy 34.3408 -41.700704) (xy 34.3408 -43.631104) (xy 34.8107 -43.631104)
				)
			)
		)
		(zone
			(layer "B.Cu")
			(hatch none 0.5)
			(connect_pads
				(clearance 0)
			)
			(min_thickness 0.25)
			(keepout
				(tracks allowed)
				(vias not_allowed)
				(pads allowed)
				(copperpour not_allowed)
				(footprints allowed)
			)
			(placement
				(enabled no)
				(sheetname "")
			)
			(fill
				(thermal_gap 0.5)
				(thermal_bridge_width 0.5)
				(island_removal_mode 0)
			)
			(polygon
				(pts
					(xy 34.8107 -41.700704) (xy 34.3408 -41.700704) (xy 34.3408 -43.631104) (xy 34.8107 -43.631104)
				)
			)
		)
		(zone
			(layer "B.Cu")
			(hatch none 0.5)
			(connect_pads
				(clearance 0)
			)
			(min_thickness 0.25)
			(keepout
				(tracks allowed)
				(vias not_allowed)
				(pads allowed)
				(copperpour not_allowed)
				(footprints allowed)
			)
			(placement
				(enabled no)
				(sheetname "")
			)
			(fill
				(thermal_gap 0.5)
				(thermal_bridge_width 0.5)
				(island_removal_mode 0)
			)
			(polygon
				(pts
					(xy 37.0713 -45.522896) (xy 37.0713 -43.631104) (xy 34.8107 -43.631104) (xy 34.8107 -45.522896)
				)
			)
		)
		(zone
			(layer "B.Cu")
			(hatch none 0.5)
			(connect_pads
				(clearance 0)
			)
			(min_thickness 0.25)
			(keepout
				(tracks allowed)
				(vias not_allowed)
				(pads allowed)
				(copperpour not_allowed)
				(footprints allowed)
			)
			(placement
				(enabled no)
				(sheetname "")
			)
			(fill
				(thermal_gap 0.5)
				(thermal_bridge_width 0.5)
				(island_removal_mode 0)
			)
			(polygon
				(pts
					(xy 37.5412 -45.522896) (xy 37.0713 -45.522896) (xy 37.0713 -47.453296) (xy 37.5412 -47.453296)
				)
			)
		)
		(zone
			(layer "B.Cu")
			(hatch none 0.5)
			(connect_pads
				(clearance 0)
			)
			(min_thickness 0.25)
			(keepout
				(tracks not_allowed)
				(vias allowed)
				(pads allowed)
				(copperpour not_allowed)
				(footprints allowed)
			)
			(placement
				(enabled no)
				(sheetname "")
			)
			(fill
				(thermal_gap 0.5)
				(thermal_bridge_width 0.5)
				(island_removal_mode 0)
			)
			(polygon
				(pts
					(xy 37.5412 -45.522896) (xy 37.0713 -45.522896) (xy 37.0713 -47.453296) (xy 37.5412 -47.453296)
				)
			)
		)
		(zone
			(layer "B.Cu")
			(hatch none 0.5)
			(connect_pads
				(clearance 0)
			)
			(min_thickness 0.25)
			(keepout
				(tracks allowed)
				(vias not_allowed)
				(pads allowed)
				(copperpour not_allowed)
				(footprints allowed)
			)
			(placement
				(enabled no)
				(sheetname "")
			)
			(fill
				(thermal_gap 0.5)
				(thermal_bridge_width 0.5)
				(island_removal_mode 0)
			)
			(polygon
				(pts
					(xy 37.5412 -41.700704) (xy 37.0713 -41.700704) (xy 37.0713 -43.631104) (xy 37.5412 -43.631104)
				)
			)
		)
		(zone
			(layer "B.Cu")
			(hatch none 0.5)
			(connect_pads
				(clearance 0)
			)
			(min_thickness 0.25)
			(keepout
				(tracks not_allowed)
				(vias allowed)
				(pads allowed)
				(copperpour not_allowed)
				(footprints allowed)
			)
			(placement
				(enabled no)
				(sheetname "")
			)
			(fill
				(thermal_gap 0.5)
				(thermal_bridge_width 0.5)
				(island_removal_mode 0)
			)
			(polygon
				(pts
					(xy 37.5412 -41.700704) (xy 37.0713 -41.700704) (xy 37.0713 -43.631104) (xy 37.5412 -43.631104)
				)
			)
		)
	)
	(footprint ""
		(layer "B.Cu")
		(at 197.231 -66.802 90)
		(property "Reference" "R85"
			(at 0 0 90)
			(layer "B.SilkS")
			(hide yes)
			(effects
				(font
					(size 1.27 1.27)
				)
				(justify mirror)
			)
		)
		(property "Value" "300R2F-GP"
			(at -1.7907 -1.1176 90)
			(unlocked yes)
			(layer "B.Fab")
			(hide yes)
			(effects
				(font
					(size 1.016 1.016)
					(thickness 0.1524)
				)
				(justify mirror)
			)
		)
		(property "Device Type" "R402H16"
			(at -1.7907 -2.6416 90)
			(unlocked yes)
			(layer "B.Fab")
			(hide yes)
			(effects
				(font
					(size 1.016 1.016)
					(thickness 0.1524)
				)
				(justify mirror)
			)
		)
		(duplicate_pad_numbers_are_jumpers no)
		(fp_rect
			(start 0.381 0.8382)
			(end -0.381 -0.8382)
			(stroke
				(width 0)
				(type default)
			)
			(fill no)
			(layer "B.CrtYd")
		)
		(fp_rect
			(start 0.381 0.8382)
			(end -0.381 -0.8382)
			(stroke
				(width 0)
				(type default)
			)
			(fill no)
			(layer "B.Fab")
		)
		(pad "1" smd custom
			(at 0 -0.4318 270)
			(size 0.127 0.127)
			(layers "B.Cu" "B.Mask" "B.Paste")
			(net "P3V3")
			(options
				(clearance outline)
				(anchor circle)
			)
			(primitives
				(gr_poly
					(pts
						(arc
							(start -0.2032 0.2794)
							(mid -0.239121 0.264521)
							(end -0.254 0.2286)
						)
						(arc
							(start -0.254 -0.2286)
							(mid -0.239121 -0.264521)
							(end -0.2032 -0.2794)
						)
						(arc
							(start 0.2032 -0.2794)
							(mid 0.239121 -0.264521)
							(end 0.254 -0.2286)
						)
						(arc
							(start 0.254 0.2286)
							(mid 0.239121 0.264521)
							(end 0.2032 0.2794)
						)
					)
					(width 0)
					(fill yes)
				)
			)
		)
		(pad "2" smd custom
			(at 0 0.4318 270)
			(size 0.127 0.127)
			(layers "B.Cu" "B.Mask" "B.Paste")
			(net "BEEP_LED")
			(options
				(clearance outline)
				(anchor circle)
			)
			(primitives
				(gr_poly
					(pts
						(arc
							(start -0.2032 0.2794)
							(mid -0.239121 0.264521)
							(end -0.254 0.2286)
						)
						(arc
							(start -0.254 -0.2286)
							(mid -0.239121 -0.264521)
							(end -0.2032 -0.2794)
						)
						(arc
							(start 0.2032 -0.2794)
							(mid 0.239121 -0.264521)
							(end 0.254 -0.2286)
						)
						(arc
							(start 0.254 0.2286)
							(mid 0.239121 0.264521)
							(end 0.2032 0.2794)
						)
					)
					(width 0)
					(fill yes)
				)
			)
		)
	)
	(footprint ""
		(layer "B.Cu")
		(at 53.467 -19.558 -90)
		(property "Reference" "C231"
			(at 0 0 90)
			(layer "B.SilkS")
			(hide yes)
			(effects
				(font
					(size 1.27 1.27)
				)
				(justify mirror)
			)
		)
		(property "Value" "SCD1U16V2KX-3GP"
			(at -1.1811 -2.7051 270)
			(unlocked yes)
			(layer "B.Fab")
			(hide yes)
			(effects
				(font
					(size 1.016 1.016)
					(thickness 0.1524)
				)
				(justify mirror)
			)
		)
		(property "Device Type" "C402H22"
			(at -1.1811 -4.2291 270)
			(unlocked yes)
			(layer "B.Fab")
			(hide yes)
			(effects
				(font
					(size 1.016 1.016)
					(thickness 0.1524)
				)
				(justify mirror)
			)
		)
		(duplicate_pad_numbers_are_jumpers no)
		(fp_rect
			(start 0.381 0.7366)
			(end -0.381 -0.7366)
			(stroke
				(width 0)
				(type default)
			)
			(fill no)
			(layer "B.CrtYd")
		)
		(fp_rect
			(start 0.381 0.7366)
			(end -0.381 -0.7366)
			(stroke
				(width 0)
				(type default)
			)
			(fill no)
			(layer "B.Fab")
		)
		(pad "1" smd custom
			(at 0 -0.4572 90)
			(size 0.1143 0.1143)
			(layers "B.Cu" "B.Mask" "B.Paste")
			(net "P3V3")
			(options
				(clearance outline)
				(anchor circle)
			)
			(primitives
				(gr_poly
					(pts
						(arc
							(start -0.254 0.1778)
							(mid -0.239121 0.213721)
							(end -0.2032 0.2286)
						)
						(arc
							(start 0.2032 0.2286)
							(mid 0.239121 0.213721)
							(end 0.254 0.1778)
						)
						(arc
							(start 0.254 -0.1778)
							(mid 0.239121 -0.213721)
							(end 0.2032 -0.2286)
						)
						(arc
							(start -0.2032 -0.2286)
							(mid -0.239121 -0.213721)
							(end -0.254 -0.1778)
						)
					)
					(width 0)
					(fill yes)
				)
			)
		)
		(pad "2" smd custom
			(at 0 0.4572 90)
			(size 0.1143 0.1143)
			(layers "B.Cu" "B.Mask" "B.Paste")
			(net "GND")
			(options
				(clearance outline)
				(anchor circle)
			)
			(primitives
				(gr_poly
					(pts
						(arc
							(start -0.254 0.1778)
							(mid -0.239121 0.213721)
							(end -0.2032 0.2286)
						)
						(arc
							(start 0.2032 0.2286)
							(mid 0.239121 0.213721)
							(end 0.254 0.1778)
						)
						(arc
							(start 0.254 -0.1778)
							(mid 0.239121 -0.213721)
							(end 0.2032 -0.2286)
						)
						(arc
							(start -0.2032 -0.2286)
							(mid -0.239121 -0.213721)
							(end -0.254 -0.1778)
						)
					)
					(width 0)
					(fill yes)
				)
			)
		)
	)
	(footprint ""
		(layer "B.Cu")
		(at 83.3374 -28.9052 180)
		(property "Reference" "R364"
			(at 0 0 0)
			(layer "B.SilkS")
			(hide yes)
			(effects
				(font
					(size 1.27 1.27)
				)
				(justify mirror)
			)
		)
		(property "Value" "402R2F-GP"
			(at -0.064008 -3.993896 180)
			(unlocked yes)
			(layer "B.Fab")
			(hide yes)
			(effects
				(font
					(size 1.016 1.016)
					(thickness 0.1524)
				)
				(justify mirror)
			)
		)
		(property "Device Type" "R402H16"
			(at -0.064008 -5.517896 180)
			(unlocked yes)
			(layer "B.Fab")
			(hide yes)
			(effects
				(font
					(size 1.016 1.016)
					(thickness 0.1524)
				)
				(justify mirror)
			)
		)
		(duplicate_pad_numbers_are_jumpers no)
		(fp_rect
			(start 0.381 0.8382)
			(end -0.381 -0.8382)
			(stroke
				(width 0)
				(type default)
			)
			(fill no)
			(layer "B.CrtYd")
		)
		(fp_rect
			(start 0.381 0.8382)
			(end -0.381 -0.8382)
			(stroke
				(width 0)
				(type default)
			)
			(fill no)
			(layer "B.Fab")
		)
		(pad "1" smd custom
			(at 0 -0.4318)
			(size 0.127 0.127)
			(layers "B.Cu" "B.Mask" "B.Paste")
			(net "SATA2_OBS_P")
			(options
				(clearance outline)
				(anchor circle)
			)
			(primitives
				(gr_poly
					(pts
						(arc
							(start -0.2032 0.2794)
							(mid -0.239121 0.264521)
							(end -0.254 0.2286)
						)
						(arc
							(start -0.254 -0.2286)
							(mid -0.239121 -0.264521)
							(end -0.2032 -0.2794)
						)
						(arc
							(start 0.2032 -0.2794)
							(mid 0.239121 -0.264521)
							(end 0.254 -0.2286)
						)
						(arc
							(start 0.254 0.2286)
							(mid 0.239121 0.264521)
							(end 0.2032 0.2794)
						)
					)
					(width 0)
					(fill yes)
				)
			)
		)
		(pad "2" smd custom
			(at 0 0.4318)
			(size 0.127 0.127)
			(layers "B.Cu" "B.Mask" "B.Paste")
			(net "SATA2_OBS_N")
			(options
				(clearance outline)
				(anchor circle)
			)
			(primitives
				(gr_poly
					(pts
						(arc
							(start -0.2032 0.2794)
							(mid -0.239121 0.264521)
							(end -0.254 0.2286)
						)
						(arc
							(start -0.254 -0.2286)
							(mid -0.239121 -0.264521)
							(end -0.2032 -0.2794)
						)
						(arc
							(start 0.2032 -0.2794)
							(mid 0.239121 -0.264521)
							(end 0.254 -0.2286)
						)
						(arc
							(start 0.254 0.2286)
							(mid 0.239121 0.264521)
							(end 0.2032 0.2794)
						)
					)
					(width 0)
					(fill yes)
				)
			)
		)
	)
	(footprint ""
		(layer "B.Cu")
		(at 94.0562 -33.782)
		(property "Reference" "C217"
			(at 0 0 0)
			(layer "B.SilkS")
			(hide yes)
			(effects
				(font
					(size 1.27 1.27)
				)
				(justify mirror)
			)
		)
		(property "Value" "SC1U10V2KX-1GP"
			(at -1.1811 -2.7051 0)
			(unlocked yes)
			(layer "B.Fab")
			(hide yes)
			(effects
				(font
					(size 1.016 1.016)
					(thickness 0.1524)
				)
				(justify mirror)
			)
		)
		(property "Device Type" "C402H22"
			(at -1.1811 -4.2291 0)
			(unlocked yes)
			(layer "B.Fab")
			(hide yes)
			(effects
				(font
					(size 1.016 1.016)
					(thickness 0.1524)
				)
				(justify mirror)
			)
		)
		(duplicate_pad_numbers_are_jumpers no)
		(fp_rect
			(start 0.381 0.7366)
			(end -0.381 -0.7366)
			(stroke
				(width 0)
				(type default)
			)
			(fill no)
			(layer "B.CrtYd")
		)
		(fp_rect
			(start 0.381 0.7366)
			(end -0.381 -0.7366)
			(stroke
				(width 0)
				(type default)
			)
			(fill no)
			(layer "B.Fab")
		)
		(pad "1" smd custom
			(at 0 -0.4572 180)
			(size 0.1143 0.1143)
			(layers "B.Cu" "B.Mask" "B.Paste")
			(net "P1V0_STBY")
			(options
				(clearance outline)
				(anchor circle)
			)
			(primitives
				(gr_poly
					(pts
						(arc
							(start -0.254 0.1778)
							(mid -0.239121 0.213721)
							(end -0.2032 0.2286)
						)
						(arc
							(start 0.2032 0.2286)
							(mid 0.239121 0.213721)
							(end 0.254 0.1778)
						)
						(arc
							(start 0.254 -0.1778)
							(mid 0.239121 -0.213721)
							(end 0.2032 -0.2286)
						)
						(arc
							(start -0.2032 -0.2286)
							(mid -0.239121 -0.213721)
							(end -0.254 -0.1778)
						)
					)
					(width 0)
					(fill yes)
				)
			)
		)
		(pad "2" smd custom
			(at 0 0.4572 180)
			(size 0.1143 0.1143)
			(layers "B.Cu" "B.Mask" "B.Paste")
			(net "GND")
			(options
				(clearance outline)
				(anchor circle)
			)
			(primitives
				(gr_poly
					(pts
						(arc
							(start -0.254 0.1778)
							(mid -0.239121 0.213721)
							(end -0.2032 0.2286)
						)
						(arc
							(start 0.2032 0.2286)
							(mid 0.239121 0.213721)
							(end 0.254 0.1778)
						)
						(arc
							(start 0.254 -0.1778)
							(mid 0.239121 -0.213721)
							(end 0.2032 -0.2286)
						)
						(arc
							(start -0.2032 -0.2286)
							(mid -0.239121 -0.213721)
							(end -0.254 -0.1778)
						)
					)
					(width 0)
					(fill yes)
				)
			)
		)
	)
	(footprint ""
		(layer "B.Cu")
		(at 38.608 -42.672 90)
		(property "Reference" "C65"
			(at 0 0 90)
			(layer "B.SilkS")
			(hide yes)
			(effects
				(font
					(size 1.27 1.27)
				)
				(justify mirror)
			)
		)
		(property "Value" "SC27P50V2GN-GP"
			(at -1.8923 -1.2065 90)
			(unlocked yes)
			(layer "B.Fab")
			(hide yes)
			(effects
				(font
					(size 1.016 1.016)
					(thickness 0.1524)
				)
				(justify mirror)
			)
		)
		(property "Device Type" "C402H22"
			(at -1.8923 -2.7305 90)
			(unlocked yes)
			(layer "B.Fab")
			(hide yes)
			(effects
				(font
					(size 1.016 1.016)
					(thickness 0.1524)
				)
				(justify mirror)
			)
		)
		(duplicate_pad_numbers_are_jumpers no)
		(fp_rect
			(start 0.381 0.7366)
			(end -0.381 -0.7366)
			(stroke
				(width 0)
				(type default)
			)
			(fill no)
			(layer "B.CrtYd")
		)
		(fp_rect
			(start 0.381 0.7366)
			(end -0.381 -0.7366)
			(stroke
				(width 0)
				(type default)
			)
			(fill no)
			(layer "B.Fab")
		)
		(pad "1" smd custom
			(at 0 -0.4572 270)
			(size 0.1143 0.1143)
			(layers "B.Cu" "B.Mask" "B.Paste")
			(net "XTAL_CLK_GEN_OUT")
			(options
				(clearance outline)
				(anchor circle)
			)
			(primitives
				(gr_poly
					(pts
						(arc
							(start -0.254 0.1778)
							(mid -0.239121 0.213721)
							(end -0.2032 0.2286)
						)
						(arc
							(start 0.2032 0.2286)
							(mid 0.239121 0.213721)
							(end 0.254 0.1778)
						)
						(arc
							(start 0.254 -0.1778)
							(mid 0.239121 -0.213721)
							(end 0.2032 -0.2286)
						)
						(arc
							(start -0.2032 -0.2286)
							(mid -0.239121 -0.213721)
							(end -0.254 -0.1778)
						)
					)
					(width 0)
					(fill yes)
				)
			)
		)
		(pad "2" smd custom
			(at 0 0.4572 270)
			(size 0.1143 0.1143)
			(layers "B.Cu" "B.Mask" "B.Paste")
			(net "GND")
			(options
				(clearance outline)
				(anchor circle)
			)
			(primitives
				(gr_poly
					(pts
						(arc
							(start -0.254 0.1778)
							(mid -0.239121 0.213721)
							(end -0.2032 0.2286)
						)
						(arc
							(start 0.2032 0.2286)
							(mid 0.239121 0.213721)
							(end 0.254 0.1778)
						)
						(arc
							(start 0.254 -0.1778)
							(mid 0.239121 -0.213721)
							(end 0.2032 -0.2286)
						)
						(arc
							(start -0.2032 -0.2286)
							(mid -0.239121 -0.213721)
							(end -0.254 -0.1778)
						)
					)
					(width 0)
					(fill yes)
				)
			)
		)
	)
	(footprint ""
		(layer "B.Cu")
		(at 92.71 -45.6438 -90)
		(property "Reference" "C155"
			(at 0 0 90)
			(layer "B.SilkS")
			(hide yes)
			(effects
				(font
					(size 1.27 1.27)
				)
				(justify mirror)
			)
		)
		(property "Value" "SC1U10V2KX-1GP"
			(at -1.1811 -2.7051 270)
			(unlocked yes)
			(layer "B.Fab")
			(hide yes)
			(effects
				(font
					(size 1.016 1.016)
					(thickness 0.1524)
				)
				(justify mirror)
			)
		)
		(property "Device Type" "C402H22"
			(at -1.1811 -4.2291 270)
			(unlocked yes)
			(layer "B.Fab")
			(hide yes)
			(effects
				(font
					(size 1.016 1.016)
					(thickness 0.1524)
				)
				(justify mirror)
			)
		)
		(duplicate_pad_numbers_are_jumpers no)
		(fp_rect
			(start 0.381 0.7366)
			(end -0.381 -0.7366)
			(stroke
				(width 0)
				(type default)
			)
			(fill no)
			(layer "B.CrtYd")
		)
		(fp_rect
			(start 0.381 0.7366)
			(end -0.381 -0.7366)
			(stroke
				(width 0)
				(type default)
			)
			(fill no)
			(layer "B.Fab")
		)
		(pad "1" smd custom
			(at 0 -0.4572 90)
			(size 0.1143 0.1143)
			(layers "B.Cu" "B.Mask" "B.Paste")
			(net "P1V0")
			(options
				(clearance outline)
				(anchor circle)
			)
			(primitives
				(gr_poly
					(pts
						(arc
							(start -0.254 0.1778)
							(mid -0.239121 0.213721)
							(end -0.2032 0.2286)
						)
						(arc
							(start 0.2032 0.2286)
							(mid 0.239121 0.213721)
							(end 0.254 0.1778)
						)
						(arc
							(start 0.254 -0.1778)
							(mid 0.239121 -0.213721)
							(end 0.2032 -0.2286)
						)
						(arc
							(start -0.2032 -0.2286)
							(mid -0.239121 -0.213721)
							(end -0.254 -0.1778)
						)
					)
					(width 0)
					(fill yes)
				)
			)
		)
		(pad "2" smd custom
			(at 0 0.4572 90)
			(size 0.1143 0.1143)
			(layers "B.Cu" "B.Mask" "B.Paste")
			(net "GND")
			(options
				(clearance outline)
				(anchor circle)
			)
			(primitives
				(gr_poly
					(pts
						(arc
							(start -0.254 0.1778)
							(mid -0.239121 0.213721)
							(end -0.2032 0.2286)
						)
						(arc
							(start 0.2032 0.2286)
							(mid 0.239121 0.213721)
							(end 0.254 0.1778)
						)
						(arc
							(start 0.254 -0.1778)
							(mid 0.239121 -0.213721)
							(end 0.2032 -0.2286)
						)
						(arc
							(start -0.2032 -0.2286)
							(mid -0.239121 -0.213721)
							(end -0.254 -0.1778)
						)
					)
					(width 0)
					(fill yes)
				)
			)
		)
	)
	(footprint ""
		(layer "B.Cu")
		(at 197.993 -42.672 -90)
		(property "Reference" "R155"
			(at 0 0 90)
			(layer "B.SilkS")
			(hide yes)
			(effects
				(font
					(size 1.27 1.27)
				)
				(justify mirror)
			)
		)
		(property "Value" "300R2F-GP"
			(at -0.064008 -3.993896 270)
			(unlocked yes)
			(layer "B.Fab")
			(hide yes)
			(effects
				(font
					(size 1.016 1.016)
					(thickness 0.1524)
				)
				(justify mirror)
			)
		)
		(property "Device Type" "R402H16"
			(at -0.064008 -5.517896 270)
			(unlocked yes)
			(layer "B.Fab")
			(hide yes)
			(effects
				(font
					(size 1.016 1.016)
					(thickness 0.1524)
				)
				(justify mirror)
			)
		)
		(duplicate_pad_numbers_are_jumpers no)
		(fp_rect
			(start 0.381 0.8382)
			(end -0.381 -0.8382)
			(stroke
				(width 0)
				(type default)
			)
			(fill no)
			(layer "B.CrtYd")
		)
		(fp_rect
			(start 0.381 0.8382)
			(end -0.381 -0.8382)
			(stroke
				(width 0)
				(type default)
			)
			(fill no)
			(layer "B.Fab")
		)
		(pad "1" smd custom
			(at 0 -0.4318 90)
			(size 0.127 0.127)
			(layers "B.Cu" "B.Mask" "B.Paste")
			(net "PORT80_R_BIT6")
			(options
				(clearance outline)
				(anchor circle)
			)
			(primitives
				(gr_poly
					(pts
						(arc
							(start -0.2032 0.2794)
							(mid -0.239121 0.264521)
							(end -0.254 0.2286)
						)
						(arc
							(start -0.254 -0.2286)
							(mid -0.239121 -0.264521)
							(end -0.2032 -0.2794)
						)
						(arc
							(start 0.2032 -0.2794)
							(mid 0.239121 -0.264521)
							(end 0.254 -0.2286)
						)
						(arc
							(start 0.254 0.2286)
							(mid 0.239121 0.264521)
							(end 0.2032 0.2794)
						)
					)
					(width 0)
					(fill yes)
				)
			)
		)
		(pad "2" smd custom
			(at 0 0.4318 90)
			(size 0.127 0.127)
			(layers "B.Cu" "B.Mask" "B.Paste")
			(net "P3V3_STBY")
			(options
				(clearance outline)
				(anchor circle)
			)
			(primitives
				(gr_poly
					(pts
						(arc
							(start -0.2032 0.2794)
							(mid -0.239121 0.264521)
							(end -0.254 0.2286)
						)
						(arc
							(start -0.254 -0.2286)
							(mid -0.239121 -0.264521)
							(end -0.2032 -0.2794)
						)
						(arc
							(start 0.2032 -0.2794)
							(mid 0.239121 -0.264521)
							(end 0.254 -0.2286)
						)
						(arc
							(start 0.254 0.2286)
							(mid 0.239121 0.264521)
							(end 0.2032 0.2794)
						)
					)
					(width 0)
					(fill yes)
				)
			)
		)
	)
	(footprint ""
		(layer "B.Cu")
		(at 197.612 -4.6736 180)
		(property "Reference" "R384"
			(at 0 0 0)
			(layer "B.SilkS")
			(hide yes)
			(effects
				(font
					(size 1.27 1.27)
				)
				(justify mirror)
			)
		)
		(property "Value" "0R2J-2-GP"
			(at -0.064008 -3.993896 180)
			(unlocked yes)
			(layer "B.Fab")
			(hide yes)
			(effects
				(font
					(size 1.016 1.016)
					(thickness 0.1524)
				)
				(justify mirror)
			)
		)
		(property "Device Type" "R402H16"
			(at -0.064008 -5.517896 180)
			(unlocked yes)
			(layer "B.Fab")
			(hide yes)
			(effects
				(font
					(size 1.016 1.016)
					(thickness 0.1524)
				)
				(justify mirror)
			)
		)
		(duplicate_pad_numbers_are_jumpers no)
		(fp_rect
			(start 0.381 0.8382)
			(end -0.381 -0.8382)
			(stroke
				(width 0)
				(type default)
			)
			(fill no)
			(layer "B.CrtYd")
		)
		(fp_rect
			(start 0.381 0.8382)
			(end -0.381 -0.8382)
			(stroke
				(width 0)
				(type default)
			)
			(fill no)
			(layer "B.Fab")
		)
		(pad "1" smd custom
			(at 0 -0.4318)
			(size 0.127 0.127)
			(layers "B.Cu" "B.Mask" "B.Paste")
			(net "SMB_M_B0_R_DATA")
			(options
				(clearance outline)
				(anchor circle)
			)
			(primitives
				(gr_poly
					(pts
						(arc
							(start -0.2032 0.2794)
							(mid -0.239121 0.264521)
							(end -0.254 0.2286)
						)
						(arc
							(start -0.254 -0.2286)
							(mid -0.239121 -0.264521)
							(end -0.2032 -0.2794)
						)
						(arc
							(start 0.2032 -0.2794)
							(mid 0.239121 -0.264521)
							(end 0.254 -0.2286)
						)
						(arc
							(start 0.254 0.2286)
							(mid 0.239121 0.264521)
							(end 0.2032 0.2794)
						)
					)
					(width 0)
					(fill yes)
				)
			)
		)
		(pad "2" smd custom
			(at 0 0.4318)
			(size 0.127 0.127)
			(layers "B.Cu" "B.Mask" "B.Paste")
			(net "SMB_HOST_LV_DATA")
			(options
				(clearance outline)
				(anchor circle)
			)
			(primitives
				(gr_poly
					(pts
						(arc
							(start -0.2032 0.2794)
							(mid -0.239121 0.264521)
							(end -0.254 0.2286)
						)
						(arc
							(start -0.254 -0.2286)
							(mid -0.239121 -0.264521)
							(end -0.2032 -0.2794)
						)
						(arc
							(start 0.2032 -0.2794)
							(mid 0.239121 -0.264521)
							(end 0.254 -0.2286)
						)
						(arc
							(start 0.254 0.2286)
							(mid 0.239121 0.264521)
							(end 0.2032 0.2794)
						)
					)
					(width 0)
					(fill yes)
				)
			)
		)
	)
	(footprint ""
		(layer "B.Cu")
		(at 95.60306 -48.0441 180)
		(property "Reference" "C145"
			(at 0 0 0)
			(layer "B.SilkS")
			(hide yes)
			(effects
				(font
					(size 1.27 1.27)
				)
				(justify mirror)
			)
		)
		(property "Value" "SC1U10V2KX-1GP"
			(at -1.1811 -2.7051 180)
			(unlocked yes)
			(layer "B.Fab")
			(hide yes)
			(effects
				(font
					(size 1.016 1.016)
					(thickness 0.1524)
				)
				(justify mirror)
			)
		)
		(property "Device Type" "C402H22"
			(at -1.1811 -4.2291 180)
			(unlocked yes)
			(layer "B.Fab")
			(hide yes)
			(effects
				(font
					(size 1.016 1.016)
					(thickness 0.1524)
				)
				(justify mirror)
			)
		)
		(duplicate_pad_numbers_are_jumpers no)
		(fp_rect
			(start 0.381 0.7366)
			(end -0.381 -0.7366)
			(stroke
				(width 0)
				(type default)
			)
			(fill no)
			(layer "B.CrtYd")
		)
		(fp_rect
			(start 0.381 0.7366)
			(end -0.381 -0.7366)
			(stroke
				(width 0)
				(type default)
			)
			(fill no)
			(layer "B.Fab")
		)
		(pad "1" smd custom
			(at 0 -0.4572)
			(size 0.1143 0.1143)
			(layers "B.Cu" "B.Mask" "B.Paste")
			(net "P1V0")
			(options
				(clearance outline)
				(anchor circle)
			)
			(primitives
				(gr_poly
					(pts
						(arc
							(start -0.254 0.1778)
							(mid -0.239121 0.213721)
							(end -0.2032 0.2286)
						)
						(arc
							(start 0.2032 0.2286)
							(mid 0.239121 0.213721)
							(end 0.254 0.1778)
						)
						(arc
							(start 0.254 -0.1778)
							(mid 0.239121 -0.213721)
							(end 0.2032 -0.2286)
						)
						(arc
							(start -0.2032 -0.2286)
							(mid -0.239121 -0.213721)
							(end -0.254 -0.1778)
						)
					)
					(width 0)
					(fill yes)
				)
			)
		)
		(pad "2" smd custom
			(at 0 0.4572)
			(size 0.1143 0.1143)
			(layers "B.Cu" "B.Mask" "B.Paste")
			(net "GND")
			(options
				(clearance outline)
				(anchor circle)
			)
			(primitives
				(gr_poly
					(pts
						(arc
							(start -0.254 0.1778)
							(mid -0.239121 0.213721)
							(end -0.2032 0.2286)
						)
						(arc
							(start 0.2032 0.2286)
							(mid 0.239121 0.213721)
							(end 0.254 0.1778)
						)
						(arc
							(start 0.254 -0.1778)
							(mid 0.239121 -0.213721)
							(end 0.2032 -0.2286)
						)
						(arc
							(start -0.2032 -0.2286)
							(mid -0.239121 -0.213721)
							(end -0.254 -0.1778)
						)
					)
					(width 0)
					(fill yes)
				)
			)
		)
	)
	(footprint ""
		(layer "B.Cu")
		(at 103.251 -15.748 90)
		(property "Reference" "U39"
			(at 0 0 90)
			(layer "B.SilkS")
			(hide yes)
			(effects
				(font
					(size 1.27 1.27)
				)
				(justify mirror)
			)
		)
		(property "Value" "SNLVC1G126DCKR-GP"
			(at 0 -8.0772 90)
			(unlocked yes)
			(layer "B.Fab")
			(hide yes)
			(effects
				(font
					(size 1.016 1.016)
					(thickness 0.1524)
				)
				(justify mirror)
			)
		)
		(property "Device Type" "SC70-5H44"
			(at 0 -9.6012 90)
			(unlocked yes)
			(layer "B.Fab")
			(hide yes)
			(effects
				(font
					(size 1.016 1.016)
					(thickness 0.1524)
				)
				(justify mirror)
			)
		)
		(duplicate_pad_numbers_are_jumpers no)
		(fp_line
			(start 1.0033 -0.3302)
			(end -1.0033 -0.3302)
			(stroke
				(width 0.1524)
				(type default)
			)
			(layer "B.SilkS")
		)
		(fp_line
			(start -1.0033 -0.3302)
			(end -1.0033 0.3302)
			(stroke
				(width 0.1524)
				(type default)
			)
			(layer "B.SilkS")
		)
		(fp_line
			(start 1.0033 0.3302)
			(end 1.0033 -0.3302)
			(stroke
				(width 0.1524)
				(type default)
			)
			(layer "B.SilkS")
		)
		(fp_line
			(start -1.0033 0.3302)
			(end 1.0033 0.3302)
			(stroke
				(width 0.1524)
				(type default)
			)
			(layer "B.SilkS")
		)
		(fp_poly
			(pts
				(xy 1.0033 1.4859) (xy 1.0033 0.8001) (xy 1.1811 0.8001) (xy 1.1811 -0.8001) (xy 1.0033 -0.8001)
				(xy 1.0033 -1.4859) (xy -1.0033 -1.4859) (xy -1.0033 -0.8001) (xy -1.1811 -0.8001) (xy -1.1811 0.8001)
				(xy -1.0033 0.8001) (xy -1.0033 1.4859) (xy -0.2921 1.4859) (xy -0.2921 0.8001) (xy 0.2921 0.8001)
				(xy 0.2921 1.4859)
			)
			(stroke
				(width 0)
				(type default)
			)
			(fill no)
			(layer "B.CrtYd")
		)
		(fp_poly
			(pts
				(xy 1.0033 1.4859) (xy 1.0033 0.8001) (xy 1.1811 0.8001) (xy 1.1811 -0.8001) (xy 1.0033 -0.8001)
				(xy 1.0033 -1.4859) (xy -1.0033 -1.4859) (xy -1.0033 -0.8001) (xy -1.1811 -0.8001) (xy -1.1811 0.8001)
				(xy -1.0033 0.8001) (xy -1.0033 1.4859) (xy -0.2921 1.4859) (xy -0.2921 0.8001) (xy 0.2921 0.8001)
				(xy 0.2921 1.4859)
			)
			(stroke
				(width 0)
				(type default)
			)
			(fill no)
			(layer "B.Fab")
		)
		(pad "1" smd rect
			(at -0.65024 -0.93472 270)
			(size 0.3556 0.762)
			(layers "B.Cu" "B.Mask" "B.Paste")
			(net "PMU_PLTRST#")
		)
		(pad "2" smd rect
			(at 0 -0.93472 270)
			(size 0.3556 0.762)
			(layers "B.Cu" "B.Mask" "B.Paste")
			(net "IRQ_CPU_IERR#")
		)
		(pad "3" smd rect
			(at 0.65024 -0.93472 270)
			(size 0.3556 0.762)
			(layers "B.Cu" "B.Mask" "B.Paste")
			(net "GND")
		)
		(pad "4" smd rect
			(at 0.65024 0.93472 270)
			(size 0.3556 0.762)
			(layers "B.Cu" "B.Mask" "B.Paste")
			(net "IRQ_CPU_LV_IERR#")
		)
		(pad "5" smd rect
			(at -0.65024 0.93472 270)
			(size 0.3556 0.762)
			(layers "B.Cu" "B.Mask" "B.Paste")
			(net "P3V3")
		)
	)
	(footprint ""
		(layer "B.Cu")
		(at 78.613 -36.6268 -90)
		(property "Reference" "C200"
			(at 0 0 90)
			(layer "B.SilkS")
			(hide yes)
			(effects
				(font
					(size 1.27 1.27)
				)
				(justify mirror)
			)
		)
		(property "Value" "SCD1U16V2KX-3GP"
			(at -1.1811 -2.7051 270)
			(unlocked yes)
			(layer "B.Fab")
			(hide yes)
			(effects
				(font
					(size 1.016 1.016)
					(thickness 0.1524)
				)
				(justify mirror)
			)
		)
		(property "Device Type" "C402H22"
			(at -1.1811 -4.2291 270)
			(unlocked yes)
			(layer "B.Fab")
			(hide yes)
			(effects
				(font
					(size 1.016 1.016)
					(thickness 0.1524)
				)
				(justify mirror)
			)
		)
		(duplicate_pad_numbers_are_jumpers no)
		(fp_rect
			(start 0.381 0.7366)
			(end -0.381 -0.7366)
			(stroke
				(width 0)
				(type default)
			)
			(fill no)
			(layer "B.CrtYd")
		)
		(fp_rect
			(start 0.381 0.7366)
			(end -0.381 -0.7366)
			(stroke
				(width 0)
				(type default)
			)
			(fill no)
			(layer "B.Fab")
		)
		(pad "1" smd custom
			(at 0 -0.4572 90)
			(size 0.1143 0.1143)
			(layers "B.Cu" "B.Mask" "B.Paste")
			(net "RTC_EXTPAD")
			(options
				(clearance outline)
				(anchor circle)
			)
			(primitives
				(gr_poly
					(pts
						(arc
							(start -0.254 0.1778)
							(mid -0.239121 0.213721)
							(end -0.2032 0.2286)
						)
						(arc
							(start 0.2032 0.2286)
							(mid 0.239121 0.213721)
							(end 0.254 0.1778)
						)
						(arc
							(start 0.254 -0.1778)
							(mid 0.239121 -0.213721)
							(end 0.2032 -0.2286)
						)
						(arc
							(start -0.2032 -0.2286)
							(mid -0.239121 -0.213721)
							(end -0.254 -0.1778)
						)
					)
					(width 0)
					(fill yes)
				)
			)
		)
		(pad "2" smd custom
			(at 0 0.4572 90)
			(size 0.1143 0.1143)
			(layers "B.Cu" "B.Mask" "B.Paste")
			(net "GND")
			(options
				(clearance outline)
				(anchor circle)
			)
			(primitives
				(gr_poly
					(pts
						(arc
							(start -0.254 0.1778)
							(mid -0.239121 0.213721)
							(end -0.2032 0.2286)
						)
						(arc
							(start 0.2032 0.2286)
							(mid 0.239121 0.213721)
							(end 0.254 0.1778)
						)
						(arc
							(start 0.254 -0.1778)
							(mid 0.239121 -0.213721)
							(end 0.2032 -0.2286)
						)
						(arc
							(start -0.2032 -0.2286)
							(mid -0.239121 -0.213721)
							(end -0.254 -0.1778)
						)
					)
					(width 0)
					(fill yes)
				)
			)
		)
	)
	(footprint ""
		(layer "B.Cu")
		(at 193.548 -40.386)
		(property "Reference" "PD2"
			(at 0 0 0)
			(layer "B.SilkS")
			(hide yes)
			(effects
				(font
					(size 1.27 1.27)
				)
				(justify mirror)
			)
		)
		(property "Value" "MM3Z5V6T1G-GP"
			(at -2.5527 -1.9812 0)
			(unlocked yes)
			(layer "B.Fab")
			(hide yes)
			(effects
				(font
					(size 1.016 1.016)
					(thickness 0.1524)
				)
				(justify mirror)
			)
		)
		(property "Device Type" "SOD323AKH40"
			(at -2.5527 -3.5052 0)
			(unlocked yes)
			(layer "B.Fab")
			(hide yes)
			(effects
				(font
					(size 1.016 1.016)
					(thickness 0.1524)
				)
				(justify mirror)
			)
		)
		(duplicate_pad_numbers_are_jumpers no)
		(fp_line
			(start -0.7747 1.7653)
			(end 0.7747 1.7653)
			(stroke
				(width 0.254)
				(type default)
			)
			(layer "B.SilkS")
		)
		(fp_rect
			(start 0.9017 1.6383)
			(end -0.9017 -1.6383)
			(stroke
				(width 0)
				(type default)
			)
			(fill no)
			(layer "B.CrtYd")
		)
		(fp_rect
			(start 0.9017 1.6383)
			(end -0.9017 -1.6383)
			(stroke
				(width 0)
				(type default)
			)
			(fill no)
			(layer "B.Fab")
		)
		(pad "A" smd rect
			(at 0 -1.100074 180)
			(size 0.5588 0.8128)
			(layers "B.Cu" "B.Mask" "B.Paste")
			(net "GND")
		)
		(pad "K" smd rect
			(at 0 1.100074 180)
			(size 0.5588 0.8128)
			(layers "B.Cu" "B.Mask" "B.Paste")
			(net "VDDR_Z")
		)
	)
	(footprint ""
		(layer "B.Cu")
		(at 53.848 -12.7 180)
		(property "Reference" "R393"
			(at 0 0 0)
			(layer "B.SilkS")
			(hide yes)
			(effects
				(font
					(size 1.27 1.27)
				)
				(justify mirror)
			)
		)
		(property "Value" "0R2J-2-GP"
			(at -1.7907 -1.1176 180)
			(unlocked yes)
			(layer "B.Fab")
			(hide yes)
			(effects
				(font
					(size 1.016 1.016)
					(thickness 0.1524)
				)
				(justify mirror)
			)
		)
		(property "Device Type" "R402H16"
			(at -1.7907 -2.6416 180)
			(unlocked yes)
			(layer "B.Fab")
			(hide yes)
			(effects
				(font
					(size 1.016 1.016)
					(thickness 0.1524)
				)
				(justify mirror)
			)
		)
		(duplicate_pad_numbers_are_jumpers no)
		(fp_rect
			(start 0.381 0.8382)
			(end -0.381 -0.8382)
			(stroke
				(width 0)
				(type default)
			)
			(fill no)
			(layer "B.CrtYd")
		)
		(fp_rect
			(start 0.381 0.8382)
			(end -0.381 -0.8382)
			(stroke
				(width 0)
				(type default)
			)
			(fill no)
			(layer "B.Fab")
		)
		(pad "1" smd custom
			(at 0 -0.4318)
			(size 0.127 0.127)
			(layers "B.Cu" "B.Mask" "B.Paste")
			(net "GBE_R_SMBCLK")
			(options
				(clearance outline)
				(anchor circle)
			)
			(primitives
				(gr_poly
					(pts
						(arc
							(start -0.2032 0.2794)
							(mid -0.239121 0.264521)
							(end -0.254 0.2286)
						)
						(arc
							(start -0.254 -0.2286)
							(mid -0.239121 -0.264521)
							(end -0.2032 -0.2794)
						)
						(arc
							(start 0.2032 -0.2794)
							(mid 0.239121 -0.264521)
							(end 0.254 -0.2286)
						)
						(arc
							(start 0.254 0.2286)
							(mid 0.239121 0.264521)
							(end 0.2032 0.2794)
						)
					)
					(width 0)
					(fill yes)
				)
			)
		)
		(pad "2" smd custom
			(at 0 0.4318)
			(size 0.127 0.127)
			(layers "B.Cu" "B.Mask" "B.Paste")
			(net "GF_GBE_SMBCLK")
			(options
				(clearance outline)
				(anchor circle)
			)
			(primitives
				(gr_poly
					(pts
						(arc
							(start -0.2032 0.2794)
							(mid -0.239121 0.264521)
							(end -0.254 0.2286)
						)
						(arc
							(start -0.254 -0.2286)
							(mid -0.239121 -0.264521)
							(end -0.2032 -0.2794)
						)
						(arc
							(start 0.2032 -0.2794)
							(mid 0.239121 -0.264521)
							(end 0.254 -0.2286)
						)
						(arc
							(start 0.254 0.2286)
							(mid 0.239121 0.264521)
							(end 0.2032 0.2794)
						)
					)
					(width 0)
					(fill yes)
				)
			)
		)
	)
	(footprint ""
		(layer "B.Cu")
		(at 67.0814 -38.8874 180)
		(property "Reference" "PR127"
			(at 0 0 0)
			(layer "B.SilkS")
			(hide yes)
			(effects
				(font
					(size 1.27 1.27)
				)
				(justify mirror)
			)
		)
		(property "Value" "0R2J-2-GP"
			(at -1.7907 -1.1176 180)
			(unlocked yes)
			(layer "B.Fab")
			(hide yes)
			(effects
				(font
					(size 1.016 1.016)
					(thickness 0.1524)
				)
				(justify mirror)
			)
		)
		(property "Device Type" "R402H16"
			(at -1.7907 -2.6416 180)
			(unlocked yes)
			(layer "B.Fab")
			(hide yes)
			(effects
				(font
					(size 1.016 1.016)
					(thickness 0.1524)
				)
				(justify mirror)
			)
		)
		(duplicate_pad_numbers_are_jumpers no)
		(fp_rect
			(start 0.381 0.8382)
			(end -0.381 -0.8382)
			(stroke
				(width 0)
				(type default)
			)
			(fill no)
			(layer "B.CrtYd")
		)
		(fp_rect
			(start 0.381 0.8382)
			(end -0.381 -0.8382)
			(stroke
				(width 0)
				(type default)
			)
			(fill no)
			(layer "B.Fab")
		)
		(pad "1" smd custom
			(at 0 -0.4318)
			(size 0.127 0.127)
			(layers "B.Cu" "B.Mask" "B.Paste")
			(net "PMU_SLP_DDRVTT#")
			(options
				(clearance outline)
				(anchor circle)
			)
			(primitives
				(gr_poly
					(pts
						(arc
							(start -0.2032 0.2794)
							(mid -0.239121 0.264521)
							(end -0.254 0.2286)
						)
						(arc
							(start -0.254 -0.2286)
							(mid -0.239121 -0.264521)
							(end -0.2032 -0.2794)
						)
						(arc
							(start 0.2032 -0.2794)
							(mid 0.239121 -0.264521)
							(end 0.254 -0.2286)
						)
						(arc
							(start 0.254 0.2286)
							(mid 0.239121 0.264521)
							(end 0.2032 0.2794)
						)
					)
					(width 0)
					(fill yes)
				)
			)
		)
		(pad "2" smd custom
			(at 0 0.4318)
			(size 0.127 0.127)
			(layers "B.Cu" "B.Mask" "B.Paste")
			(net "PVTT_DDR_EN")
			(options
				(clearance outline)
				(anchor circle)
			)
			(primitives
				(gr_poly
					(pts
						(arc
							(start -0.2032 0.2794)
							(mid -0.239121 0.264521)
							(end -0.254 0.2286)
						)
						(arc
							(start -0.254 -0.2286)
							(mid -0.239121 -0.264521)
							(end -0.2032 -0.2794)
						)
						(arc
							(start 0.2032 -0.2794)
							(mid 0.239121 -0.264521)
							(end 0.254 -0.2286)
						)
						(arc
							(start 0.254 0.2286)
							(mid 0.239121 0.264521)
							(end 0.2032 0.2794)
						)
					)
					(width 0)
					(fill yes)
				)
			)
		)
	)
	(footprint ""
		(layer "B.Cu")
		(at 5.5372 -28.321 -90)
		(property "Reference" "PC81"
			(at 0 0 90)
			(layer "B.SilkS")
			(hide yes)
			(effects
				(font
					(size 1.27 1.27)
				)
				(justify mirror)
			)
		)
		(property "Value" "SC22U25V5MX-GP"
			(at 0 -4.9022 270)
			(unlocked yes)
			(layer "B.Fab")
			(hide yes)
			(effects
				(font
					(size 1.016 1.016)
					(thickness 0.1524)
				)
				(justify mirror)
			)
		)
		(property "Device Type" "C805H58"
			(at 0 -6.8072 270)
			(unlocked yes)
			(layer "B.Fab")
			(hide yes)
			(effects
				(font
					(size 1.016 1.016)
					(thickness 0.1524)
				)
				(justify mirror)
			)
		)
		(duplicate_pad_numbers_are_jumpers no)
		(fp_line
			(start -0.6096 0)
			(end 0.6096 0)
			(stroke
				(width 0.3048)
				(type default)
			)
			(layer "B.SilkS")
		)
		(fp_poly
			(pts
				(xy 0.9017 1.4351) (xy -0.9017 1.4351) (xy -0.9017 -1.4351) (xy 0.9017 -1.4351)
			)
			(stroke
				(width 0)
				(type default)
			)
			(fill no)
			(layer "B.CrtYd")
		)
		(fp_poly
			(pts
				(xy -0.9017 1.4351) (xy -0.9017 -1.4351) (xy 0.9017 -1.4351) (xy 0.9017 1.4351)
			)
			(stroke
				(width 0)
				(type default)
			)
			(fill no)
			(layer "B.Fab")
		)
		(pad "1" smd rect
			(at 0 -0.8382 90)
			(size 1.5494 0.9398)
			(layers "B.Cu" "B.Mask" "B.Paste")
			(net "P1V0_VIN")
		)
		(pad "2" smd rect
			(at 0 0.8382 90)
			(size 1.5494 0.9398)
			(layers "B.Cu" "B.Mask" "B.Paste")
			(net "GND")
		)
	)
	(footprint ""
		(layer "B.Cu")
		(at 38.23081 -12.7)
		(property "Reference" "C266"
			(at 0 0 0)
			(layer "B.SilkS")
			(hide yes)
			(effects
				(font
					(size 1.27 1.27)
				)
				(justify mirror)
			)
		)
		(property "Value" "SCD1U16V2KX-3GP"
			(at -1.1811 -2.7051 0)
			(unlocked yes)
			(layer "B.Fab")
			(hide yes)
			(effects
				(font
					(size 1.016 1.016)
					(thickness 0.1524)
				)
				(justify mirror)
			)
		)
		(property "Device Type" "C402H22"
			(at -1.1811 -4.2291 0)
			(unlocked yes)
			(layer "B.Fab")
			(hide yes)
			(effects
				(font
					(size 1.016 1.016)
					(thickness 0.1524)
				)
				(justify mirror)
			)
		)
		(duplicate_pad_numbers_are_jumpers no)
		(fp_rect
			(start 0.381 0.7366)
			(end -0.381 -0.7366)
			(stroke
				(width 0)
				(type default)
			)
			(fill no)
			(layer "B.CrtYd")
		)
		(fp_rect
			(start 0.381 0.7366)
			(end -0.381 -0.7366)
			(stroke
				(width 0)
				(type default)
			)
			(fill no)
			(layer "B.Fab")
		)
		(pad "1" smd custom
			(at 0 -0.4572 180)
			(size 0.1143 0.1143)
			(layers "B.Cu" "B.Mask" "B.Paste")
			(net "P2E_CPU_SAS_C_TX_DP6")
			(options
				(clearance outline)
				(anchor circle)
			)
			(primitives
				(gr_poly
					(pts
						(arc
							(start -0.254 0.1778)
							(mid -0.239121 0.213721)
							(end -0.2032 0.2286)
						)
						(arc
							(start 0.2032 0.2286)
							(mid 0.239121 0.213721)
							(end 0.254 0.1778)
						)
						(arc
							(start 0.254 -0.1778)
							(mid 0.239121 -0.213721)
							(end 0.2032 -0.2286)
						)
						(arc
							(start -0.2032 -0.2286)
							(mid -0.239121 -0.213721)
							(end -0.254 -0.1778)
						)
					)
					(width 0)
					(fill yes)
				)
			)
		)
		(pad "2" smd custom
			(at 0 0.4572 180)
			(size 0.1143 0.1143)
			(layers "B.Cu" "B.Mask" "B.Paste")
			(net "P2E_CPU_SAS_TX_DP6")
			(options
				(clearance outline)
				(anchor circle)
			)
			(primitives
				(gr_poly
					(pts
						(arc
							(start -0.254 0.1778)
							(mid -0.239121 0.213721)
							(end -0.2032 0.2286)
						)
						(arc
							(start 0.2032 0.2286)
							(mid 0.239121 0.213721)
							(end 0.254 0.1778)
						)
						(arc
							(start 0.254 -0.1778)
							(mid 0.239121 -0.213721)
							(end 0.2032 -0.2286)
						)
						(arc
							(start -0.2032 -0.2286)
							(mid -0.239121 -0.213721)
							(end -0.254 -0.1778)
						)
					)
					(width 0)
					(fill yes)
				)
			)
		)
	)
	(footprint ""
		(layer "B.Cu")
		(at 163.068 -59.309)
		(property "Reference" "C362"
			(at 0 0 0)
			(layer "B.SilkS")
			(hide yes)
			(effects
				(font
					(size 1.27 1.27)
				)
				(justify mirror)
			)
		)
		(property "Value" "SC47U6D3V5MX-1-GP"
			(at 0 -4.9022 0)
			(unlocked yes)
			(layer "B.Fab")
			(hide yes)
			(effects
				(font
					(size 1.016 1.016)
					(thickness 0.1524)
				)
				(justify mirror)
			)
		)
		(property "Device Type" "C805H54"
			(at 0 -6.8072 0)
			(unlocked yes)
			(layer "B.Fab")
			(hide yes)
			(effects
				(font
					(size 1.016 1.016)
					(thickness 0.1524)
				)
				(justify mirror)
			)
		)
		(duplicate_pad_numbers_are_jumpers no)
		(fp_line
			(start -0.6096 0)
			(end 0.6096 0)
			(stroke
				(width 0.3048)
				(type default)
			)
			(layer "B.SilkS")
		)
		(fp_poly
			(pts
				(xy 0.9017 1.4351) (xy -0.9017 1.4351) (xy -0.9017 -1.4351) (xy 0.9017 -1.4351)
			)
			(stroke
				(width 0)
				(type default)
			)
			(fill no)
			(layer "B.CrtYd")
		)
		(fp_poly
			(pts
				(xy -0.9017 1.4351) (xy -0.9017 -1.4351) (xy 0.9017 -1.4351) (xy 0.9017 1.4351)
			)
			(stroke
				(width 0)
				(type default)
			)
			(fill no)
			(layer "B.Fab")
		)
		(pad "1" smd rect
			(at 0 -0.8382 180)
			(size 1.5494 0.9398)
			(layers "B.Cu" "B.Mask" "B.Paste")
			(net "PV_VDDR")
		)
		(pad "2" smd rect
			(at 0 0.8382 180)
			(size 1.5494 0.9398)
			(layers "B.Cu" "B.Mask" "B.Paste")
			(net "GND")
		)
	)
	(footprint ""
		(layer "B.Cu")
		(at 17.526 -57.9882)
		(property "Reference" "PR12"
			(at 0 0 0)
			(layer "B.SilkS")
			(hide yes)
			(effects
				(font
					(size 1.27 1.27)
				)
				(justify mirror)
			)
		)
		(property "Value" "100R3F-1-GP"
			(at 0.0254 -2.0193 0)
			(unlocked yes)
			(layer "B.Fab")
			(hide yes)
			(effects
				(font
					(size 1.016 1.016)
					(thickness 0.1524)
				)
				(justify mirror)
			)
		)
		(property "Device Type" "R603H22"
			(at 0.0254 -3.5433 0)
			(unlocked yes)
			(layer "B.Fab")
			(hide yes)
			(effects
				(font
					(size 1.016 1.016)
					(thickness 0.1524)
				)
				(justify mirror)
			)
		)
		(duplicate_pad_numbers_are_jumpers no)
		(fp_line
			(start -0.4318 0)
			(end -0.2032 0)
			(stroke
				(width 0.2032)
				(type default)
			)
			(layer "B.SilkS")
		)
		(fp_line
			(start 0.2032 0)
			(end 0.4191 0)
			(stroke
				(width 0.2032)
				(type default)
			)
			(layer "B.SilkS")
		)
		(fp_rect
			(start 0.635 1.1811)
			(end -0.635 -1.1811)
			(stroke
				(width 0)
				(type default)
			)
			(fill no)
			(layer "B.CrtYd")
		)
		(fp_rect
			(start 0.635 1.1811)
			(end -0.635 -1.1811)
			(stroke
				(width 0)
				(type default)
			)
			(fill no)
			(layer "B.Fab")
		)
		(pad "1" smd custom
			(at 0 -0.6604 180)
			(size 0.19685 0.19685)
			(layers "B.Cu" "B.Mask" "B.Paste")
			(net "VR_PVNN_FB")
			(options
				(clearance outline)
				(anchor circle)
			)
			(primitives
				(gr_poly
					(pts
						(arc
							(start 0.508 0.2921)
							(mid 0.478242 0.363942)
							(end 0.4064 0.3937)
						)
						(arc
							(start -0.4064 0.3937)
							(mid -0.478242 0.363942)
							(end -0.508 0.2921)
						)
						(arc
							(start -0.508 -0.2921)
							(mid -0.478242 -0.363942)
							(end -0.4064 -0.3937)
						)
						(arc
							(start 0.4064 -0.3937)
							(mid 0.478242 -0.363942)
							(end 0.508 -0.2921)
						)
					)
					(width 0)
					(fill yes)
				)
			)
		)
		(pad "2" smd custom
			(at 0 0.6604 180)
			(size 0.19685 0.19685)
			(layers "B.Cu" "B.Mask" "B.Paste")
			(net "VR_PVNN_VSEN_R")
			(options
				(clearance outline)
				(anchor circle)
			)
			(primitives
				(gr_poly
					(pts
						(arc
							(start 0.508 0.2921)
							(mid 0.478242 0.363942)
							(end 0.4064 0.3937)
						)
						(arc
							(start -0.4064 0.3937)
							(mid -0.478242 0.363942)
							(end -0.508 0.2921)
						)
						(arc
							(start -0.508 -0.2921)
							(mid -0.478242 -0.363942)
							(end -0.4064 -0.3937)
						)
						(arc
							(start 0.4064 -0.3937)
							(mid 0.478242 -0.363942)
							(end 0.508 -0.2921)
						)
					)
					(width 0)
					(fill yes)
				)
			)
		)
	)
	(footprint ""
		(layer "B.Cu")
		(at 26.797 -49.149)
		(property "Reference" "PC128"
			(at 0 0 0)
			(layer "B.SilkS")
			(hide yes)
			(effects
				(font
					(size 1.27 1.27)
				)
				(justify mirror)
			)
		)
		(property "Value" "SCD1U16V2KX-3GP"
			(at -1.8923 -1.2065 0)
			(unlocked yes)
			(layer "B.Fab")
			(hide yes)
			(effects
				(font
					(size 1.016 1.016)
					(thickness 0.1524)
				)
				(justify mirror)
			)
		)
		(property "Device Type" "C402H22"
			(at -1.8923 -2.7305 0)
			(unlocked yes)
			(layer "B.Fab")
			(hide yes)
			(effects
				(font
					(size 1.016 1.016)
					(thickness 0.1524)
				)
				(justify mirror)
			)
		)
		(duplicate_pad_numbers_are_jumpers no)
		(fp_rect
			(start 0.381 0.7366)
			(end -0.381 -0.7366)
			(stroke
				(width 0)
				(type default)
			)
			(fill no)
			(layer "B.CrtYd")
		)
		(fp_rect
			(start 0.381 0.7366)
			(end -0.381 -0.7366)
			(stroke
				(width 0)
				(type default)
			)
			(fill no)
			(layer "B.Fab")
		)
		(pad "1" smd custom
			(at 0 -0.4572 180)
			(size 0.1143 0.1143)
			(layers "B.Cu" "B.Mask" "B.Paste")
			(net "P1V5_STBY_IN")
			(options
				(clearance outline)
				(anchor circle)
			)
			(primitives
				(gr_poly
					(pts
						(arc
							(start -0.254 0.1778)
							(mid -0.239121 0.213721)
							(end -0.2032 0.2286)
						)
						(arc
							(start 0.2032 0.2286)
							(mid 0.239121 0.213721)
							(end 0.254 0.1778)
						)
						(arc
							(start 0.254 -0.1778)
							(mid 0.239121 -0.213721)
							(end 0.2032 -0.2286)
						)
						(arc
							(start -0.2032 -0.2286)
							(mid -0.239121 -0.213721)
							(end -0.254 -0.1778)
						)
					)
					(width 0)
					(fill yes)
				)
			)
		)
		(pad "2" smd custom
			(at 0 0.4572 180)
			(size 0.1143 0.1143)
			(layers "B.Cu" "B.Mask" "B.Paste")
			(net "GND")
			(options
				(clearance outline)
				(anchor circle)
			)
			(primitives
				(gr_poly
					(pts
						(arc
							(start -0.254 0.1778)
							(mid -0.239121 0.213721)
							(end -0.2032 0.2286)
						)
						(arc
							(start 0.2032 0.2286)
							(mid 0.239121 0.213721)
							(end 0.254 0.1778)
						)
						(arc
							(start 0.254 -0.1778)
							(mid 0.239121 -0.213721)
							(end 0.2032 -0.2286)
						)
						(arc
							(start -0.2032 -0.2286)
							(mid -0.239121 -0.213721)
							(end -0.254 -0.1778)
						)
					)
					(width 0)
					(fill yes)
				)
			)
		)
	)
	(footprint ""
		(layer "B.Cu")
		(at 15.367 -31.369)
		(property "Reference" "PC159"
			(at 0 0 0)
			(layer "B.SilkS")
			(hide yes)
			(effects
				(font
					(size 1.27 1.27)
				)
				(justify mirror)
			)
		)
		(property "Value" "SC4D7U25V5KX-1-GP"
			(at 0 -4.9022 0)
			(unlocked yes)
			(layer "B.Fab")
			(hide yes)
			(effects
				(font
					(size 1.016 1.016)
					(thickness 0.1524)
				)
				(justify mirror)
			)
		)
		(property "Device Type" "C805H58"
			(at 0 -6.8072 0)
			(unlocked yes)
			(layer "B.Fab")
			(hide yes)
			(effects
				(font
					(size 1.016 1.016)
					(thickness 0.1524)
				)
				(justify mirror)
			)
		)
		(duplicate_pad_numbers_are_jumpers no)
		(fp_line
			(start -0.6096 0)
			(end 0.6096 0)
			(stroke
				(width 0.3048)
				(type default)
			)
			(layer "B.SilkS")
		)
		(fp_poly
			(pts
				(xy 0.9017 1.4351) (xy -0.9017 1.4351) (xy -0.9017 -1.4351) (xy 0.9017 -1.4351)
			)
			(stroke
				(width 0)
				(type default)
			)
			(fill no)
			(layer "B.CrtYd")
		)
		(fp_poly
			(pts
				(xy -0.9017 1.4351) (xy -0.9017 -1.4351) (xy 0.9017 -1.4351) (xy 0.9017 1.4351)
			)
			(stroke
				(width 0)
				(type default)
			)
			(fill no)
			(layer "B.Fab")
		)
		(pad "1" smd rect
			(at 0 -0.8382 180)
			(size 1.5494 0.9398)
			(layers "B.Cu" "B.Mask" "B.Paste")
			(net "P3V3_STBY_EN")
		)
		(pad "2" smd rect
			(at 0 0.8382 180)
			(size 1.5494 0.9398)
			(layers "B.Cu" "B.Mask" "B.Paste")
			(net "AGND_P3V3_STBY")
		)
	)
	(footprint ""
		(layer "B.Cu")
		(at 75.565 -58.674 -90)
		(property "Reference" "R135"
			(at 0 0 90)
			(layer "B.SilkS")
			(hide yes)
			(effects
				(font
					(size 1.27 1.27)
				)
				(justify mirror)
			)
		)
		(property "Value" "0R2J-2-GP"
			(at -0.064008 -3.993896 270)
			(unlocked yes)
			(layer "B.Fab")
			(hide yes)
			(effects
				(font
					(size 1.016 1.016)
					(thickness 0.1524)
				)
				(justify mirror)
			)
		)
		(property "Device Type" "R402H16"
			(at -0.064008 -5.517896 270)
			(unlocked yes)
			(layer "B.Fab")
			(hide yes)
			(effects
				(font
					(size 1.016 1.016)
					(thickness 0.1524)
				)
				(justify mirror)
			)
		)
		(duplicate_pad_numbers_are_jumpers no)
		(fp_rect
			(start 0.381 0.8382)
			(end -0.381 -0.8382)
			(stroke
				(width 0)
				(type default)
			)
			(fill no)
			(layer "B.CrtYd")
		)
		(fp_rect
			(start 0.381 0.8382)
			(end -0.381 -0.8382)
			(stroke
				(width 0)
				(type default)
			)
			(fill no)
			(layer "B.Fab")
		)
		(pad "1" smd custom
			(at 0 -0.4318 90)
			(size 0.127 0.127)
			(layers "B.Cu" "B.Mask" "B.Paste")
			(net "VOL1_SEN_DATA")
			(options
				(clearance outline)
				(anchor circle)
			)
			(primitives
				(gr_poly
					(pts
						(arc
							(start -0.2032 0.2794)
							(mid -0.239121 0.264521)
							(end -0.254 0.2286)
						)
						(arc
							(start -0.254 -0.2286)
							(mid -0.239121 -0.264521)
							(end -0.2032 -0.2794)
						)
						(arc
							(start 0.2032 -0.2794)
							(mid 0.239121 -0.264521)
							(end 0.254 -0.2286)
						)
						(arc
							(start 0.254 0.2286)
							(mid 0.239121 0.264521)
							(end 0.2032 0.2794)
						)
					)
					(width 0)
					(fill yes)
				)
			)
		)
		(pad "2" smd custom
			(at 0 0.4318 90)
			(size 0.127 0.127)
			(layers "B.Cu" "B.Mask" "B.Paste")
			(net "SMB_HOST_LV_DATA")
			(options
				(clearance outline)
				(anchor circle)
			)
			(primitives
				(gr_poly
					(pts
						(arc
							(start -0.2032 0.2794)
							(mid -0.239121 0.264521)
							(end -0.254 0.2286)
						)
						(arc
							(start -0.254 -0.2286)
							(mid -0.239121 -0.264521)
							(end -0.2032 -0.2794)
						)
						(arc
							(start 0.2032 -0.2794)
							(mid 0.239121 -0.264521)
							(end 0.254 -0.2286)
						)
						(arc
							(start 0.254 0.2286)
							(mid 0.239121 0.264521)
							(end 0.2032 0.2794)
						)
					)
					(width 0)
					(fill yes)
				)
			)
		)
	)
	(footprint ""
		(layer "B.Cu")
		(at 39.37 -14.605 -90)
		(property "Reference" "R430"
			(at 0 0 90)
			(layer "B.SilkS")
			(hide yes)
			(effects
				(font
					(size 1.27 1.27)
				)
				(justify mirror)
			)
		)
		(property "Value" "43D2R2F-GP"
			(at -1.7907 -1.1176 270)
			(unlocked yes)
			(layer "B.Fab")
			(hide yes)
			(effects
				(font
					(size 1.016 1.016)
					(thickness 0.1524)
				)
				(justify mirror)
			)
		)
		(property "Device Type" "R402H16"
			(at -1.7907 -2.6416 270)
			(unlocked yes)
			(layer "B.Fab")
			(hide yes)
			(effects
				(font
					(size 1.016 1.016)
					(thickness 0.1524)
				)
				(justify mirror)
			)
		)
		(duplicate_pad_numbers_are_jumpers no)
		(fp_rect
			(start 0.381 0.8382)
			(end -0.381 -0.8382)
			(stroke
				(width 0)
				(type default)
			)
			(fill no)
			(layer "B.CrtYd")
		)
		(fp_rect
			(start 0.381 0.8382)
			(end -0.381 -0.8382)
			(stroke
				(width 0)
				(type default)
			)
			(fill no)
			(layer "B.Fab")
		)
		(pad "1" smd custom
			(at 0 -0.4318 90)
			(size 0.127 0.127)
			(layers "B.Cu" "B.Mask" "B.Paste")
			(net "CLK_100M_PCIE_SAS_DN")
			(options
				(clearance outline)
				(anchor circle)
			)
			(primitives
				(gr_poly
					(pts
						(arc
							(start -0.2032 0.2794)
							(mid -0.239121 0.264521)
							(end -0.254 0.2286)
						)
						(arc
							(start -0.254 -0.2286)
							(mid -0.239121 -0.264521)
							(end -0.2032 -0.2794)
						)
						(arc
							(start 0.2032 -0.2794)
							(mid 0.239121 -0.264521)
							(end 0.254 -0.2286)
						)
						(arc
							(start 0.254 0.2286)
							(mid 0.239121 0.264521)
							(end 0.2032 0.2794)
						)
					)
					(width 0)
					(fill yes)
				)
			)
		)
		(pad "2" smd custom
			(at 0 0.4318 90)
			(size 0.127 0.127)
			(layers "B.Cu" "B.Mask" "B.Paste")
			(net "GND")
			(options
				(clearance outline)
				(anchor circle)
			)
			(primitives
				(gr_poly
					(pts
						(arc
							(start -0.2032 0.2794)
							(mid -0.239121 0.264521)
							(end -0.254 0.2286)
						)
						(arc
							(start -0.254 -0.2286)
							(mid -0.239121 -0.264521)
							(end -0.2032 -0.2794)
						)
						(arc
							(start 0.2032 -0.2794)
							(mid 0.239121 -0.264521)
							(end 0.254 -0.2286)
						)
						(arc
							(start 0.254 0.2286)
							(mid 0.239121 0.264521)
							(end 0.2032 0.2794)
						)
					)
					(width 0)
					(fill yes)
				)
			)
		)
	)
	(footprint ""
		(layer "B.Cu")
		(at 103.124 -52.832 -90)
		(property "Reference" "R285"
			(at 0 0 90)
			(layer "B.SilkS")
			(hide yes)
			(effects
				(font
					(size 1.27 1.27)
				)
				(justify mirror)
			)
		)
		(property "Value" "0R2J-2-GP"
			(at -0.064008 -3.993896 270)
			(unlocked yes)
			(layer "B.Fab")
			(hide yes)
			(effects
				(font
					(size 1.016 1.016)
					(thickness 0.1524)
				)
				(justify mirror)
			)
		)
		(property "Device Type" "R402H16"
			(at -0.064008 -5.517896 270)
			(unlocked yes)
			(layer "B.Fab")
			(hide yes)
			(effects
				(font
					(size 1.016 1.016)
					(thickness 0.1524)
				)
				(justify mirror)
			)
		)
		(duplicate_pad_numbers_are_jumpers no)
		(fp_rect
			(start 0.381 0.8382)
			(end -0.381 -0.8382)
			(stroke
				(width 0)
				(type default)
			)
			(fill no)
			(layer "B.CrtYd")
		)
		(fp_rect
			(start 0.381 0.8382)
			(end -0.381 -0.8382)
			(stroke
				(width 0)
				(type default)
			)
			(fill no)
			(layer "B.Fab")
		)
		(pad "1" smd custom
			(at 0 -0.4318 90)
			(size 0.127 0.127)
			(layers "B.Cu" "B.Mask" "B.Paste")
			(net "M_DRAM_PWROK")
			(options
				(clearance outline)
				(anchor circle)
			)
			(primitives
				(gr_poly
					(pts
						(arc
							(start -0.2032 0.2794)
							(mid -0.239121 0.264521)
							(end -0.254 0.2286)
						)
						(arc
							(start -0.254 -0.2286)
							(mid -0.239121 -0.264521)
							(end -0.2032 -0.2794)
						)
						(arc
							(start 0.2032 -0.2794)
							(mid 0.239121 -0.264521)
							(end 0.254 -0.2286)
						)
						(arc
							(start 0.254 0.2286)
							(mid 0.239121 0.264521)
							(end 0.2032 0.2794)
						)
					)
					(width 0)
					(fill yes)
				)
			)
		)
		(pad "2" smd custom
			(at 0 0.4318 90)
			(size 0.127 0.127)
			(layers "B.Cu" "B.Mask" "B.Paste")
			(net "GND")
			(options
				(clearance outline)
				(anchor circle)
			)
			(primitives
				(gr_poly
					(pts
						(arc
							(start -0.2032 0.2794)
							(mid -0.239121 0.264521)
							(end -0.254 0.2286)
						)
						(arc
							(start -0.254 -0.2286)
							(mid -0.239121 -0.264521)
							(end -0.2032 -0.2794)
						)
						(arc
							(start 0.2032 -0.2794)
							(mid 0.239121 -0.264521)
							(end 0.254 -0.2286)
						)
						(arc
							(start 0.254 0.2286)
							(mid 0.239121 0.264521)
							(end 0.2032 0.2794)
						)
					)
					(width 0)
					(fill yes)
				)
			)
		)
	)
	(footprint ""
		(layer "B.Cu")
		(at 32.258 -53.594 180)
		(property "Reference" "PC125"
			(at 0 0 0)
			(layer "B.SilkS")
			(hide yes)
			(effects
				(font
					(size 1.27 1.27)
				)
				(justify mirror)
			)
		)
		(property "Value" "SCD1U16V2KX-3GP"
			(at -1.8923 -1.2065 180)
			(unlocked yes)
			(layer "B.Fab")
			(hide yes)
			(effects
				(font
					(size 1.016 1.016)
					(thickness 0.1524)
				)
				(justify mirror)
			)
		)
		(property "Device Type" "C402H22"
			(at -1.8923 -2.7305 180)
			(unlocked yes)
			(layer "B.Fab")
			(hide yes)
			(effects
				(font
					(size 1.016 1.016)
					(thickness 0.1524)
				)
				(justify mirror)
			)
		)
		(duplicate_pad_numbers_are_jumpers no)
		(fp_rect
			(start 0.381 0.7366)
			(end -0.381 -0.7366)
			(stroke
				(width 0)
				(type default)
			)
			(fill no)
			(layer "B.CrtYd")
		)
		(fp_rect
			(start 0.381 0.7366)
			(end -0.381 -0.7366)
			(stroke
				(width 0)
				(type default)
			)
			(fill no)
			(layer "B.Fab")
		)
		(pad "1" smd custom
			(at 0 -0.4572)
			(size 0.1143 0.1143)
			(layers "B.Cu" "B.Mask" "B.Paste")
			(net "P1V5_STBY_BIAS")
			(options
				(clearance outline)
				(anchor circle)
			)
			(primitives
				(gr_poly
					(pts
						(arc
							(start -0.254 0.1778)
							(mid -0.239121 0.213721)
							(end -0.2032 0.2286)
						)
						(arc
							(start 0.2032 0.2286)
							(mid 0.239121 0.213721)
							(end 0.254 0.1778)
						)
						(arc
							(start 0.254 -0.1778)
							(mid 0.239121 -0.213721)
							(end 0.2032 -0.2286)
						)
						(arc
							(start -0.2032 -0.2286)
							(mid -0.239121 -0.213721)
							(end -0.254 -0.1778)
						)
					)
					(width 0)
					(fill yes)
				)
			)
		)
		(pad "2" smd custom
			(at 0 0.4572)
			(size 0.1143 0.1143)
			(layers "B.Cu" "B.Mask" "B.Paste")
			(net "GND")
			(options
				(clearance outline)
				(anchor circle)
			)
			(primitives
				(gr_poly
					(pts
						(arc
							(start -0.254 0.1778)
							(mid -0.239121 0.213721)
							(end -0.2032 0.2286)
						)
						(arc
							(start 0.2032 0.2286)
							(mid 0.239121 0.213721)
							(end 0.254 0.1778)
						)
						(arc
							(start 0.254 -0.1778)
							(mid 0.239121 -0.213721)
							(end 0.2032 -0.2286)
						)
						(arc
							(start -0.2032 -0.2286)
							(mid -0.239121 -0.213721)
							(end -0.254 -0.1778)
						)
					)
					(width 0)
					(fill yes)
				)
			)
		)
	)
	(footprint ""
		(layer "B.Cu")
		(at 70.7898 -60.833)
		(property "Reference" "R486"
			(at 0 0 0)
			(layer "B.SilkS")
			(hide yes)
			(effects
				(font
					(size 1.27 1.27)
				)
				(justify mirror)
			)
		)
		(property "Value" "10KR2F-2-GP"
			(at -1.7907 -1.1176 0)
			(unlocked yes)
			(layer "B.Fab")
			(hide yes)
			(effects
				(font
					(size 1.016 1.016)
					(thickness 0.1524)
				)
				(justify mirror)
			)
		)
		(property "Device Type" "R402H16"
			(at -1.7907 -2.6416 0)
			(unlocked yes)
			(layer "B.Fab")
			(hide yes)
			(effects
				(font
					(size 1.016 1.016)
					(thickness 0.1524)
				)
				(justify mirror)
			)
		)
		(duplicate_pad_numbers_are_jumpers no)
		(fp_rect
			(start 0.381 0.8382)
			(end -0.381 -0.8382)
			(stroke
				(width 0)
				(type default)
			)
			(fill no)
			(layer "B.CrtYd")
		)
		(fp_rect
			(start 0.381 0.8382)
			(end -0.381 -0.8382)
			(stroke
				(width 0)
				(type default)
			)
			(fill no)
			(layer "B.Fab")
		)
		(pad "1" smd custom
			(at 0 -0.4318 180)
			(size 0.127 0.127)
			(layers "B.Cu" "B.Mask" "B.Paste")
			(net "P3V3_STBY_SENSE")
			(options
				(clearance outline)
				(anchor circle)
			)
			(primitives
				(gr_poly
					(pts
						(arc
							(start -0.2032 0.2794)
							(mid -0.239121 0.264521)
							(end -0.254 0.2286)
						)
						(arc
							(start -0.254 -0.2286)
							(mid -0.239121 -0.264521)
							(end -0.2032 -0.2794)
						)
						(arc
							(start 0.2032 -0.2794)
							(mid 0.239121 -0.264521)
							(end 0.254 -0.2286)
						)
						(arc
							(start 0.254 0.2286)
							(mid 0.239121 0.264521)
							(end 0.2032 0.2794)
						)
					)
					(width 0)
					(fill yes)
				)
			)
		)
		(pad "2" smd custom
			(at 0 0.4318 180)
			(size 0.127 0.127)
			(layers "B.Cu" "B.Mask" "B.Paste")
			(net "GND")
			(options
				(clearance outline)
				(anchor circle)
			)
			(primitives
				(gr_poly
					(pts
						(arc
							(start -0.2032 0.2794)
							(mid -0.239121 0.264521)
							(end -0.254 0.2286)
						)
						(arc
							(start -0.254 -0.2286)
							(mid -0.239121 -0.264521)
							(end -0.2032 -0.2794)
						)
						(arc
							(start 0.2032 -0.2794)
							(mid 0.239121 -0.264521)
							(end 0.254 -0.2286)
						)
						(arc
							(start 0.254 0.2286)
							(mid 0.239121 0.264521)
							(end 0.2032 0.2794)
						)
					)
					(width 0)
					(fill yes)
				)
			)
		)
	)
	(footprint ""
		(layer "B.Cu")
		(at 17.272 -51.181 180)
		(property "Reference" "R500"
			(at 0 0 0)
			(layer "B.SilkS")
			(hide yes)
			(effects
				(font
					(size 1.27 1.27)
				)
				(justify mirror)
			)
		)
		(property "Value" "150R3F-GP"
			(at 0.0254 -2.0193 180)
			(unlocked yes)
			(layer "B.Fab")
			(hide yes)
			(effects
				(font
					(size 1.016 1.016)
					(thickness 0.1524)
				)
				(justify mirror)
			)
		)
		(property "Device Type" "R603H22"
			(at 0.0254 -3.5433 180)
			(unlocked yes)
			(layer "B.Fab")
			(hide yes)
			(effects
				(font
					(size 1.016 1.016)
					(thickness 0.1524)
				)
				(justify mirror)
			)
		)
		(duplicate_pad_numbers_are_jumpers no)
		(fp_line
			(start 0.2032 0)
			(end 0.4191 0)
			(stroke
				(width 0.2032)
				(type default)
			)
			(layer "B.SilkS")
		)
		(fp_line
			(start -0.4318 0)
			(end -0.2032 0)
			(stroke
				(width 0.2032)
				(type default)
			)
			(layer "B.SilkS")
		)
		(fp_rect
			(start 0.635 1.1811)
			(end -0.635 -1.1811)
			(stroke
				(width 0)
				(type default)
			)
			(fill no)
			(layer "B.CrtYd")
		)
		(fp_rect
			(start 0.635 1.1811)
			(end -0.635 -1.1811)
			(stroke
				(width 0)
				(type default)
			)
			(fill no)
			(layer "B.Fab")
		)
		(pad "1" smd custom
			(at 0 -0.6604)
			(size 0.19685 0.19685)
			(layers "B.Cu" "B.Mask" "B.Paste")
			(net "P3V3")
			(options
				(clearance outline)
				(anchor circle)
			)
			(primitives
				(gr_poly
					(pts
						(arc
							(start 0.508 0.2921)
							(mid 0.478242 0.363942)
							(end 0.4064 0.3937)
						)
						(arc
							(start -0.4064 0.3937)
							(mid -0.478242 0.363942)
							(end -0.508 0.2921)
						)
						(arc
							(start -0.508 -0.2921)
							(mid -0.478242 -0.363942)
							(end -0.4064 -0.3937)
						)
						(arc
							(start 0.4064 -0.3937)
							(mid 0.478242 -0.363942)
							(end 0.508 -0.2921)
						)
					)
					(width 0)
					(fill yes)
				)
			)
		)
		(pad "2" smd custom
			(at 0 0.6604)
			(size 0.19685 0.19685)
			(layers "B.Cu" "B.Mask" "B.Paste")
			(net "P3V3_DISCHARGE_D")
			(options
				(clearance outline)
				(anchor circle)
			)
			(primitives
				(gr_poly
					(pts
						(arc
							(start 0.508 0.2921)
							(mid 0.478242 0.363942)
							(end 0.4064 0.3937)
						)
						(arc
							(start -0.4064 0.3937)
							(mid -0.478242 0.363942)
							(end -0.508 0.2921)
						)
						(arc
							(start -0.508 -0.2921)
							(mid -0.478242 -0.363942)
							(end -0.4064 -0.3937)
						)
						(arc
							(start 0.4064 -0.3937)
							(mid 0.478242 -0.363942)
							(end 0.508 -0.2921)
						)
					)
					(width 0)
					(fill yes)
				)
			)
		)
	)
	(footprint ""
		(layer "B.Cu")
		(at 46.228 -12.7)
		(property "Reference" "C262"
			(at 0 0 0)
			(layer "B.SilkS")
			(hide yes)
			(effects
				(font
					(size 1.27 1.27)
				)
				(justify mirror)
			)
		)
		(property "Value" "SCD1U16V2KX-3GP"
			(at -1.1811 -2.7051 0)
			(unlocked yes)
			(layer "B.Fab")
			(hide yes)
			(effects
				(font
					(size 1.016 1.016)
					(thickness 0.1524)
				)
				(justify mirror)
			)
		)
		(property "Device Type" "C402H22"
			(at -1.1811 -4.2291 0)
			(unlocked yes)
			(layer "B.Fab")
			(hide yes)
			(effects
				(font
					(size 1.016 1.016)
					(thickness 0.1524)
				)
				(justify mirror)
			)
		)
		(duplicate_pad_numbers_are_jumpers no)
		(fp_rect
			(start 0.381 0.7366)
			(end -0.381 -0.7366)
			(stroke
				(width 0)
				(type default)
			)
			(fill no)
			(layer "B.CrtYd")
		)
		(fp_rect
			(start 0.381 0.7366)
			(end -0.381 -0.7366)
			(stroke
				(width 0)
				(type default)
			)
			(fill no)
			(layer "B.Fab")
		)
		(pad "1" smd custom
			(at 0 -0.4572 180)
			(size 0.1143 0.1143)
			(layers "B.Cu" "B.Mask" "B.Paste")
			(net "P2E_CPU_SAS_C_TX_DP4")
			(options
				(clearance outline)
				(anchor circle)
			)
			(primitives
				(gr_poly
					(pts
						(arc
							(start -0.254 0.1778)
							(mid -0.239121 0.213721)
							(end -0.2032 0.2286)
						)
						(arc
							(start 0.2032 0.2286)
							(mid 0.239121 0.213721)
							(end 0.254 0.1778)
						)
						(arc
							(start 0.254 -0.1778)
							(mid 0.239121 -0.213721)
							(end 0.2032 -0.2286)
						)
						(arc
							(start -0.2032 -0.2286)
							(mid -0.239121 -0.213721)
							(end -0.254 -0.1778)
						)
					)
					(width 0)
					(fill yes)
				)
			)
		)
		(pad "2" smd custom
			(at 0 0.4572 180)
			(size 0.1143 0.1143)
			(layers "B.Cu" "B.Mask" "B.Paste")
			(net "P2E_CPU_SAS_TX_DP4")
			(options
				(clearance outline)
				(anchor circle)
			)
			(primitives
				(gr_poly
					(pts
						(arc
							(start -0.254 0.1778)
							(mid -0.239121 0.213721)
							(end -0.2032 0.2286)
						)
						(arc
							(start 0.2032 0.2286)
							(mid 0.239121 0.213721)
							(end 0.254 0.1778)
						)
						(arc
							(start 0.254 -0.1778)
							(mid 0.239121 -0.213721)
							(end 0.2032 -0.2286)
						)
						(arc
							(start -0.2032 -0.2286)
							(mid -0.239121 -0.213721)
							(end -0.254 -0.1778)
						)
					)
					(width 0)
					(fill yes)
				)
			)
		)
	)
	(footprint ""
		(layer "B.Cu")
		(at 48.006 -28.194 180)
		(property "Reference" "R450"
			(at 0 0 0)
			(layer "B.SilkS")
			(hide yes)
			(effects
				(font
					(size 1.27 1.27)
				)
				(justify mirror)
			)
		)
		(property "Value" "4K7R2F-GP"
			(at -1.7907 -1.1176 180)
			(unlocked yes)
			(layer "B.Fab")
			(hide yes)
			(effects
				(font
					(size 1.016 1.016)
					(thickness 0.1524)
				)
				(justify mirror)
			)
		)
		(property "Device Type" "R402H16"
			(at -1.7907 -2.6416 180)
			(unlocked yes)
			(layer "B.Fab")
			(hide yes)
			(effects
				(font
					(size 1.016 1.016)
					(thickness 0.1524)
				)
				(justify mirror)
			)
		)
		(duplicate_pad_numbers_are_jumpers no)
		(fp_rect
			(start 0.381 0.8382)
			(end -0.381 -0.8382)
			(stroke
				(width 0)
				(type default)
			)
			(fill no)
			(layer "B.CrtYd")
		)
		(fp_rect
			(start 0.381 0.8382)
			(end -0.381 -0.8382)
			(stroke
				(width 0)
				(type default)
			)
			(fill no)
			(layer "B.Fab")
		)
		(pad "1" smd custom
			(at 0 -0.4318)
			(size 0.127 0.127)
			(layers "B.Cu" "B.Mask" "B.Paste")
			(net "CLK_GEN_PG")
			(options
				(clearance outline)
				(anchor circle)
			)
			(primitives
				(gr_poly
					(pts
						(arc
							(start -0.2032 0.2794)
							(mid -0.239121 0.264521)
							(end -0.254 0.2286)
						)
						(arc
							(start -0.254 -0.2286)
							(mid -0.239121 -0.264521)
							(end -0.2032 -0.2794)
						)
						(arc
							(start 0.2032 -0.2794)
							(mid 0.239121 -0.264521)
							(end 0.254 -0.2286)
						)
						(arc
							(start 0.254 0.2286)
							(mid 0.239121 0.264521)
							(end 0.2032 0.2794)
						)
					)
					(width 0)
					(fill yes)
				)
			)
		)
		(pad "2" smd custom
			(at 0 0.4318)
			(size 0.127 0.127)
			(layers "B.Cu" "B.Mask" "B.Paste")
			(net "GND")
			(options
				(clearance outline)
				(anchor circle)
			)
			(primitives
				(gr_poly
					(pts
						(arc
							(start -0.2032 0.2794)
							(mid -0.239121 0.264521)
							(end -0.254 0.2286)
						)
						(arc
							(start -0.254 -0.2286)
							(mid -0.239121 -0.264521)
							(end -0.2032 -0.2794)
						)
						(arc
							(start 0.2032 -0.2794)
							(mid 0.239121 -0.264521)
							(end 0.254 -0.2286)
						)
						(arc
							(start 0.254 0.2286)
							(mid 0.239121 0.264521)
							(end 0.2032 0.2794)
						)
					)
					(width 0)
					(fill yes)
				)
			)
		)
	)
	(footprint ""
		(layer "B.Cu")
		(at 91.186 -46.101 180)
		(property "Reference" "C143"
			(at 0 0 0)
			(layer "B.SilkS")
			(hide yes)
			(effects
				(font
					(size 1.27 1.27)
				)
				(justify mirror)
			)
		)
		(property "Value" "SCD1U16V2JX-1-GP"
			(at -1.1811 -2.7051 180)
			(unlocked yes)
			(layer "B.Fab")
			(hide yes)
			(effects
				(font
					(size 1.016 1.016)
					(thickness 0.1524)
				)
				(justify mirror)
			)
		)
		(property "Device Type" "C402H22"
			(at -1.1811 -4.2291 180)
			(unlocked yes)
			(layer "B.Fab")
			(hide yes)
			(effects
				(font
					(size 1.016 1.016)
					(thickness 0.1524)
				)
				(justify mirror)
			)
		)
		(duplicate_pad_numbers_are_jumpers no)
		(fp_rect
			(start 0.381 0.7366)
			(end -0.381 -0.7366)
			(stroke
				(width 0)
				(type default)
			)
			(fill no)
			(layer "B.CrtYd")
		)
		(fp_rect
			(start 0.381 0.7366)
			(end -0.381 -0.7366)
			(stroke
				(width 0)
				(type default)
			)
			(fill no)
			(layer "B.Fab")
		)
		(pad "1" smd custom
			(at 0 -0.4572)
			(size 0.1143 0.1143)
			(layers "B.Cu" "B.Mask" "B.Paste")
			(net "P3V3_CPU")
			(options
				(clearance outline)
				(anchor circle)
			)
			(primitives
				(gr_poly
					(pts
						(arc
							(start -0.254 0.1778)
							(mid -0.239121 0.213721)
							(end -0.2032 0.2286)
						)
						(arc
							(start 0.2032 0.2286)
							(mid 0.239121 0.213721)
							(end 0.254 0.1778)
						)
						(arc
							(start 0.254 -0.1778)
							(mid 0.239121 -0.213721)
							(end 0.2032 -0.2286)
						)
						(arc
							(start -0.2032 -0.2286)
							(mid -0.239121 -0.213721)
							(end -0.254 -0.1778)
						)
					)
					(width 0)
					(fill yes)
				)
			)
		)
		(pad "2" smd custom
			(at 0 0.4572)
			(size 0.1143 0.1143)
			(layers "B.Cu" "B.Mask" "B.Paste")
			(net "GND")
			(options
				(clearance outline)
				(anchor circle)
			)
			(primitives
				(gr_poly
					(pts
						(arc
							(start -0.254 0.1778)
							(mid -0.239121 0.213721)
							(end -0.2032 0.2286)
						)
						(arc
							(start 0.2032 0.2286)
							(mid 0.239121 0.213721)
							(end 0.254 0.1778)
						)
						(arc
							(start 0.254 -0.1778)
							(mid 0.239121 -0.213721)
							(end 0.2032 -0.2286)
						)
						(arc
							(start -0.2032 -0.2286)
							(mid -0.239121 -0.213721)
							(end -0.254 -0.1778)
						)
					)
					(width 0)
					(fill yes)
				)
			)
		)
	)
	(footprint ""
		(layer "B.Cu")
		(at 144.399 -45.466 -90)
		(property "Reference" "R336"
			(at 0 0 90)
			(layer "B.SilkS")
			(hide yes)
			(effects
				(font
					(size 1.27 1.27)
				)
				(justify mirror)
			)
		)
		(property "Value" "1KR2F-3-GP"
			(at -0.064008 -3.993896 270)
			(unlocked yes)
			(layer "B.Fab")
			(hide yes)
			(effects
				(font
					(size 1.016 1.016)
					(thickness 0.1524)
				)
				(justify mirror)
			)
		)
		(property "Device Type" "R402H16"
			(at -0.064008 -5.517896 270)
			(unlocked yes)
			(layer "B.Fab")
			(hide yes)
			(effects
				(font
					(size 1.016 1.016)
					(thickness 0.1524)
				)
				(justify mirror)
			)
		)
		(duplicate_pad_numbers_are_jumpers no)
		(fp_rect
			(start 0.381 0.8382)
			(end -0.381 -0.8382)
			(stroke
				(width 0)
				(type default)
			)
			(fill no)
			(layer "B.CrtYd")
		)
		(fp_rect
			(start 0.381 0.8382)
			(end -0.381 -0.8382)
			(stroke
				(width 0)
				(type default)
			)
			(fill no)
			(layer "B.Fab")
		)
		(pad "1" smd custom
			(at 0 -0.4318 90)
			(size 0.127 0.127)
			(layers "B.Cu" "B.Mask" "B.Paste")
			(net "JTAG_PLD_TCK")
			(options
				(clearance outline)
				(anchor circle)
			)
			(primitives
				(gr_poly
					(pts
						(arc
							(start -0.2032 0.2794)
							(mid -0.239121 0.264521)
							(end -0.254 0.2286)
						)
						(arc
							(start -0.254 -0.2286)
							(mid -0.239121 -0.264521)
							(end -0.2032 -0.2794)
						)
						(arc
							(start 0.2032 -0.2794)
							(mid 0.239121 -0.264521)
							(end 0.254 -0.2286)
						)
						(arc
							(start 0.254 0.2286)
							(mid 0.239121 0.264521)
							(end 0.2032 0.2794)
						)
					)
					(width 0)
					(fill yes)
				)
			)
		)
		(pad "2" smd custom
			(at 0 0.4318 90)
			(size 0.127 0.127)
			(layers "B.Cu" "B.Mask" "B.Paste")
			(net "GND")
			(options
				(clearance outline)
				(anchor circle)
			)
			(primitives
				(gr_poly
					(pts
						(arc
							(start -0.2032 0.2794)
							(mid -0.239121 0.264521)
							(end -0.254 0.2286)
						)
						(arc
							(start -0.254 -0.2286)
							(mid -0.239121 -0.264521)
							(end -0.2032 -0.2794)
						)
						(arc
							(start 0.2032 -0.2794)
							(mid 0.239121 -0.264521)
							(end 0.254 -0.2286)
						)
						(arc
							(start 0.254 0.2286)
							(mid 0.239121 0.264521)
							(end 0.2032 0.2794)
						)
					)
					(width 0)
					(fill yes)
				)
			)
		)
	)
	(footprint ""
		(layer "B.Cu")
		(at 201.295 -38.6842 90)
		(property "Reference" "LED9"
			(at 0 0 90)
			(layer "B.SilkS")
			(hide yes)
			(effects
				(font
					(size 1.27 1.27)
				)
				(justify mirror)
			)
		)
		(property "Value" "LED-YG-51-GP"
			(at 0.0381 -2.6162 90)
			(unlocked yes)
			(layer "B.Fab")
			(hide yes)
			(effects
				(font
					(size 1.016 1.016)
					(thickness 0.1524)
				)
				(justify mirror)
			)
		)
		(property "Device Type" "LED1608AKH40"
			(at 0.0381 -4.1402 90)
			(unlocked yes)
			(layer "B.Fab")
			(hide yes)
			(effects
				(font
					(size 1.016 1.016)
					(thickness 0.1524)
				)
				(justify mirror)
			)
		)
		(duplicate_pad_numbers_are_jumpers no)
		(fp_line
			(start 0.5334 1.3081)
			(end -0.5334 1.3081)
			(stroke
				(width 0.254)
				(type default)
			)
			(layer "B.SilkS")
		)
		(fp_rect
			(start 0.6604 1.1811)
			(end -0.6604 -1.1811)
			(stroke
				(width 0)
				(type default)
			)
			(fill no)
			(layer "B.CrtYd")
		)
		(fp_rect
			(start 0.6604 1.1811)
			(end -0.6604 -1.1811)
			(stroke
				(width 0)
				(type default)
			)
			(fill no)
			(layer "B.Fab")
		)
		(pad "A" smd rect
			(at 0 -0.652526 270)
			(size 1.0668 0.8128)
			(layers "B.Cu" "B.Mask" "B.Paste")
			(net "PORT80_R_BIT4")
		)
		(pad "K" smd rect
			(at 0 0.652526 270)
			(size 1.0668 0.8128)
			(layers "B.Cu" "B.Mask" "B.Paste")
			(net "PORT80_BIT4")
		)
	)
	(footprint ""
		(layer "B.Cu")
		(at 118.11 -6.096 90)
		(property "Reference" "C335"
			(at 0 0 90)
			(layer "B.SilkS")
			(hide yes)
			(effects
				(font
					(size 1.27 1.27)
				)
				(justify mirror)
			)
		)
		(property "Value" "SCD1U10V2KX-5GP"
			(at -1.8923 -1.2065 90)
			(unlocked yes)
			(layer "B.Fab")
			(hide yes)
			(effects
				(font
					(size 1.016 1.016)
					(thickness 0.1524)
				)
				(justify mirror)
			)
		)
		(property "Device Type" "C402H22"
			(at -1.8923 -2.7305 90)
			(unlocked yes)
			(layer "B.Fab")
			(hide yes)
			(effects
				(font
					(size 1.016 1.016)
					(thickness 0.1524)
				)
				(justify mirror)
			)
		)
		(duplicate_pad_numbers_are_jumpers no)
		(fp_rect
			(start 0.381 0.7366)
			(end -0.381 -0.7366)
			(stroke
				(width 0)
				(type default)
			)
			(fill no)
			(layer "B.CrtYd")
		)
		(fp_rect
			(start 0.381 0.7366)
			(end -0.381 -0.7366)
			(stroke
				(width 0)
				(type default)
			)
			(fill no)
			(layer "B.Fab")
		)
		(pad "1" smd custom
			(at 0 -0.4572 270)
			(size 0.1143 0.1143)
			(layers "B.Cu" "B.Mask" "B.Paste")
			(net "P3V3")
			(options
				(clearance outline)
				(anchor circle)
			)
			(primitives
				(gr_poly
					(pts
						(arc
							(start -0.254 0.1778)
							(mid -0.239121 0.213721)
							(end -0.2032 0.2286)
						)
						(arc
							(start 0.2032 0.2286)
							(mid 0.239121 0.213721)
							(end 0.254 0.1778)
						)
						(arc
							(start 0.254 -0.1778)
							(mid 0.239121 -0.213721)
							(end 0.2032 -0.2286)
						)
						(arc
							(start -0.2032 -0.2286)
							(mid -0.239121 -0.213721)
							(end -0.254 -0.1778)
						)
					)
					(width 0)
					(fill yes)
				)
			)
		)
		(pad "2" smd custom
			(at 0 0.4572 270)
			(size 0.1143 0.1143)
			(layers "B.Cu" "B.Mask" "B.Paste")
			(net "GND")
			(options
				(clearance outline)
				(anchor circle)
			)
			(primitives
				(gr_poly
					(pts
						(arc
							(start -0.254 0.1778)
							(mid -0.239121 0.213721)
							(end -0.2032 0.2286)
						)
						(arc
							(start 0.2032 0.2286)
							(mid 0.239121 0.213721)
							(end 0.254 0.1778)
						)
						(arc
							(start 0.254 -0.1778)
							(mid 0.239121 -0.213721)
							(end 0.2032 -0.2286)
						)
						(arc
							(start -0.2032 -0.2286)
							(mid -0.239121 -0.213721)
							(end -0.254 -0.1778)
						)
					)
					(width 0)
					(fill yes)
				)
			)
		)
	)
	(footprint ""
		(layer "B.Cu")
		(at 19.812 -61.087 180)
		(property "Reference" "PR2"
			(at 0 0 0)
			(layer "B.SilkS")
			(hide yes)
			(effects
				(font
					(size 1.27 1.27)
				)
				(justify mirror)
			)
		)
		(property "Value" "1KR2F-3-GP"
			(at -1.7907 -1.1176 180)
			(unlocked yes)
			(layer "B.Fab")
			(hide yes)
			(effects
				(font
					(size 1.016 1.016)
					(thickness 0.1524)
				)
				(justify mirror)
			)
		)
		(property "Device Type" "R402H16"
			(at -1.7907 -2.6416 180)
			(unlocked yes)
			(layer "B.Fab")
			(hide yes)
			(effects
				(font
					(size 1.016 1.016)
					(thickness 0.1524)
				)
				(justify mirror)
			)
		)
		(duplicate_pad_numbers_are_jumpers no)
		(fp_rect
			(start 0.381 0.8382)
			(end -0.381 -0.8382)
			(stroke
				(width 0)
				(type default)
			)
			(fill no)
			(layer "B.CrtYd")
		)
		(fp_rect
			(start 0.381 0.8382)
			(end -0.381 -0.8382)
			(stroke
				(width 0)
				(type default)
			)
			(fill no)
			(layer "B.Fab")
		)
		(pad "1" smd custom
			(at 0 -0.4318)
			(size 0.127 0.127)
			(layers "B.Cu" "B.Mask" "B.Paste")
			(net "VR_PVNN_FB")
			(options
				(clearance outline)
				(anchor circle)
			)
			(primitives
				(gr_poly
					(pts
						(arc
							(start -0.2032 0.2794)
							(mid -0.239121 0.264521)
							(end -0.254 0.2286)
						)
						(arc
							(start -0.254 -0.2286)
							(mid -0.239121 -0.264521)
							(end -0.2032 -0.2794)
						)
						(arc
							(start 0.2032 -0.2794)
							(mid 0.239121 -0.264521)
							(end 0.254 -0.2286)
						)
						(arc
							(start 0.254 0.2286)
							(mid 0.239121 0.264521)
							(end 0.2032 0.2794)
						)
					)
					(width 0)
					(fill yes)
				)
			)
		)
		(pad "2" smd custom
			(at 0 0.4318)
			(size 0.127 0.127)
			(layers "B.Cu" "B.Mask" "B.Paste")
			(net "VR_PVNN_FB_RC2")
			(options
				(clearance outline)
				(anchor circle)
			)
			(primitives
				(gr_poly
					(pts
						(arc
							(start -0.2032 0.2794)
							(mid -0.239121 0.264521)
							(end -0.254 0.2286)
						)
						(arc
							(start -0.254 -0.2286)
							(mid -0.239121 -0.264521)
							(end -0.2032 -0.2794)
						)
						(arc
							(start 0.2032 -0.2794)
							(mid 0.239121 -0.264521)
							(end 0.254 -0.2286)
						)
						(arc
							(start 0.254 0.2286)
							(mid 0.239121 0.264521)
							(end 0.2032 0.2794)
						)
					)
					(width 0)
					(fill yes)
				)
			)
		)
	)
	(footprint ""
		(layer "B.Cu")
		(at 89.154 -46.228 180)
		(property "Reference" "R298"
			(at 0 0 0)
			(layer "B.SilkS")
			(hide yes)
			(effects
				(font
					(size 1.27 1.27)
				)
				(justify mirror)
			)
		)
		(property "Value" "10KR2F-2-GP"
			(at -0.064008 -3.993896 180)
			(unlocked yes)
			(layer "B.Fab")
			(hide yes)
			(effects
				(font
					(size 1.016 1.016)
					(thickness 0.1524)
				)
				(justify mirror)
			)
		)
		(property "Device Type" "R402H16"
			(at -0.064008 -5.517896 180)
			(unlocked yes)
			(layer "B.Fab")
			(hide yes)
			(effects
				(font
					(size 1.016 1.016)
					(thickness 0.1524)
				)
				(justify mirror)
			)
		)
		(duplicate_pad_numbers_are_jumpers no)
		(fp_rect
			(start 0.381 0.8382)
			(end -0.381 -0.8382)
			(stroke
				(width 0)
				(type default)
			)
			(fill no)
			(layer "B.CrtYd")
		)
		(fp_rect
			(start 0.381 0.8382)
			(end -0.381 -0.8382)
			(stroke
				(width 0)
				(type default)
			)
			(fill no)
			(layer "B.Fab")
		)
		(pad "1" smd custom
			(at 0 -0.4318)
			(size 0.127 0.127)
			(layers "B.Cu" "B.Mask" "B.Paste")
			(net "IRQ_CPU_SERIAL")
			(options
				(clearance outline)
				(anchor circle)
			)
			(primitives
				(gr_poly
					(pts
						(arc
							(start -0.2032 0.2794)
							(mid -0.239121 0.264521)
							(end -0.254 0.2286)
						)
						(arc
							(start -0.254 -0.2286)
							(mid -0.239121 -0.264521)
							(end -0.2032 -0.2794)
						)
						(arc
							(start 0.2032 -0.2794)
							(mid 0.239121 -0.264521)
							(end 0.254 -0.2286)
						)
						(arc
							(start 0.254 0.2286)
							(mid 0.239121 0.264521)
							(end 0.2032 0.2794)
						)
					)
					(width 0)
					(fill yes)
				)
			)
		)
		(pad "2" smd custom
			(at 0 0.4318)
			(size 0.127 0.127)
			(layers "B.Cu" "B.Mask" "B.Paste")
			(net "GND")
			(options
				(clearance outline)
				(anchor circle)
			)
			(primitives
				(gr_poly
					(pts
						(arc
							(start -0.2032 0.2794)
							(mid -0.239121 0.264521)
							(end -0.254 0.2286)
						)
						(arc
							(start -0.254 -0.2286)
							(mid -0.239121 -0.264521)
							(end -0.2032 -0.2794)
						)
						(arc
							(start 0.2032 -0.2794)
							(mid 0.239121 -0.264521)
							(end 0.254 -0.2286)
						)
						(arc
							(start 0.254 0.2286)
							(mid 0.239121 0.264521)
							(end 0.2032 0.2794)
						)
					)
					(width 0)
					(fill yes)
				)
			)
		)
	)
	(footprint ""
		(layer "B.Cu")
		(at 18.923 -21.463 -90)
		(property "Reference" "PR99"
			(at 0 0 90)
			(layer "B.SilkS")
			(hide yes)
			(effects
				(font
					(size 1.27 1.27)
				)
				(justify mirror)
			)
		)
		(property "Value" "0R2J-2-GP"
			(at -1.7907 -1.1176 270)
			(unlocked yes)
			(layer "B.Fab")
			(hide yes)
			(effects
				(font
					(size 1.016 1.016)
					(thickness 0.1524)
				)
				(justify mirror)
			)
		)
		(property "Device Type" "R402H16"
			(at -1.7907 -2.6416 270)
			(unlocked yes)
			(layer "B.Fab")
			(hide yes)
			(effects
				(font
					(size 1.016 1.016)
					(thickness 0.1524)
				)
				(justify mirror)
			)
		)
		(duplicate_pad_numbers_are_jumpers no)
		(fp_rect
			(start 0.381 0.8382)
			(end -0.381 -0.8382)
			(stroke
				(width 0)
				(type default)
			)
			(fill no)
			(layer "B.CrtYd")
		)
		(fp_rect
			(start 0.381 0.8382)
			(end -0.381 -0.8382)
			(stroke
				(width 0)
				(type default)
			)
			(fill no)
			(layer "B.Fab")
		)
		(pad "1" smd custom
			(at 0 -0.4318 90)
			(size 0.127 0.127)
			(layers "B.Cu" "B.Mask" "B.Paste")
			(net "PWRGD_P1V35_PG")
			(options
				(clearance outline)
				(anchor circle)
			)
			(primitives
				(gr_poly
					(pts
						(arc
							(start -0.2032 0.2794)
							(mid -0.239121 0.264521)
							(end -0.254 0.2286)
						)
						(arc
							(start -0.254 -0.2286)
							(mid -0.239121 -0.264521)
							(end -0.2032 -0.2794)
						)
						(arc
							(start 0.2032 -0.2794)
							(mid 0.239121 -0.264521)
							(end 0.254 -0.2286)
						)
						(arc
							(start 0.254 0.2286)
							(mid 0.239121 0.264521)
							(end 0.2032 0.2794)
						)
					)
					(width 0)
					(fill yes)
				)
			)
		)
		(pad "2" smd custom
			(at 0 0.4318 90)
			(size 0.127 0.127)
			(layers "B.Cu" "B.Mask" "B.Paste")
			(net "P1V0_EN")
			(options
				(clearance outline)
				(anchor circle)
			)
			(primitives
				(gr_poly
					(pts
						(arc
							(start -0.2032 0.2794)
							(mid -0.239121 0.264521)
							(end -0.254 0.2286)
						)
						(arc
							(start -0.254 -0.2286)
							(mid -0.239121 -0.264521)
							(end -0.2032 -0.2794)
						)
						(arc
							(start 0.2032 -0.2794)
							(mid 0.239121 -0.264521)
							(end 0.254 -0.2286)
						)
						(arc
							(start 0.254 0.2286)
							(mid 0.239121 0.264521)
							(end 0.2032 0.2794)
						)
					)
					(width 0)
					(fill yes)
				)
			)
		)
	)
	(footprint ""
		(layer "B.Cu")
		(at 41.402 -42.291)
		(property "Reference" "R120"
			(at 0 0 0)
			(layer "B.SilkS")
			(hide yes)
			(effects
				(font
					(size 1.27 1.27)
				)
				(justify mirror)
			)
		)
		(property "Value" "0R2J-2-GP"
			(at -0.064008 -3.993896 0)
			(unlocked yes)
			(layer "B.Fab")
			(hide yes)
			(effects
				(font
					(size 1.016 1.016)
					(thickness 0.1524)
				)
				(justify mirror)
			)
		)
		(property "Device Type" "R402H16"
			(at -0.064008 -5.517896 0)
			(unlocked yes)
			(layer "B.Fab")
			(hide yes)
			(effects
				(font
					(size 1.016 1.016)
					(thickness 0.1524)
				)
				(justify mirror)
			)
		)
		(duplicate_pad_numbers_are_jumpers no)
		(fp_rect
			(start 0.381 0.8382)
			(end -0.381 -0.8382)
			(stroke
				(width 0)
				(type default)
			)
			(fill no)
			(layer "B.CrtYd")
		)
		(fp_rect
			(start 0.381 0.8382)
			(end -0.381 -0.8382)
			(stroke
				(width 0)
				(type default)
			)
			(fill no)
			(layer "B.Fab")
		)
		(pad "1" smd custom
			(at 0 -0.4318 180)
			(size 0.127 0.127)
			(layers "B.Cu" "B.Mask" "B.Paste")
			(net "CLK_GEN_R_PG")
			(options
				(clearance outline)
				(anchor circle)
			)
			(primitives
				(gr_poly
					(pts
						(arc
							(start -0.2032 0.2794)
							(mid -0.239121 0.264521)
							(end -0.254 0.2286)
						)
						(arc
							(start -0.254 -0.2286)
							(mid -0.239121 -0.264521)
							(end -0.2032 -0.2794)
						)
						(arc
							(start 0.2032 -0.2794)
							(mid 0.239121 -0.264521)
							(end 0.254 -0.2286)
						)
						(arc
							(start 0.254 0.2286)
							(mid 0.239121 0.264521)
							(end 0.2032 0.2794)
						)
					)
					(width 0)
					(fill yes)
				)
			)
		)
		(pad "2" smd custom
			(at 0 0.4318 180)
			(size 0.127 0.127)
			(layers "B.Cu" "B.Mask" "B.Paste")
			(net "CLK_GEN_PG")
			(options
				(clearance outline)
				(anchor circle)
			)
			(primitives
				(gr_poly
					(pts
						(arc
							(start -0.2032 0.2794)
							(mid -0.239121 0.264521)
							(end -0.254 0.2286)
						)
						(arc
							(start -0.254 -0.2286)
							(mid -0.239121 -0.264521)
							(end -0.2032 -0.2794)
						)
						(arc
							(start 0.2032 -0.2794)
							(mid 0.239121 -0.264521)
							(end 0.254 -0.2286)
						)
						(arc
							(start 0.254 0.2286)
							(mid 0.239121 0.264521)
							(end 0.2032 0.2794)
						)
					)
					(width 0)
					(fill yes)
				)
			)
		)
	)
	(footprint ""
		(layer "B.Cu")
		(at 133.731 -37.719 -90)
		(property "Reference" "C136"
			(at 0 0 90)
			(layer "B.SilkS")
			(hide yes)
			(effects
				(font
					(size 1.27 1.27)
				)
				(justify mirror)
			)
		)
		(property "Value" "SCD1U10V2KX-5GP"
			(at -1.1811 -2.7051 270)
			(unlocked yes)
			(layer "B.Fab")
			(hide yes)
			(effects
				(font
					(size 1.016 1.016)
					(thickness 0.1524)
				)
				(justify mirror)
			)
		)
		(property "Device Type" "C402H22"
			(at -1.1811 -4.2291 270)
			(unlocked yes)
			(layer "B.Fab")
			(hide yes)
			(effects
				(font
					(size 1.016 1.016)
					(thickness 0.1524)
				)
				(justify mirror)
			)
		)
		(duplicate_pad_numbers_are_jumpers no)
		(fp_rect
			(start 0.381 0.7366)
			(end -0.381 -0.7366)
			(stroke
				(width 0)
				(type default)
			)
			(fill no)
			(layer "B.CrtYd")
		)
		(fp_rect
			(start 0.381 0.7366)
			(end -0.381 -0.7366)
			(stroke
				(width 0)
				(type default)
			)
			(fill no)
			(layer "B.Fab")
		)
		(pad "1" smd custom
			(at 0 -0.4572 90)
			(size 0.1143 0.1143)
			(layers "B.Cu" "B.Mask" "B.Paste")
			(net "P3V3_STBY")
			(options
				(clearance outline)
				(anchor circle)
			)
			(primitives
				(gr_poly
					(pts
						(arc
							(start -0.254 0.1778)
							(mid -0.239121 0.213721)
							(end -0.2032 0.2286)
						)
						(arc
							(start 0.2032 0.2286)
							(mid 0.239121 0.213721)
							(end 0.254 0.1778)
						)
						(arc
							(start 0.254 -0.1778)
							(mid 0.239121 -0.213721)
							(end 0.2032 -0.2286)
						)
						(arc
							(start -0.2032 -0.2286)
							(mid -0.239121 -0.213721)
							(end -0.254 -0.1778)
						)
					)
					(width 0)
					(fill yes)
				)
			)
		)
		(pad "2" smd custom
			(at 0 0.4572 90)
			(size 0.1143 0.1143)
			(layers "B.Cu" "B.Mask" "B.Paste")
			(net "GND")
			(options
				(clearance outline)
				(anchor circle)
			)
			(primitives
				(gr_poly
					(pts
						(arc
							(start -0.254 0.1778)
							(mid -0.239121 0.213721)
							(end -0.2032 0.2286)
						)
						(arc
							(start 0.2032 0.2286)
							(mid 0.239121 0.213721)
							(end 0.254 0.1778)
						)
						(arc
							(start 0.254 -0.1778)
							(mid 0.239121 -0.213721)
							(end 0.2032 -0.2286)
						)
						(arc
							(start -0.2032 -0.2286)
							(mid -0.239121 -0.213721)
							(end -0.254 -0.1778)
						)
					)
					(width 0)
					(fill yes)
				)
			)
		)
	)
	(footprint ""
		(layer "B.Cu")
		(at 74.168 -40.767 90)
		(property "Reference" "R318"
			(at 0 0 90)
			(layer "B.SilkS")
			(hide yes)
			(effects
				(font
					(size 1.27 1.27)
				)
				(justify mirror)
			)
		)
		(property "Value" "4K7R2F-GP"
			(at -0.064008 -3.993896 90)
			(unlocked yes)
			(layer "B.Fab")
			(hide yes)
			(effects
				(font
					(size 1.016 1.016)
					(thickness 0.1524)
				)
				(justify mirror)
			)
		)
		(property "Device Type" "R402H16"
			(at -0.064008 -5.517896 90)
			(unlocked yes)
			(layer "B.Fab")
			(hide yes)
			(effects
				(font
					(size 1.016 1.016)
					(thickness 0.1524)
				)
				(justify mirror)
			)
		)
		(duplicate_pad_numbers_are_jumpers no)
		(fp_rect
			(start 0.381 0.8382)
			(end -0.381 -0.8382)
			(stroke
				(width 0)
				(type default)
			)
			(fill no)
			(layer "B.CrtYd")
		)
		(fp_rect
			(start 0.381 0.8382)
			(end -0.381 -0.8382)
			(stroke
				(width 0)
				(type default)
			)
			(fill no)
			(layer "B.Fab")
		)
		(pad "1" smd custom
			(at 0 -0.4318 270)
			(size 0.127 0.127)
			(layers "B.Cu" "B.Mask" "B.Paste")
			(net "P3V3")
			(options
				(clearance outline)
				(anchor circle)
			)
			(primitives
				(gr_poly
					(pts
						(arc
							(start -0.2032 0.2794)
							(mid -0.239121 0.264521)
							(end -0.254 0.2286)
						)
						(arc
							(start -0.254 -0.2286)
							(mid -0.239121 -0.264521)
							(end -0.2032 -0.2794)
						)
						(arc
							(start 0.2032 -0.2794)
							(mid 0.239121 -0.264521)
							(end 0.254 -0.2286)
						)
						(arc
							(start 0.254 0.2286)
							(mid 0.239121 0.264521)
							(end 0.2032 0.2794)
						)
					)
					(width 0)
					(fill yes)
				)
			)
		)
		(pad "2" smd custom
			(at 0 0.4318 270)
			(size 0.127 0.127)
			(layers "B.Cu" "B.Mask" "B.Paste")
			(net "BD_ID_1")
			(options
				(clearance outline)
				(anchor circle)
			)
			(primitives
				(gr_poly
					(pts
						(arc
							(start -0.2032 0.2794)
							(mid -0.239121 0.264521)
							(end -0.254 0.2286)
						)
						(arc
							(start -0.254 -0.2286)
							(mid -0.239121 -0.264521)
							(end -0.2032 -0.2794)
						)
						(arc
							(start 0.2032 -0.2794)
							(mid 0.239121 -0.264521)
							(end 0.254 -0.2286)
						)
						(arc
							(start 0.254 0.2286)
							(mid 0.239121 0.264521)
							(end 0.2032 0.2794)
						)
					)
					(width 0)
					(fill yes)
				)
			)
		)
	)
	(footprint ""
		(layer "B.Cu")
		(at 74.168 -40.005 -90)
		(property "Reference" "R323"
			(at 0 0 90)
			(layer "B.SilkS")
			(hide yes)
			(effects
				(font
					(size 1.27 1.27)
				)
				(justify mirror)
			)
		)
		(property "Value" "10KR2F-2-GP"
			(at -0.064008 -3.993896 270)
			(unlocked yes)
			(layer "B.Fab")
			(hide yes)
			(effects
				(font
					(size 1.016 1.016)
					(thickness 0.1524)
				)
				(justify mirror)
			)
		)
		(property "Device Type" "R402H16"
			(at -0.064008 -5.517896 270)
			(unlocked yes)
			(layer "B.Fab")
			(hide yes)
			(effects
				(font
					(size 1.016 1.016)
					(thickness 0.1524)
				)
				(justify mirror)
			)
		)
		(duplicate_pad_numbers_are_jumpers no)
		(fp_rect
			(start 0.381 0.8382)
			(end -0.381 -0.8382)
			(stroke
				(width 0)
				(type default)
			)
			(fill no)
			(layer "B.CrtYd")
		)
		(fp_rect
			(start 0.381 0.8382)
			(end -0.381 -0.8382)
			(stroke
				(width 0)
				(type default)
			)
			(fill no)
			(layer "B.Fab")
		)
		(pad "1" smd custom
			(at 0 -0.4318 90)
			(size 0.127 0.127)
			(layers "B.Cu" "B.Mask" "B.Paste")
			(net "CORE_PWROK")
			(options
				(clearance outline)
				(anchor circle)
			)
			(primitives
				(gr_poly
					(pts
						(arc
							(start -0.2032 0.2794)
							(mid -0.239121 0.264521)
							(end -0.254 0.2286)
						)
						(arc
							(start -0.254 -0.2286)
							(mid -0.239121 -0.264521)
							(end -0.2032 -0.2794)
						)
						(arc
							(start 0.2032 -0.2794)
							(mid 0.239121 -0.264521)
							(end 0.254 -0.2286)
						)
						(arc
							(start 0.254 0.2286)
							(mid 0.239121 0.264521)
							(end 0.2032 0.2794)
						)
					)
					(width 0)
					(fill yes)
				)
			)
		)
		(pad "2" smd custom
			(at 0 0.4318 90)
			(size 0.127 0.127)
			(layers "B.Cu" "B.Mask" "B.Paste")
			(net "GND")
			(options
				(clearance outline)
				(anchor circle)
			)
			(primitives
				(gr_poly
					(pts
						(arc
							(start -0.2032 0.2794)
							(mid -0.239121 0.264521)
							(end -0.254 0.2286)
						)
						(arc
							(start -0.254 -0.2286)
							(mid -0.239121 -0.264521)
							(end -0.2032 -0.2794)
						)
						(arc
							(start 0.2032 -0.2794)
							(mid 0.239121 -0.264521)
							(end 0.254 -0.2286)
						)
						(arc
							(start 0.254 0.2286)
							(mid 0.239121 0.264521)
							(end 0.2032 0.2794)
						)
					)
					(width 0)
					(fill yes)
				)
			)
		)
	)
	(footprint ""
		(layer "B.Cu")
		(at 45.7708 -22.2504)
		(property "Reference" "U28"
			(at 0 0 0)
			(layer "B.SilkS")
			(hide yes)
			(effects
				(font
					(size 1.27 1.27)
				)
				(justify mirror)
			)
		)
		(property "Value" "9DB833AGILFT-GP"
			(at 7.7724 -0.4572 0)
			(unlocked yes)
			(layer "B.Fab")
			(hide yes)
			(effects
				(font
					(size 1.016 1.016)
					(thickness 0.1524)
				)
				(justify mirror)
			)
		)
		(property "Device Type" "TSOIC48H48"
			(at 7.7724 -1.9812 0)
			(unlocked yes)
			(layer "B.Fab")
			(hide yes)
			(effects
				(font
					(size 1.016 1.016)
					(thickness 0.1524)
				)
				(justify mirror)
			)
		)
		(duplicate_pad_numbers_are_jumpers no)
		(fp_line
			(start -5.8674 -2.6162)
			(end 6.4262 -2.6162)
			(stroke
				(width 0.1524)
				(type default)
			)
			(layer "B.SilkS")
		)
		(fp_line
			(start -5.8674 2.6162)
			(end -5.8674 -2.6162)
			(stroke
				(width 0.1524)
				(type default)
			)
			(layer "B.SilkS")
		)
		(fp_line
			(start 5.7658 0)
			(end 6.4262 0.6604)
			(stroke
				(width 0.1524)
				(type default)
			)
			(layer "B.SilkS")
		)
		(fp_line
			(start 6.3754 2.6162)
			(end 6.3754 4.2926)
			(stroke
				(width 0.254)
				(type default)
			)
			(layer "B.SilkS")
		)
		(fp_line
			(start 6.4262 -2.6162)
			(end 6.4262 -0.6604)
			(stroke
				(width 0.1524)
				(type default)
			)
			(layer "B.SilkS")
		)
		(fp_line
			(start 6.4262 -0.6604)
			(end 5.7658 0)
			(stroke
				(width 0.1524)
				(type default)
			)
			(layer "B.SilkS")
		)
		(fp_line
			(start 6.4262 0.6604)
			(end 6.4262 -0.6604)
			(stroke
				(width 0.1524)
				(type default)
			)
			(layer "B.SilkS")
		)
		(fp_line
			(start 6.4262 2.6162)
			(end -5.8674 2.6162)
			(stroke
				(width 0.1524)
				(type default)
			)
			(layer "B.SilkS")
		)
		(fp_line
			(start 6.4262 2.6162)
			(end 6.4262 0.6604)
			(stroke
				(width 0.1524)
				(type default)
			)
			(layer "B.SilkS")
		)
		(fp_rect
			(start 6.5024 4.4196)
			(end -6.5024 -4.4196)
			(stroke
				(width 0)
				(type default)
			)
			(fill no)
			(layer "B.CrtYd")
		)
		(fp_rect
			(start 6.5024 4.4196)
			(end -6.5024 -4.4196)
			(stroke
				(width 0)
				(type default)
			)
			(fill no)
			(layer "B.Fab")
		)
		(pad "1" smd rect
			(at 5.75437 3.5941 180)
			(size 0.3048 1.397)
			(layers "B.Cu" "B.Mask" "B.Paste")
			(net "CLKBUFF_SRC_DIV#")
		)
		(pad "2" smd rect
			(at 5.25399 3.5941 180)
			(size 0.3048 1.397)
			(layers "B.Cu" "B.Mask" "B.Paste")
			(net "P3V3_VDDA_CLKBUFF")
		)
		(pad "3" smd rect
			(at 4.75361 3.5941 180)
			(size 0.3048 1.397)
			(layers "B.Cu" "B.Mask" "B.Paste")
			(net "GND")
		)
		(pad "4" smd rect
			(at 4.25323 3.5941 180)
			(size 0.3048 1.397)
			(layers "B.Cu" "B.Mask" "B.Paste")
			(net "CLK_100M_CLKBUFF_DP")
		)
		(pad "5" smd rect
			(at 3.75285 3.5941 180)
			(size 0.3048 1.397)
			(layers "B.Cu" "B.Mask" "B.Paste")
			(net "CLK_100M_CLKBUFF_DN")
		)
		(pad "6" smd rect
			(at 3.25247 3.5941 180)
			(size 0.3048 1.397)
			(layers "B.Cu" "B.Mask" "B.Paste")
			(net "CLKBUFF_OE0#")
		)
		(pad "7" smd rect
			(at 2.75209 3.5941 180)
			(size 0.3048 1.397)
			(layers "B.Cu" "B.Mask" "B.Paste")
			(net "CLKBUFF_OE3#")
		)
		(pad "8" smd rect
			(at 2.25171 3.5941 180)
			(size 0.3048 1.397)
			(layers "B.Cu" "B.Mask" "B.Paste")
			(net "CLK_100M_CLKBUFF_NGFF_R_DP")
		)
		(pad "9" smd rect
			(at 1.75133 3.5941 180)
			(size 0.3048 1.397)
			(layers "B.Cu" "B.Mask" "B.Paste")
			(net "CLK_100M_CLKBUFF_NGFF_R_DN")
		)
		(pad "10" smd rect
			(at 1.25095 3.5941 180)
			(size 0.3048 1.397)
			(layers "B.Cu" "B.Mask" "B.Paste")
			(net "GND")
		)
		(pad "11" smd rect
			(at 0.75057 3.5941 180)
			(size 0.3048 1.397)
			(layers "B.Cu" "B.Mask" "B.Paste")
			(net "P3V3_VDD_CLKBUFF")
		)
		(pad "12" smd rect
			(at 0.25019 3.5941 180)
			(size 0.3048 1.397)
			(layers "B.Cu" "B.Mask" "B.Paste")
			(net "CLK_100M_PCIE2_REFCLK_R_DP")
		)
		(pad "13" smd rect
			(at -0.25019 3.5941 180)
			(size 0.3048 1.397)
			(layers "B.Cu" "B.Mask" "B.Paste")
			(net "CLK_100M_PCIE2_REFCLK_R_DN")
		)
		(pad "14" smd rect
			(at -0.75057 3.5941 180)
			(size 0.3048 1.397)
			(layers "B.Cu" "B.Mask" "B.Paste")
			(net "CLKBUFF_OE1#")
		)
		(pad "15" smd rect
			(at -1.25095 3.5941 180)
			(size 0.3048 1.397)
			(layers "B.Cu" "B.Mask" "B.Paste")
			(net "CLKBUFF_OE2#")
		)
		(pad "16" smd rect
			(at -1.75133 3.5941 180)
			(size 0.3048 1.397)
			(layers "B.Cu" "B.Mask" "B.Paste")
			(net "CLK_100M_CLKBUFF_ENET_R_DP")
		)
		(pad "17" smd rect
			(at -2.25171 3.5941 180)
			(size 0.3048 1.397)
			(layers "B.Cu" "B.Mask" "B.Paste")
			(net "CLK_100M_CLKBUFF_ENET_R_DN")
		)
		(pad "18" smd rect
			(at -2.75209 3.5941 180)
			(size 0.3048 1.397)
			(layers "B.Cu" "B.Mask" "B.Paste")
			(net "GND")
		)
		(pad "19" smd rect
			(at -3.25247 3.5941 180)
			(size 0.3048 1.397)
			(layers "B.Cu" "B.Mask" "B.Paste")
			(net "P3V3_VDD_CLKBUFF")
		)
		(pad "20" smd rect
			(at -3.75285 3.5941 180)
			(size 0.3048 1.397)
			(layers "B.Cu" "B.Mask" "B.Paste")
			(net "CLK_100M_CLKBUFF_SAS_R_DP")
		)
		(pad "21" smd rect
			(at -4.25323 3.5941 180)
			(size 0.3048 1.397)
			(layers "B.Cu" "B.Mask" "B.Paste")
			(net "CLK_100M_CLKBUFF_SAS_R_DN")
		)
		(pad "22" smd rect
			(at -4.75361 3.5941 180)
			(size 0.3048 1.397)
			(layers "B.Cu" "B.Mask" "B.Paste")
			(net "CLKBUFF_BYPASS_OR_PLL")
		)
		(pad "23" smd rect
			(at -5.25399 3.5941 180)
			(size 0.3048 1.397)
			(layers "B.Cu" "B.Mask" "B.Paste")
			(net "SMB_CLKBUFF_R_CLK")
		)
		(pad "24" smd rect
			(at -5.75437 3.5941 180)
			(size 0.3048 1.397)
			(layers "B.Cu" "B.Mask" "B.Paste")
			(net "SMB_CLKBUFF_R_DATA")
		)
		(pad "25" smd rect
			(at -5.75437 -3.5941 180)
			(size 0.3048 1.397)
			(layers "B.Cu" "B.Mask" "B.Paste")
			(net "GND")
		)
		(pad "26" smd rect
			(at -5.25399 -3.5941 180)
			(size 0.3048 1.397)
			(layers "B.Cu" "B.Mask" "B.Paste")
			(net "GND")
		)
		(pad "27" smd rect
			(at -4.75361 -3.5941 180)
			(size 0.3048 1.397)
			(layers "B.Cu" "B.Mask" "B.Paste")
			(net "P3V3_VDD_CLKBUFF")
		)
		(pad "28" smd rect
			(at -4.25323 -3.5941 180)
			(size 0.3048 1.397)
			(layers "B.Cu" "B.Mask" "B.Paste")
			(net "CLKCUFF_SMB_ADDR")
		)
		(pad "29" smd rect
			(at -3.75285 -3.5941 180)
			(size 0.3048 1.397)
			(layers "B.Cu" "B.Mask" "B.Paste")
			(net "CLK_100M_CLKBUFF_PCIE_R_DN")
		)
		(pad "30" smd rect
			(at -3.25247 -3.5941 180)
			(size 0.3048 1.397)
			(layers "B.Cu" "B.Mask" "B.Paste")
			(net "CLK_100M_CLKBUFF_PCIE_R_DP")
		)
		(pad "31" smd rect
			(at -2.75209 -3.5941 180)
			(size 0.3048 1.397)
			(layers "B.Cu" "B.Mask" "B.Paste")
			(net "P3V3_VDD_CLKBUFF")
		)
		(pad "32" smd rect
			(at -2.25171 -3.5941 180)
			(size 0.3048 1.397)
			(layers "B.Cu" "B.Mask" "B.Paste")
			(net "GND")
		)
		(pad "33" smd rect
			(at -1.75133 -3.5941 180)
			(size 0.3048 1.397)
			(layers "B.Cu" "B.Mask" "B.Paste")
			(net "Net_145")
		)
		(pad "34" smd rect
			(at -1.25095 -3.5941 180)
			(size 0.3048 1.397)
			(layers "B.Cu" "B.Mask" "B.Paste")
			(net "Net_146")
		)
		(pad "35" smd rect
			(at -0.75057 -3.5941 180)
			(size 0.3048 1.397)
			(layers "B.Cu" "B.Mask" "B.Paste")
			(net "CLKBUFF_OE5#")
		)
		(pad "36" smd rect
			(at -0.25019 -3.5941 180)
			(size 0.3048 1.397)
			(layers "B.Cu" "B.Mask" "B.Paste")
			(net "CLKBUFF_OE6#")
		)
		(pad "37" smd rect
			(at 0.25019 -3.5941 180)
			(size 0.3048 1.397)
			(layers "B.Cu" "B.Mask" "B.Paste")
			(net "Net_147")
		)
		(pad "38" smd rect
			(at 0.75057 -3.5941 180)
			(size 0.3048 1.397)
			(layers "B.Cu" "B.Mask" "B.Paste")
			(net "Net_148")
		)
		(pad "39" smd rect
			(at 1.25095 -3.5941 180)
			(size 0.3048 1.397)
			(layers "B.Cu" "B.Mask" "B.Paste")
			(net "P3V3_VDD_CLKBUFF")
		)
		(pad "40" smd rect
			(at 1.75133 -3.5941 180)
			(size 0.3048 1.397)
			(layers "B.Cu" "B.Mask" "B.Paste")
			(net "CLK_GEN_PG")
		)
		(pad "41" smd rect
			(at 2.25171 -3.5941 180)
			(size 0.3048 1.397)
			(layers "B.Cu" "B.Mask" "B.Paste")
			(net "Net_149")
		)
		(pad "42" smd rect
			(at 2.75209 -3.5941 180)
			(size 0.3048 1.397)
			(layers "B.Cu" "B.Mask" "B.Paste")
			(net "Net_150")
		)
		(pad "43" smd rect
			(at 3.25247 -3.5941 180)
			(size 0.3048 1.397)
			(layers "B.Cu" "B.Mask" "B.Paste")
			(net "CLKBUFF_OE4#")
		)
		(pad "44" smd rect
			(at 3.75285 -3.5941 180)
			(size 0.3048 1.397)
			(layers "B.Cu" "B.Mask" "B.Paste")
			(net "CLKBUFF_OE7#")
		)
		(pad "45" smd rect
			(at 4.25323 -3.5941 180)
			(size 0.3048 1.397)
			(layers "B.Cu" "B.Mask" "B.Paste")
			(net "Net_151")
		)
		(pad "46" smd rect
			(at 4.75361 -3.5941 180)
			(size 0.3048 1.397)
			(layers "B.Cu" "B.Mask" "B.Paste")
			(net "CLKBUFF_IREF")
		)
		(pad "47" smd rect
			(at 5.25399 -3.5941 180)
			(size 0.3048 1.397)
			(layers "B.Cu" "B.Mask" "B.Paste")
			(net "GND")
		)
		(pad "48" smd rect
			(at 5.75437 -3.5941 180)
			(size 0.3048 1.397)
			(layers "B.Cu" "B.Mask" "B.Paste")
			(net "P3V3_VDDA_CLKBUFF")
		)
	)
	(footprint ""
		(layer "B.Cu")
		(at 153.924 -59.309)
		(property "Reference" "C105"
			(at 0 0 0)
			(layer "B.SilkS")
			(hide yes)
			(effects
				(font
					(size 1.27 1.27)
				)
				(justify mirror)
			)
		)
		(property "Value" "SC10U6D3V3MX-GP"
			(at 0.0254 -2.0193 0)
			(unlocked yes)
			(layer "B.Fab")
			(hide yes)
			(effects
				(font
					(size 1.016 1.016)
					(thickness 0.1524)
				)
				(justify mirror)
			)
		)
		(property "Device Type" "C603H38"
			(at 0.0254 -3.5433 0)
			(unlocked yes)
			(layer "B.Fab")
			(hide yes)
			(effects
				(font
					(size 1.016 1.016)
					(thickness 0.1524)
				)
				(justify mirror)
			)
		)
		(duplicate_pad_numbers_are_jumpers no)
		(fp_line
			(start 0.4064 0)
			(end -0.4064 0)
			(stroke
				(width 0.2286)
				(type default)
			)
			(layer "B.SilkS")
		)
		(fp_rect
			(start 0.635 1.1811)
			(end -0.635 -1.1811)
			(stroke
				(width 0)
				(type default)
			)
			(fill no)
			(layer "B.CrtYd")
		)
		(fp_rect
			(start 0.635 1.1811)
			(end -0.635 -1.1811)
			(stroke
				(width 0)
				(type default)
			)
			(fill no)
			(layer "B.Fab")
		)
		(pad "1" smd custom
			(at 0 -0.6604 180)
			(size 0.19685 0.19685)
			(layers "B.Cu" "B.Mask" "B.Paste")
			(net "PV_VDDR")
			(options
				(clearance outline)
				(anchor circle)
			)
			(primitives
				(gr_poly
					(pts
						(arc
							(start 0.508 0.2921)
							(mid 0.478242 0.363942)
							(end 0.4064 0.3937)
						)
						(arc
							(start -0.4064 0.3937)
							(mid -0.478242 0.363942)
							(end -0.508 0.2921)
						)
						(arc
							(start -0.508 -0.2921)
							(mid -0.478242 -0.363942)
							(end -0.4064 -0.3937)
						)
						(arc
							(start 0.4064 -0.3937)
							(mid 0.478242 -0.363942)
							(end 0.508 -0.2921)
						)
					)
					(width 0)
					(fill yes)
				)
			)
		)
		(pad "2" smd custom
			(at 0 0.6604 180)
			(size 0.19685 0.19685)
			(layers "B.Cu" "B.Mask" "B.Paste")
			(net "GND")
			(options
				(clearance outline)
				(anchor circle)
			)
			(primitives
				(gr_poly
					(pts
						(arc
							(start 0.508 0.2921)
							(mid 0.478242 0.363942)
							(end 0.4064 0.3937)
						)
						(arc
							(start -0.4064 0.3937)
							(mid -0.478242 0.363942)
							(end -0.508 0.2921)
						)
						(arc
							(start -0.508 -0.2921)
							(mid -0.478242 -0.363942)
							(end -0.4064 -0.3937)
						)
						(arc
							(start 0.4064 -0.3937)
							(mid 0.478242 -0.363942)
							(end 0.508 -0.2921)
						)
					)
					(width 0)
					(fill yes)
				)
			)
		)
	)
	(footprint ""
		(layer "B.Cu")
		(at 78.486 -22.4282 -90)
		(property "Reference" "PC195"
			(at 0 0 90)
			(layer "B.SilkS")
			(hide yes)
			(effects
				(font
					(size 1.27 1.27)
				)
				(justify mirror)
			)
		)
		(property "Value" "SCD1U16V2KX-3GP"
			(at -1.1811 -2.7051 270)
			(unlocked yes)
			(layer "B.Fab")
			(hide yes)
			(effects
				(font
					(size 1.016 1.016)
					(thickness 0.1524)
				)
				(justify mirror)
			)
		)
		(property "Device Type" "C402H22"
			(at -1.1811 -4.2291 270)
			(unlocked yes)
			(layer "B.Fab")
			(hide yes)
			(effects
				(font
					(size 1.016 1.016)
					(thickness 0.1524)
				)
				(justify mirror)
			)
		)
		(duplicate_pad_numbers_are_jumpers no)
		(fp_rect
			(start 0.381 0.7366)
			(end -0.381 -0.7366)
			(stroke
				(width 0)
				(type default)
			)
			(fill no)
			(layer "B.CrtYd")
		)
		(fp_rect
			(start 0.381 0.7366)
			(end -0.381 -0.7366)
			(stroke
				(width 0)
				(type default)
			)
			(fill no)
			(layer "B.Fab")
		)
		(pad "1" smd custom
			(at 0 -0.4572 90)
			(size 0.1143 0.1143)
			(layers "B.Cu" "B.Mask" "B.Paste")
			(net "TPS74801_1V35_BIAS")
			(options
				(clearance outline)
				(anchor circle)
			)
			(primitives
				(gr_poly
					(pts
						(arc
							(start -0.254 0.1778)
							(mid -0.239121 0.213721)
							(end -0.2032 0.2286)
						)
						(arc
							(start 0.2032 0.2286)
							(mid 0.239121 0.213721)
							(end 0.254 0.1778)
						)
						(arc
							(start 0.254 -0.1778)
							(mid 0.239121 -0.213721)
							(end 0.2032 -0.2286)
						)
						(arc
							(start -0.2032 -0.2286)
							(mid -0.239121 -0.213721)
							(end -0.254 -0.1778)
						)
					)
					(width 0)
					(fill yes)
				)
			)
		)
		(pad "2" smd custom
			(at 0 0.4572 90)
			(size 0.1143 0.1143)
			(layers "B.Cu" "B.Mask" "B.Paste")
			(net "GND")
			(options
				(clearance outline)
				(anchor circle)
			)
			(primitives
				(gr_poly
					(pts
						(arc
							(start -0.254 0.1778)
							(mid -0.239121 0.213721)
							(end -0.2032 0.2286)
						)
						(arc
							(start 0.2032 0.2286)
							(mid 0.239121 0.213721)
							(end 0.254 0.1778)
						)
						(arc
							(start 0.254 -0.1778)
							(mid 0.239121 -0.213721)
							(end 0.2032 -0.2286)
						)
						(arc
							(start -0.2032 -0.2286)
							(mid -0.239121 -0.213721)
							(end -0.254 -0.1778)
						)
					)
					(width 0)
					(fill yes)
				)
			)
		)
	)
	(footprint ""
		(layer "B.Cu")
		(at 134.366 -44.704 -90)
		(property "Reference" "C149"
			(at 0 0 90)
			(layer "B.SilkS")
			(hide yes)
			(effects
				(font
					(size 1.27 1.27)
				)
				(justify mirror)
			)
		)
		(property "Value" "SCD1U10V2KX-5GP"
			(at -1.1811 -2.7051 270)
			(unlocked yes)
			(layer "B.Fab")
			(hide yes)
			(effects
				(font
					(size 1.016 1.016)
					(thickness 0.1524)
				)
				(justify mirror)
			)
		)
		(property "Device Type" "C402H22"
			(at -1.1811 -4.2291 270)
			(unlocked yes)
			(layer "B.Fab")
			(hide yes)
			(effects
				(font
					(size 1.016 1.016)
					(thickness 0.1524)
				)
				(justify mirror)
			)
		)
		(duplicate_pad_numbers_are_jumpers no)
		(fp_rect
			(start 0.381 0.7366)
			(end -0.381 -0.7366)
			(stroke
				(width 0)
				(type default)
			)
			(fill no)
			(layer "B.CrtYd")
		)
		(fp_rect
			(start 0.381 0.7366)
			(end -0.381 -0.7366)
			(stroke
				(width 0)
				(type default)
			)
			(fill no)
			(layer "B.Fab")
		)
		(pad "1" smd custom
			(at 0 -0.4572 90)
			(size 0.1143 0.1143)
			(layers "B.Cu" "B.Mask" "B.Paste")
			(net "P2V5_STBY")
			(options
				(clearance outline)
				(anchor circle)
			)
			(primitives
				(gr_poly
					(pts
						(arc
							(start -0.254 0.1778)
							(mid -0.239121 0.213721)
							(end -0.2032 0.2286)
						)
						(arc
							(start 0.2032 0.2286)
							(mid 0.239121 0.213721)
							(end 0.254 0.1778)
						)
						(arc
							(start 0.254 -0.1778)
							(mid 0.239121 -0.213721)
							(end 0.2032 -0.2286)
						)
						(arc
							(start -0.2032 -0.2286)
							(mid -0.239121 -0.213721)
							(end -0.254 -0.1778)
						)
					)
					(width 0)
					(fill yes)
				)
			)
		)
		(pad "2" smd custom
			(at 0 0.4572 90)
			(size 0.1143 0.1143)
			(layers "B.Cu" "B.Mask" "B.Paste")
			(net "GND")
			(options
				(clearance outline)
				(anchor circle)
			)
			(primitives
				(gr_poly
					(pts
						(arc
							(start -0.254 0.1778)
							(mid -0.239121 0.213721)
							(end -0.2032 0.2286)
						)
						(arc
							(start 0.2032 0.2286)
							(mid 0.239121 0.213721)
							(end 0.254 0.1778)
						)
						(arc
							(start 0.254 -0.1778)
							(mid 0.239121 -0.213721)
							(end 0.2032 -0.2286)
						)
						(arc
							(start -0.2032 -0.2286)
							(mid -0.239121 -0.213721)
							(end -0.254 -0.1778)
						)
					)
					(width 0)
					(fill yes)
				)
			)
		)
	)
	(footprint ""
		(layer "B.Cu")
		(at 22.3012 -54.229 180)
		(property "Reference" "PR74"
			(at 0 0 0)
			(layer "B.SilkS")
			(hide yes)
			(effects
				(font
					(size 1.27 1.27)
				)
				(justify mirror)
			)
		)
		(property "Value" "0R2J-2-GP"
			(at -1.7907 -1.1176 180)
			(unlocked yes)
			(layer "B.Fab")
			(hide yes)
			(effects
				(font
					(size 1.016 1.016)
					(thickness 0.1524)
				)
				(justify mirror)
			)
		)
		(property "Device Type" "R402H16"
			(at -1.7907 -2.6416 180)
			(unlocked yes)
			(layer "B.Fab")
			(hide yes)
			(effects
				(font
					(size 1.016 1.016)
					(thickness 0.1524)
				)
				(justify mirror)
			)
		)
		(duplicate_pad_numbers_are_jumpers no)
		(fp_rect
			(start 0.381 0.8382)
			(end -0.381 -0.8382)
			(stroke
				(width 0)
				(type default)
			)
			(fill no)
			(layer "B.CrtYd")
		)
		(fp_rect
			(start 0.381 0.8382)
			(end -0.381 -0.8382)
			(stroke
				(width 0)
				(type default)
			)
			(fill no)
			(layer "B.Fab")
		)
		(pad "1" smd custom
			(at 0 -0.4318)
			(size 0.127 0.127)
			(layers "B.Cu" "B.Mask" "B.Paste")
			(net "PVCCP_ISEN2")
			(options
				(clearance outline)
				(anchor circle)
			)
			(primitives
				(gr_poly
					(pts
						(arc
							(start -0.2032 0.2794)
							(mid -0.239121 0.264521)
							(end -0.254 0.2286)
						)
						(arc
							(start -0.254 -0.2286)
							(mid -0.239121 -0.264521)
							(end -0.2032 -0.2794)
						)
						(arc
							(start 0.2032 -0.2794)
							(mid 0.239121 -0.264521)
							(end 0.254 -0.2286)
						)
						(arc
							(start 0.254 0.2286)
							(mid 0.239121 0.264521)
							(end 0.2032 0.2794)
						)
					)
					(width 0)
					(fill yes)
				)
			)
		)
		(pad "2" smd custom
			(at 0 0.4318)
			(size 0.127 0.127)
			(layers "B.Cu" "B.Mask" "B.Paste")
			(net "VR_PVCCP_PVNN_VDD")
			(options
				(clearance outline)
				(anchor circle)
			)
			(primitives
				(gr_poly
					(pts
						(arc
							(start -0.2032 0.2794)
							(mid -0.239121 0.264521)
							(end -0.254 0.2286)
						)
						(arc
							(start -0.254 -0.2286)
							(mid -0.239121 -0.264521)
							(end -0.2032 -0.2794)
						)
						(arc
							(start 0.2032 -0.2794)
							(mid 0.239121 -0.264521)
							(end 0.254 -0.2286)
						)
						(arc
							(start 0.254 0.2286)
							(mid 0.239121 0.264521)
							(end 0.2032 0.2794)
						)
					)
					(width 0)
					(fill yes)
				)
			)
		)
	)
	(footprint ""
		(layer "B.Cu")
		(at 91.845384 -51.755802 -90)
		(property "Reference" "R278"
			(at 0 0 90)
			(layer "B.SilkS")
			(hide yes)
			(effects
				(font
					(size 1.27 1.27)
				)
				(justify mirror)
			)
		)
		(property "Value" "100R3F-1-GP"
			(at 0.0254 -2.5146 270)
			(unlocked yes)
			(layer "B.Fab")
			(hide yes)
			(effects
				(font
					(size 1.016 1.016)
					(thickness 0.1524)
				)
				(justify mirror)
			)
		)
		(property "Device Type" "R603H22"
			(at 0.0254 -4.0386 270)
			(unlocked yes)
			(layer "B.Fab")
			(hide yes)
			(effects
				(font
					(size 1.016 1.016)
					(thickness 0.1524)
				)
				(justify mirror)
			)
		)
		(duplicate_pad_numbers_are_jumpers no)
		(fp_line
			(start -0.4318 0)
			(end -0.2032 0)
			(stroke
				(width 0.2032)
				(type default)
			)
			(layer "B.SilkS")
		)
		(fp_line
			(start 0.2032 0)
			(end 0.4191 0)
			(stroke
				(width 0.2032)
				(type default)
			)
			(layer "B.SilkS")
		)
		(fp_rect
			(start 0.635 1.1811)
			(end -0.635 -1.1811)
			(stroke
				(width 0)
				(type default)
			)
			(fill no)
			(layer "B.CrtYd")
		)
		(fp_rect
			(start 0.635 1.1811)
			(end -0.635 -1.1811)
			(stroke
				(width 0)
				(type default)
			)
			(fill no)
			(layer "B.Fab")
		)
		(pad "1" smd custom
			(at 0 -0.6604 90)
			(size 0.19685 0.19685)
			(layers "B.Cu" "B.Mask" "B.Paste")
			(net "PCIE_OBS_P")
			(options
				(clearance outline)
				(anchor circle)
			)
			(primitives
				(gr_poly
					(pts
						(arc
							(start 0.508 0.2921)
							(mid 0.478242 0.363942)
							(end 0.4064 0.3937)
						)
						(arc
							(start -0.4064 0.3937)
							(mid -0.478242 0.363942)
							(end -0.508 0.2921)
						)
						(arc
							(start -0.508 -0.2921)
							(mid -0.478242 -0.363942)
							(end -0.4064 -0.3937)
						)
						(arc
							(start 0.4064 -0.3937)
							(mid 0.478242 -0.363942)
							(end 0.508 -0.2921)
						)
					)
					(width 0)
					(fill yes)
				)
			)
		)
		(pad "2" smd custom
			(at 0 0.6604 90)
			(size 0.19685 0.19685)
			(layers "B.Cu" "B.Mask" "B.Paste")
			(net "PCIE_OBS_N")
			(options
				(clearance outline)
				(anchor circle)
			)
			(primitives
				(gr_poly
					(pts
						(arc
							(start 0.508 0.2921)
							(mid 0.478242 0.363942)
							(end 0.4064 0.3937)
						)
						(arc
							(start -0.4064 0.3937)
							(mid -0.478242 0.363942)
							(end -0.508 0.2921)
						)
						(arc
							(start -0.508 -0.2921)
							(mid -0.478242 -0.363942)
							(end -0.4064 -0.3937)
						)
						(arc
							(start 0.4064 -0.3937)
							(mid 0.478242 -0.363942)
							(end 0.508 -0.2921)
						)
					)
					(width 0)
					(fill yes)
				)
			)
		)
	)
	(footprint ""
		(layer "B.Cu")
		(at 69.1388 -34.3154 -90)
		(property "Reference" "U45"
			(at 0 0 90)
			(layer "B.SilkS")
			(hide yes)
			(effects
				(font
					(size 1.27 1.27)
				)
				(justify mirror)
			)
		)
		(property "Value" "SNLVC1G17DCKR-GP"
			(at 0 -8.0772 270)
			(unlocked yes)
			(layer "B.Fab")
			(hide yes)
			(effects
				(font
					(size 1.016 1.016)
					(thickness 0.1524)
				)
				(justify mirror)
			)
		)
		(property "Device Type" "SC70-5H44"
			(at 0 -9.6012 270)
			(unlocked yes)
			(layer "B.Fab")
			(hide yes)
			(effects
				(font
					(size 1.016 1.016)
					(thickness 0.1524)
				)
				(justify mirror)
			)
		)
		(duplicate_pad_numbers_are_jumpers no)
		(fp_line
			(start -1.0033 0.3302)
			(end 1.0033 0.3302)
			(stroke
				(width 0.1524)
				(type default)
			)
			(layer "B.SilkS")
		)
		(fp_line
			(start 1.0033 0.3302)
			(end 1.0033 -0.3302)
			(stroke
				(width 0.1524)
				(type default)
			)
			(layer "B.SilkS")
		)
		(fp_line
			(start -1.0033 -0.3302)
			(end -1.0033 0.3302)
			(stroke
				(width 0.1524)
				(type default)
			)
			(layer "B.SilkS")
		)
		(fp_line
			(start 1.0033 -0.3302)
			(end -1.0033 -0.3302)
			(stroke
				(width 0.1524)
				(type default)
			)
			(layer "B.SilkS")
		)
		(fp_poly
			(pts
				(xy 1.0033 1.4859) (xy 1.0033 0.8001) (xy 1.1811 0.8001) (xy 1.1811 -0.8001) (xy 1.0033 -0.8001)
				(xy 1.0033 -1.4859) (xy -1.0033 -1.4859) (xy -1.0033 -0.8001) (xy -1.1811 -0.8001) (xy -1.1811 0.8001)
				(xy -1.0033 0.8001) (xy -1.0033 1.4859) (xy -0.2921 1.4859) (xy -0.2921 0.8001) (xy 0.2921 0.8001)
				(xy 0.2921 1.4859)
			)
			(stroke
				(width 0)
				(type default)
			)
			(fill no)
			(layer "B.CrtYd")
		)
		(fp_poly
			(pts
				(xy 1.0033 1.4859) (xy 1.0033 0.8001) (xy 1.1811 0.8001) (xy 1.1811 -0.8001) (xy 1.0033 -0.8001)
				(xy 1.0033 -1.4859) (xy -1.0033 -1.4859) (xy -1.0033 -0.8001) (xy -1.1811 -0.8001) (xy -1.1811 0.8001)
				(xy -1.0033 0.8001) (xy -1.0033 1.4859) (xy -0.2921 1.4859) (xy -0.2921 0.8001) (xy 0.2921 0.8001)
				(xy 0.2921 1.4859)
			)
			(stroke
				(width 0)
				(type default)
			)
			(fill no)
			(layer "B.Fab")
		)
		(pad "1" smd rect
			(at -0.65024 -0.93472 90)
			(size 0.3556 0.762)
			(layers "B.Cu" "B.Mask" "B.Paste")
			(net "Net_68")
		)
		(pad "2" smd rect
			(at 0 -0.93472 90)
			(size 0.3556 0.762)
			(layers "B.Cu" "B.Mask" "B.Paste")
			(net "SRTCRST_BUF_IN#")
		)
		(pad "3" smd rect
			(at 0.65024 -0.93472 90)
			(size 0.3556 0.762)
			(layers "B.Cu" "B.Mask" "B.Paste")
			(net "GND")
		)
		(pad "4" smd rect
			(at 0.65024 0.93472 90)
			(size 0.3556 0.762)
			(layers "B.Cu" "B.Mask" "B.Paste")
			(net "SRTCRST#")
		)
		(pad "5" smd rect
			(at -0.65024 0.93472 90)
			(size 0.3556 0.762)
			(layers "B.Cu" "B.Mask" "B.Paste")
			(net "P3V3_STBY")
		)
	)
	(footprint ""
		(layer "B.Cu")
		(at 91.6813 -34.2138 -90)
		(property "Reference" "C213"
			(at 0 0 90)
			(layer "B.SilkS")
			(hide yes)
			(effects
				(font
					(size 1.27 1.27)
				)
				(justify mirror)
			)
		)
		(property "Value" "SC1U10V2KX-1GP"
			(at -1.1811 -2.7051 270)
			(unlocked yes)
			(layer "B.Fab")
			(hide yes)
			(effects
				(font
					(size 1.016 1.016)
					(thickness 0.1524)
				)
				(justify mirror)
			)
		)
		(property "Device Type" "C402H22"
			(at -1.1811 -4.2291 270)
			(unlocked yes)
			(layer "B.Fab")
			(hide yes)
			(effects
				(font
					(size 1.016 1.016)
					(thickness 0.1524)
				)
				(justify mirror)
			)
		)
		(duplicate_pad_numbers_are_jumpers no)
		(fp_rect
			(start 0.381 0.7366)
			(end -0.381 -0.7366)
			(stroke
				(width 0)
				(type default)
			)
			(fill no)
			(layer "B.CrtYd")
		)
		(fp_rect
			(start 0.381 0.7366)
			(end -0.381 -0.7366)
			(stroke
				(width 0)
				(type default)
			)
			(fill no)
			(layer "B.Fab")
		)
		(pad "1" smd custom
			(at 0 -0.4572 90)
			(size 0.1143 0.1143)
			(layers "B.Cu" "B.Mask" "B.Paste")
			(net "P1V0_STBY")
			(options
				(clearance outline)
				(anchor circle)
			)
			(primitives
				(gr_poly
					(pts
						(arc
							(start -0.254 0.1778)
							(mid -0.239121 0.213721)
							(end -0.2032 0.2286)
						)
						(arc
							(start 0.2032 0.2286)
							(mid 0.239121 0.213721)
							(end 0.254 0.1778)
						)
						(arc
							(start 0.254 -0.1778)
							(mid 0.239121 -0.213721)
							(end 0.2032 -0.2286)
						)
						(arc
							(start -0.2032 -0.2286)
							(mid -0.239121 -0.213721)
							(end -0.254 -0.1778)
						)
					)
					(width 0)
					(fill yes)
				)
			)
		)
		(pad "2" smd custom
			(at 0 0.4572 90)
			(size 0.1143 0.1143)
			(layers "B.Cu" "B.Mask" "B.Paste")
			(net "GND")
			(options
				(clearance outline)
				(anchor circle)
			)
			(primitives
				(gr_poly
					(pts
						(arc
							(start -0.254 0.1778)
							(mid -0.239121 0.213721)
							(end -0.2032 0.2286)
						)
						(arc
							(start 0.2032 0.2286)
							(mid 0.239121 0.213721)
							(end 0.254 0.1778)
						)
						(arc
							(start 0.254 -0.1778)
							(mid 0.239121 -0.213721)
							(end 0.2032 -0.2286)
						)
						(arc
							(start -0.2032 -0.2286)
							(mid -0.239121 -0.213721)
							(end -0.254 -0.1778)
						)
					)
					(width 0)
					(fill yes)
				)
			)
		)
	)
	(footprint ""
		(layer "B.Cu")
		(at 89.662 -36.068)
		(property "Reference" "C121"
			(at 0 0 0)
			(layer "B.SilkS")
			(hide yes)
			(effects
				(font
					(size 1.27 1.27)
				)
				(justify mirror)
			)
		)
		(property "Value" "SCD1U16V2KX-3GP"
			(at -1.1811 -2.7051 0)
			(unlocked yes)
			(layer "B.Fab")
			(hide yes)
			(effects
				(font
					(size 1.016 1.016)
					(thickness 0.1524)
				)
				(justify mirror)
			)
		)
		(property "Device Type" "C402H22"
			(at -1.1811 -4.2291 0)
			(unlocked yes)
			(layer "B.Fab")
			(hide yes)
			(effects
				(font
					(size 1.016 1.016)
					(thickness 0.1524)
				)
				(justify mirror)
			)
		)
		(duplicate_pad_numbers_are_jumpers no)
		(fp_rect
			(start 0.381 0.7366)
			(end -0.381 -0.7366)
			(stroke
				(width 0)
				(type default)
			)
			(fill no)
			(layer "B.CrtYd")
		)
		(fp_rect
			(start 0.381 0.7366)
			(end -0.381 -0.7366)
			(stroke
				(width 0)
				(type default)
			)
			(fill no)
			(layer "B.Fab")
		)
		(pad "1" smd custom
			(at 0 -0.4572 180)
			(size 0.1143 0.1143)
			(layers "B.Cu" "B.Mask" "B.Paste")
			(net "P3V3_CPU")
			(options
				(clearance outline)
				(anchor circle)
			)
			(primitives
				(gr_poly
					(pts
						(arc
							(start -0.254 0.1778)
							(mid -0.239121 0.213721)
							(end -0.2032 0.2286)
						)
						(arc
							(start 0.2032 0.2286)
							(mid 0.239121 0.213721)
							(end 0.254 0.1778)
						)
						(arc
							(start 0.254 -0.1778)
							(mid 0.239121 -0.213721)
							(end 0.2032 -0.2286)
						)
						(arc
							(start -0.2032 -0.2286)
							(mid -0.239121 -0.213721)
							(end -0.254 -0.1778)
						)
					)
					(width 0)
					(fill yes)
				)
			)
		)
		(pad "2" smd custom
			(at 0 0.4572 180)
			(size 0.1143 0.1143)
			(layers "B.Cu" "B.Mask" "B.Paste")
			(net "GND")
			(options
				(clearance outline)
				(anchor circle)
			)
			(primitives
				(gr_poly
					(pts
						(arc
							(start -0.254 0.1778)
							(mid -0.239121 0.213721)
							(end -0.2032 0.2286)
						)
						(arc
							(start 0.2032 0.2286)
							(mid 0.239121 0.213721)
							(end 0.254 0.1778)
						)
						(arc
							(start 0.254 -0.1778)
							(mid 0.239121 -0.213721)
							(end 0.2032 -0.2286)
						)
						(arc
							(start -0.2032 -0.2286)
							(mid -0.239121 -0.213721)
							(end -0.254 -0.1778)
						)
					)
					(width 0)
					(fill yes)
				)
			)
		)
	)
	(footprint ""
		(layer "B.Cu")
		(at 103.759 -14.097 -90)
		(property "Reference" "R477"
			(at 0 0 90)
			(layer "B.SilkS")
			(hide yes)
			(effects
				(font
					(size 1.27 1.27)
				)
				(justify mirror)
			)
		)
		(property "Value" "10KR2F-2-GP"
			(at -1.7907 -1.1176 270)
			(unlocked yes)
			(layer "B.Fab")
			(hide yes)
			(effects
				(font
					(size 1.016 1.016)
					(thickness 0.1524)
				)
				(justify mirror)
			)
		)
		(property "Device Type" "R402H16"
			(at -1.7907 -2.6416 270)
			(unlocked yes)
			(layer "B.Fab")
			(hide yes)
			(effects
				(font
					(size 1.016 1.016)
					(thickness 0.1524)
				)
				(justify mirror)
			)
		)
		(duplicate_pad_numbers_are_jumpers no)
		(fp_rect
			(start 0.381 0.8382)
			(end -0.381 -0.8382)
			(stroke
				(width 0)
				(type default)
			)
			(fill no)
			(layer "B.CrtYd")
		)
		(fp_rect
			(start 0.381 0.8382)
			(end -0.381 -0.8382)
			(stroke
				(width 0)
				(type default)
			)
			(fill no)
			(layer "B.Fab")
		)
		(pad "1" smd custom
			(at 0 -0.4318 90)
			(size 0.127 0.127)
			(layers "B.Cu" "B.Mask" "B.Paste")
			(net "P3V3")
			(options
				(clearance outline)
				(anchor circle)
			)
			(primitives
				(gr_poly
					(pts
						(arc
							(start -0.2032 0.2794)
							(mid -0.239121 0.264521)
							(end -0.254 0.2286)
						)
						(arc
							(start -0.254 -0.2286)
							(mid -0.239121 -0.264521)
							(end -0.2032 -0.2794)
						)
						(arc
							(start 0.2032 -0.2794)
							(mid 0.239121 -0.264521)
							(end 0.254 -0.2286)
						)
						(arc
							(start 0.254 0.2286)
							(mid 0.239121 0.264521)
							(end 0.2032 0.2794)
						)
					)
					(width 0)
					(fill yes)
				)
			)
		)
		(pad "2" smd custom
			(at 0 0.4318 90)
			(size 0.127 0.127)
			(layers "B.Cu" "B.Mask" "B.Paste")
			(net "IRQ_CPU_IERR#")
			(options
				(clearance outline)
				(anchor circle)
			)
			(primitives
				(gr_poly
					(pts
						(arc
							(start -0.2032 0.2794)
							(mid -0.239121 0.264521)
							(end -0.254 0.2286)
						)
						(arc
							(start -0.254 -0.2286)
							(mid -0.239121 -0.264521)
							(end -0.2032 -0.2794)
						)
						(arc
							(start 0.2032 -0.2794)
							(mid 0.239121 -0.264521)
							(end 0.254 -0.2286)
						)
						(arc
							(start 0.254 0.2286)
							(mid 0.239121 0.264521)
							(end 0.2032 0.2794)
						)
					)
					(width 0)
					(fill yes)
				)
			)
		)
	)
	(footprint ""
		(layer "B.Cu")
		(at 94.3864 -32.5374 -90)
		(property "Reference" "R350"
			(at 0 0 90)
			(layer "B.SilkS")
			(hide yes)
			(effects
				(font
					(size 1.27 1.27)
				)
				(justify mirror)
			)
		)
		(property "Value" "162R2F-GP"
			(at -0.064008 -3.993896 270)
			(unlocked yes)
			(layer "B.Fab")
			(hide yes)
			(effects
				(font
					(size 1.016 1.016)
					(thickness 0.1524)
				)
				(justify mirror)
			)
		)
		(property "Device Type" "R402H16"
			(at -0.064008 -5.517896 270)
			(unlocked yes)
			(layer "B.Fab")
			(hide yes)
			(effects
				(font
					(size 1.016 1.016)
					(thickness 0.1524)
				)
				(justify mirror)
			)
		)
		(duplicate_pad_numbers_are_jumpers no)
		(fp_rect
			(start 0.381 0.8382)
			(end -0.381 -0.8382)
			(stroke
				(width 0)
				(type default)
			)
			(fill no)
			(layer "B.CrtYd")
		)
		(fp_rect
			(start 0.381 0.8382)
			(end -0.381 -0.8382)
			(stroke
				(width 0)
				(type default)
			)
			(fill no)
			(layer "B.Fab")
		)
		(pad "1" smd custom
			(at 0 -0.4318 90)
			(size 0.127 0.127)
			(layers "B.Cu" "B.Mask" "B.Paste")
			(net "M_B_ODTPU")
			(options
				(clearance outline)
				(anchor circle)
			)
			(primitives
				(gr_poly
					(pts
						(arc
							(start -0.2032 0.2794)
							(mid -0.239121 0.264521)
							(end -0.254 0.2286)
						)
						(arc
							(start -0.254 -0.2286)
							(mid -0.239121 -0.264521)
							(end -0.2032 -0.2794)
						)
						(arc
							(start 0.2032 -0.2794)
							(mid 0.239121 -0.264521)
							(end 0.254 -0.2286)
						)
						(arc
							(start 0.254 0.2286)
							(mid 0.239121 0.264521)
							(end 0.2032 0.2794)
						)
					)
					(width 0)
					(fill yes)
				)
			)
		)
		(pad "2" smd custom
			(at 0 0.4318 90)
			(size 0.127 0.127)
			(layers "B.Cu" "B.Mask" "B.Paste")
			(net "GND")
			(options
				(clearance outline)
				(anchor circle)
			)
			(primitives
				(gr_poly
					(pts
						(arc
							(start -0.2032 0.2794)
							(mid -0.239121 0.264521)
							(end -0.254 0.2286)
						)
						(arc
							(start -0.254 -0.2286)
							(mid -0.239121 -0.264521)
							(end -0.2032 -0.2794)
						)
						(arc
							(start 0.2032 -0.2794)
							(mid 0.239121 -0.264521)
							(end 0.254 -0.2286)
						)
						(arc
							(start 0.254 0.2286)
							(mid 0.239121 0.264521)
							(end 0.2032 0.2794)
						)
					)
					(width 0)
					(fill yes)
				)
			)
		)
	)
	(footprint ""
		(layer "B.Cu")
		(at 91.948 -64.643 -90)
		(property "Reference" "PC21"
			(at 0 0 90)
			(layer "B.SilkS")
			(hide yes)
			(effects
				(font
					(size 1.27 1.27)
				)
				(justify mirror)
			)
		)
		(property "Value" "SC10U6D3V5KX-4GP"
			(at 0.0762 -6.1214 270)
			(unlocked yes)
			(layer "B.Fab")
			(hide yes)
			(effects
				(font
					(size 1.016 1.016)
					(thickness 0.1524)
				)
				(justify mirror)
			)
		)
		(property "Device Type" "C805H58"
			(at 0.0762 -8.1534 270)
			(unlocked yes)
			(layer "B.Fab")
			(hide yes)
			(effects
				(font
					(size 1.016 1.016)
					(thickness 0.1524)
				)
				(justify mirror)
			)
		)
		(duplicate_pad_numbers_are_jumpers no)
		(fp_line
			(start -0.6096 0)
			(end 0.6096 0)
			(stroke
				(width 0.3048)
				(type default)
			)
			(layer "B.SilkS")
		)
		(fp_poly
			(pts
				(xy 0.9017 1.4351) (xy -0.9017 1.4351) (xy -0.9017 -1.4351) (xy 0.9017 -1.4351)
			)
			(stroke
				(width 0)
				(type default)
			)
			(fill no)
			(layer "B.CrtYd")
		)
		(fp_poly
			(pts
				(xy -0.9017 1.4351) (xy -0.9017 -1.4351) (xy 0.9017 -1.4351) (xy 0.9017 1.4351)
			)
			(stroke
				(width 0)
				(type default)
			)
			(fill no)
			(layer "B.Fab")
		)
		(pad "1" smd rect
			(at 0 -0.8382 90)
			(size 1.5494 0.9398)
			(layers "B.Cu" "B.Mask" "B.Paste")
			(net "P1V1")
		)
		(pad "2" smd rect
			(at 0 0.8382 90)
			(size 1.5494 0.9398)
			(layers "B.Cu" "B.Mask" "B.Paste")
			(net "GND")
		)
	)
	(footprint ""
		(layer "B.Cu")
		(at 65.4812 -20.8026)
		(property "Reference" "R504"
			(at 0 0 0)
			(layer "B.SilkS")
			(hide yes)
			(effects
				(font
					(size 1.27 1.27)
				)
				(justify mirror)
			)
		)
		(property "Value" "4K7R2F-GP"
			(at -1.7907 -1.1176 0)
			(unlocked yes)
			(layer "B.Fab")
			(hide yes)
			(effects
				(font
					(size 1.016 1.016)
					(thickness 0.1524)
				)
				(justify mirror)
			)
		)
		(property "Device Type" "R402H16"
			(at -1.7907 -2.6416 0)
			(unlocked yes)
			(layer "B.Fab")
			(hide yes)
			(effects
				(font
					(size 1.016 1.016)
					(thickness 0.1524)
				)
				(justify mirror)
			)
		)
		(duplicate_pad_numbers_are_jumpers no)
		(fp_rect
			(start 0.381 0.8382)
			(end -0.381 -0.8382)
			(stroke
				(width 0)
				(type default)
			)
			(fill no)
			(layer "B.CrtYd")
		)
		(fp_rect
			(start 0.381 0.8382)
			(end -0.381 -0.8382)
			(stroke
				(width 0)
				(type default)
			)
			(fill no)
			(layer "B.Fab")
		)
		(pad "1" smd custom
			(at 0 -0.4318 180)
			(size 0.127 0.127)
			(layers "B.Cu" "B.Mask" "B.Paste")
			(net "MSATA_ACT#")
			(options
				(clearance outline)
				(anchor circle)
			)
			(primitives
				(gr_poly
					(pts
						(arc
							(start -0.2032 0.2794)
							(mid -0.239121 0.264521)
							(end -0.254 0.2286)
						)
						(arc
							(start -0.254 -0.2286)
							(mid -0.239121 -0.264521)
							(end -0.2032 -0.2794)
						)
						(arc
							(start 0.2032 -0.2794)
							(mid 0.239121 -0.264521)
							(end 0.254 -0.2286)
						)
						(arc
							(start 0.254 0.2286)
							(mid 0.239121 0.264521)
							(end 0.2032 0.2794)
						)
					)
					(width 0)
					(fill yes)
				)
			)
		)
		(pad "2" smd custom
			(at 0 0.4318 180)
			(size 0.127 0.127)
			(layers "B.Cu" "B.Mask" "B.Paste")
			(net "GND")
			(options
				(clearance outline)
				(anchor circle)
			)
			(primitives
				(gr_poly
					(pts
						(arc
							(start -0.2032 0.2794)
							(mid -0.239121 0.264521)
							(end -0.254 0.2286)
						)
						(arc
							(start -0.254 -0.2286)
							(mid -0.239121 -0.264521)
							(end -0.2032 -0.2794)
						)
						(arc
							(start 0.2032 -0.2794)
							(mid 0.239121 -0.264521)
							(end 0.254 -0.2286)
						)
						(arc
							(start 0.254 0.2286)
							(mid 0.239121 0.264521)
							(end 0.2032 0.2794)
						)
					)
					(width 0)
					(fill yes)
				)
			)
		)
	)
	(footprint ""
		(layer "B.Cu")
		(at 190.119 -27.94)
		(property "Reference" "PR215"
			(at 0 0 0)
			(layer "B.SilkS")
			(hide yes)
			(effects
				(font
					(size 1.27 1.27)
				)
				(justify mirror)
			)
		)
		(property "Value" "2K61R2F-1-GP"
			(at -1.7907 -1.1176 0)
			(unlocked yes)
			(layer "B.Fab")
			(hide yes)
			(effects
				(font
					(size 1.016 1.016)
					(thickness 0.1524)
				)
				(justify mirror)
			)
		)
		(property "Device Type" "R402H16"
			(at -1.7907 -2.6416 0)
			(unlocked yes)
			(layer "B.Fab")
			(hide yes)
			(effects
				(font
					(size 1.016 1.016)
					(thickness 0.1524)
				)
				(justify mirror)
			)
		)
		(duplicate_pad_numbers_are_jumpers no)
		(fp_rect
			(start 0.381 0.8382)
			(end -0.381 -0.8382)
			(stroke
				(width 0)
				(type default)
			)
			(fill no)
			(layer "B.CrtYd")
		)
		(fp_rect
			(start 0.381 0.8382)
			(end -0.381 -0.8382)
			(stroke
				(width 0)
				(type default)
			)
			(fill no)
			(layer "B.Fab")
		)
		(pad "1" smd custom
			(at 0 -0.4318 180)
			(size 0.127 0.127)
			(layers "B.Cu" "B.Mask" "B.Paste")
			(net "VR_PVDDRA_ISUMP1")
			(options
				(clearance outline)
				(anchor circle)
			)
			(primitives
				(gr_poly
					(pts
						(arc
							(start -0.2032 0.2794)
							(mid -0.239121 0.264521)
							(end -0.254 0.2286)
						)
						(arc
							(start -0.254 -0.2286)
							(mid -0.239121 -0.264521)
							(end -0.2032 -0.2794)
						)
						(arc
							(start 0.2032 -0.2794)
							(mid 0.239121 -0.264521)
							(end 0.254 -0.2286)
						)
						(arc
							(start 0.254 0.2286)
							(mid 0.239121 0.264521)
							(end 0.2032 0.2794)
						)
					)
					(width 0)
					(fill yes)
				)
			)
		)
		(pad "2" smd custom
			(at 0 0.4318 180)
			(size 0.127 0.127)
			(layers "B.Cu" "B.Mask" "B.Paste")
			(net "VR_PVDDRA_ISUMP1_R")
			(options
				(clearance outline)
				(anchor circle)
			)
			(primitives
				(gr_poly
					(pts
						(arc
							(start -0.2032 0.2794)
							(mid -0.239121 0.264521)
							(end -0.254 0.2286)
						)
						(arc
							(start -0.254 -0.2286)
							(mid -0.239121 -0.264521)
							(end -0.2032 -0.2794)
						)
						(arc
							(start 0.2032 -0.2794)
							(mid 0.239121 -0.264521)
							(end 0.254 -0.2286)
						)
						(arc
							(start 0.254 0.2286)
							(mid 0.239121 0.264521)
							(end 0.2032 0.2794)
						)
					)
					(width 0)
					(fill yes)
				)
			)
		)
	)
	(footprint ""
		(layer "B.Cu")
		(at 101.092 -64.643)
		(property "Reference" "PC8"
			(at 0 0 0)
			(layer "B.SilkS")
			(hide yes)
			(effects
				(font
					(size 1.27 1.27)
				)
				(justify mirror)
			)
		)
		(property "Value" "SC1U10V2KX-1GP"
			(at -1.1811 -2.7051 0)
			(unlocked yes)
			(layer "B.Fab")
			(hide yes)
			(effects
				(font
					(size 1.016 1.016)
					(thickness 0.1524)
				)
				(justify mirror)
			)
		)
		(property "Device Type" "C402H22"
			(at -1.1811 -4.2291 0)
			(unlocked yes)
			(layer "B.Fab")
			(hide yes)
			(effects
				(font
					(size 1.016 1.016)
					(thickness 0.1524)
				)
				(justify mirror)
			)
		)
		(duplicate_pad_numbers_are_jumpers no)
		(fp_rect
			(start 0.381 0.7366)
			(end -0.381 -0.7366)
			(stroke
				(width 0)
				(type default)
			)
			(fill no)
			(layer "B.CrtYd")
		)
		(fp_rect
			(start 0.381 0.7366)
			(end -0.381 -0.7366)
			(stroke
				(width 0)
				(type default)
			)
			(fill no)
			(layer "B.Fab")
		)
		(pad "1" smd custom
			(at 0 -0.4572 180)
			(size 0.1143 0.1143)
			(layers "B.Cu" "B.Mask" "B.Paste")
			(net "AGND_P1V1")
			(options
				(clearance outline)
				(anchor circle)
			)
			(primitives
				(gr_poly
					(pts
						(arc
							(start -0.254 0.1778)
							(mid -0.239121 0.213721)
							(end -0.2032 0.2286)
						)
						(arc
							(start 0.2032 0.2286)
							(mid 0.239121 0.213721)
							(end 0.254 0.1778)
						)
						(arc
							(start 0.254 -0.1778)
							(mid 0.239121 -0.213721)
							(end 0.2032 -0.2286)
						)
						(arc
							(start -0.2032 -0.2286)
							(mid -0.239121 -0.213721)
							(end -0.254 -0.1778)
						)
					)
					(width 0)
					(fill yes)
				)
			)
		)
		(pad "2" smd custom
			(at 0 0.4572 180)
			(size 0.1143 0.1143)
			(layers "B.Cu" "B.Mask" "B.Paste")
			(net "VR_P1V1_AVIN")
			(options
				(clearance outline)
				(anchor circle)
			)
			(primitives
				(gr_poly
					(pts
						(arc
							(start -0.254 0.1778)
							(mid -0.239121 0.213721)
							(end -0.2032 0.2286)
						)
						(arc
							(start 0.2032 0.2286)
							(mid 0.239121 0.213721)
							(end 0.254 0.1778)
						)
						(arc
							(start 0.254 -0.1778)
							(mid 0.239121 -0.213721)
							(end 0.2032 -0.2286)
						)
						(arc
							(start -0.2032 -0.2286)
							(mid -0.239121 -0.213721)
							(end -0.254 -0.1778)
						)
					)
					(width 0)
					(fill yes)
				)
			)
		)
	)
	(footprint ""
		(layer "B.Cu")
		(at 81.026 -65.786)
		(property "Reference" "R289"
			(at 0 0 0)
			(layer "B.SilkS")
			(hide yes)
			(effects
				(font
					(size 1.27 1.27)
				)
				(justify mirror)
			)
		)
		(property "Value" "100R2F-L1-GP-U"
			(at -0.064008 -3.993896 0)
			(unlocked yes)
			(layer "B.Fab")
			(hide yes)
			(effects
				(font
					(size 1.016 1.016)
					(thickness 0.1524)
				)
				(justify mirror)
			)
		)
		(property "Device Type" "R402H14"
			(at -0.064008 -5.517896 0)
			(unlocked yes)
			(layer "B.Fab")
			(hide yes)
			(effects
				(font
					(size 1.016 1.016)
					(thickness 0.1524)
				)
				(justify mirror)
			)
		)
		(duplicate_pad_numbers_are_jumpers no)
		(fp_rect
			(start 0.381 0.8382)
			(end -0.381 -0.8382)
			(stroke
				(width 0)
				(type default)
			)
			(fill no)
			(layer "B.CrtYd")
		)
		(fp_rect
			(start 0.381 0.8382)
			(end -0.381 -0.8382)
			(stroke
				(width 0)
				(type default)
			)
			(fill no)
			(layer "B.Fab")
		)
		(pad "1" smd custom
			(at 0 -0.4318 180)
			(size 0.127 0.127)
			(layers "B.Cu" "B.Mask" "B.Paste")
			(net "P1V0")
			(options
				(clearance outline)
				(anchor circle)
			)
			(primitives
				(gr_poly
					(pts
						(arc
							(start -0.2032 0.2794)
							(mid -0.239121 0.264521)
							(end -0.254 0.2286)
						)
						(arc
							(start -0.254 -0.2286)
							(mid -0.239121 -0.264521)
							(end -0.2032 -0.2794)
						)
						(arc
							(start 0.2032 -0.2794)
							(mid 0.239121 -0.264521)
							(end 0.254 -0.2286)
						)
						(arc
							(start 0.254 0.2286)
							(mid 0.239121 0.264521)
							(end 0.2032 0.2794)
						)
					)
					(width 0)
					(fill yes)
				)
			)
		)
		(pad "2" smd custom
			(at 0 0.4318 180)
			(size 0.127 0.127)
			(layers "B.Cu" "B.Mask" "B.Paste")
			(net "SVID_CPU_DATA")
			(options
				(clearance outline)
				(anchor circle)
			)
			(primitives
				(gr_poly
					(pts
						(arc
							(start -0.2032 0.2794)
							(mid -0.239121 0.264521)
							(end -0.254 0.2286)
						)
						(arc
							(start -0.254 -0.2286)
							(mid -0.239121 -0.264521)
							(end -0.2032 -0.2794)
						)
						(arc
							(start 0.2032 -0.2794)
							(mid 0.239121 -0.264521)
							(end 0.254 -0.2286)
						)
						(arc
							(start 0.254 0.2286)
							(mid 0.239121 0.264521)
							(end 0.2032 0.2794)
						)
					)
					(width 0)
					(fill yes)
				)
			)
		)
	)
	(footprint ""
		(layer "B.Cu")
		(at 119.888 -65.151 180)
		(property "Reference" "R499"
			(at 0 0 0)
			(layer "B.SilkS")
			(hide yes)
			(effects
				(font
					(size 1.27 1.27)
				)
				(justify mirror)
			)
		)
		(property "Value" "4K7R2F-GP"
			(at -1.7907 -1.1176 180)
			(unlocked yes)
			(layer "B.Fab")
			(hide yes)
			(effects
				(font
					(size 1.016 1.016)
					(thickness 0.1524)
				)
				(justify mirror)
			)
		)
		(property "Device Type" "R402H16"
			(at -1.7907 -2.6416 180)
			(unlocked yes)
			(layer "B.Fab")
			(hide yes)
			(effects
				(font
					(size 1.016 1.016)
					(thickness 0.1524)
				)
				(justify mirror)
			)
		)
		(duplicate_pad_numbers_are_jumpers no)
		(fp_rect
			(start 0.381 0.8382)
			(end -0.381 -0.8382)
			(stroke
				(width 0)
				(type default)
			)
			(fill no)
			(layer "B.CrtYd")
		)
		(fp_rect
			(start 0.381 0.8382)
			(end -0.381 -0.8382)
			(stroke
				(width 0)
				(type default)
			)
			(fill no)
			(layer "B.Fab")
		)
		(pad "1" smd custom
			(at 0 -0.4318)
			(size 0.127 0.127)
			(layers "B.Cu" "B.Mask" "B.Paste")
			(net "P3V3_STBY")
			(options
				(clearance outline)
				(anchor circle)
			)
			(primitives
				(gr_poly
					(pts
						(arc
							(start -0.2032 0.2794)
							(mid -0.239121 0.264521)
							(end -0.254 0.2286)
						)
						(arc
							(start -0.254 -0.2286)
							(mid -0.239121 -0.264521)
							(end -0.2032 -0.2794)
						)
						(arc
							(start 0.2032 -0.2794)
							(mid 0.239121 -0.264521)
							(end 0.254 -0.2286)
						)
						(arc
							(start 0.254 0.2286)
							(mid 0.239121 0.264521)
							(end 0.2032 0.2794)
						)
					)
					(width 0)
					(fill yes)
				)
			)
		)
		(pad "2" smd custom
			(at 0 0.4318)
			(size 0.127 0.127)
			(layers "B.Cu" "B.Mask" "B.Paste")
			(net "SMB_HOST_LV_DATA")
			(options
				(clearance outline)
				(anchor circle)
			)
			(primitives
				(gr_poly
					(pts
						(arc
							(start -0.2032 0.2794)
							(mid -0.239121 0.264521)
							(end -0.254 0.2286)
						)
						(arc
							(start -0.254 -0.2286)
							(mid -0.239121 -0.264521)
							(end -0.2032 -0.2794)
						)
						(arc
							(start 0.2032 -0.2794)
							(mid 0.239121 -0.264521)
							(end 0.254 -0.2286)
						)
						(arc
							(start 0.254 0.2286)
							(mid 0.239121 0.264521)
							(end 0.2032 0.2794)
						)
					)
					(width 0)
					(fill yes)
				)
			)
		)
	)
	(footprint ""
		(layer "B.Cu")
		(at 27.305 -64.77 -90)
		(property "Reference" "R496"
			(at 0 0 90)
			(layer "B.SilkS")
			(hide yes)
			(effects
				(font
					(size 1.27 1.27)
				)
				(justify mirror)
			)
		)
		(property "Value" "10KR2F-2-GP"
			(at -1.7907 -1.1176 270)
			(unlocked yes)
			(layer "B.Fab")
			(hide yes)
			(effects
				(font
					(size 1.016 1.016)
					(thickness 0.1524)
				)
				(justify mirror)
			)
		)
		(property "Device Type" "R402H16"
			(at -1.7907 -2.6416 270)
			(unlocked yes)
			(layer "B.Fab")
			(hide yes)
			(effects
				(font
					(size 1.016 1.016)
					(thickness 0.1524)
				)
				(justify mirror)
			)
		)
		(duplicate_pad_numbers_are_jumpers no)
		(fp_rect
			(start 0.381 0.8382)
			(end -0.381 -0.8382)
			(stroke
				(width 0)
				(type default)
			)
			(fill no)
			(layer "B.CrtYd")
		)
		(fp_rect
			(start 0.381 0.8382)
			(end -0.381 -0.8382)
			(stroke
				(width 0)
				(type default)
			)
			(fill no)
			(layer "B.Fab")
		)
		(pad "1" smd custom
			(at 0 -0.4318 90)
			(size 0.127 0.127)
			(layers "B.Cu" "B.Mask" "B.Paste")
			(net "VCCP_5VBIAS")
			(options
				(clearance outline)
				(anchor circle)
			)
			(primitives
				(gr_poly
					(pts
						(arc
							(start -0.2032 0.2794)
							(mid -0.239121 0.264521)
							(end -0.254 0.2286)
						)
						(arc
							(start -0.254 -0.2286)
							(mid -0.239121 -0.264521)
							(end -0.2032 -0.2794)
						)
						(arc
							(start 0.2032 -0.2794)
							(mid 0.239121 -0.264521)
							(end 0.254 -0.2286)
						)
						(arc
							(start 0.254 0.2286)
							(mid 0.239121 0.264521)
							(end 0.2032 0.2794)
						)
					)
					(width 0)
					(fill yes)
				)
			)
		)
		(pad "2" smd custom
			(at 0 0.4318 90)
			(size 0.127 0.127)
			(layers "B.Cu" "B.Mask" "B.Paste")
			(net "GND")
			(options
				(clearance outline)
				(anchor circle)
			)
			(primitives
				(gr_poly
					(pts
						(arc
							(start -0.2032 0.2794)
							(mid -0.239121 0.264521)
							(end -0.254 0.2286)
						)
						(arc
							(start -0.254 -0.2286)
							(mid -0.239121 -0.264521)
							(end -0.2032 -0.2794)
						)
						(arc
							(start 0.2032 -0.2794)
							(mid 0.239121 -0.264521)
							(end 0.254 -0.2286)
						)
						(arc
							(start 0.254 0.2286)
							(mid 0.239121 0.264521)
							(end 0.2032 0.2794)
						)
					)
					(width 0)
					(fill yes)
				)
			)
		)
	)
	(footprint ""
		(layer "B.Cu")
		(at 94.361 -48.0314 180)
		(property "Reference" "C133"
			(at 0 0 0)
			(layer "B.SilkS")
			(hide yes)
			(effects
				(font
					(size 1.27 1.27)
				)
				(justify mirror)
			)
		)
		(property "Value" "SC1U10V2KX-1GP"
			(at -1.1811 -2.7051 180)
			(unlocked yes)
			(layer "B.Fab")
			(hide yes)
			(effects
				(font
					(size 1.016 1.016)
					(thickness 0.1524)
				)
				(justify mirror)
			)
		)
		(property "Device Type" "C402H22"
			(at -1.1811 -4.2291 180)
			(unlocked yes)
			(layer "B.Fab")
			(hide yes)
			(effects
				(font
					(size 1.016 1.016)
					(thickness 0.1524)
				)
				(justify mirror)
			)
		)
		(duplicate_pad_numbers_are_jumpers no)
		(fp_rect
			(start 0.381 0.7366)
			(end -0.381 -0.7366)
			(stroke
				(width 0)
				(type default)
			)
			(fill no)
			(layer "B.CrtYd")
		)
		(fp_rect
			(start 0.381 0.7366)
			(end -0.381 -0.7366)
			(stroke
				(width 0)
				(type default)
			)
			(fill no)
			(layer "B.Fab")
		)
		(pad "1" smd custom
			(at 0 -0.4572)
			(size 0.1143 0.1143)
			(layers "B.Cu" "B.Mask" "B.Paste")
			(net "P1V0")
			(options
				(clearance outline)
				(anchor circle)
			)
			(primitives
				(gr_poly
					(pts
						(arc
							(start -0.254 0.1778)
							(mid -0.239121 0.213721)
							(end -0.2032 0.2286)
						)
						(arc
							(start 0.2032 0.2286)
							(mid 0.239121 0.213721)
							(end 0.254 0.1778)
						)
						(arc
							(start 0.254 -0.1778)
							(mid 0.239121 -0.213721)
							(end 0.2032 -0.2286)
						)
						(arc
							(start -0.2032 -0.2286)
							(mid -0.239121 -0.213721)
							(end -0.254 -0.1778)
						)
					)
					(width 0)
					(fill yes)
				)
			)
		)
		(pad "2" smd custom
			(at 0 0.4572)
			(size 0.1143 0.1143)
			(layers "B.Cu" "B.Mask" "B.Paste")
			(net "GND")
			(options
				(clearance outline)
				(anchor circle)
			)
			(primitives
				(gr_poly
					(pts
						(arc
							(start -0.254 0.1778)
							(mid -0.239121 0.213721)
							(end -0.2032 0.2286)
						)
						(arc
							(start 0.2032 0.2286)
							(mid 0.239121 0.213721)
							(end 0.254 0.1778)
						)
						(arc
							(start 0.254 -0.1778)
							(mid 0.239121 -0.213721)
							(end 0.2032 -0.2286)
						)
						(arc
							(start -0.2032 -0.2286)
							(mid -0.239121 -0.213721)
							(end -0.254 -0.1778)
						)
					)
					(width 0)
					(fill yes)
				)
			)
		)
	)
	(footprint ""
		(layer "B.Cu")
		(at 100.584 -53.086 180)
		(property "Reference" "R261"
			(at 0 0 0)
			(layer "B.SilkS")
			(hide yes)
			(effects
				(font
					(size 1.27 1.27)
				)
				(justify mirror)
			)
		)
		(property "Value" "100KR2F-L1-GP"
			(at -0.064008 -3.993896 180)
			(unlocked yes)
			(layer "B.Fab")
			(hide yes)
			(effects
				(font
					(size 1.016 1.016)
					(thickness 0.1524)
				)
				(justify mirror)
			)
		)
		(property "Device Type" "R402H16"
			(at -0.064008 -5.517896 180)
			(unlocked yes)
			(layer "B.Fab")
			(hide yes)
			(effects
				(font
					(size 1.016 1.016)
					(thickness 0.1524)
				)
				(justify mirror)
			)
		)
		(duplicate_pad_numbers_are_jumpers no)
		(fp_rect
			(start 0.381 0.8382)
			(end -0.381 -0.8382)
			(stroke
				(width 0)
				(type default)
			)
			(fill no)
			(layer "B.CrtYd")
		)
		(fp_rect
			(start 0.381 0.8382)
			(end -0.381 -0.8382)
			(stroke
				(width 0)
				(type default)
			)
			(fill no)
			(layer "B.Fab")
		)
		(pad "1" smd custom
			(at 0 -0.4318)
			(size 0.127 0.127)
			(layers "B.Cu" "B.Mask" "B.Paste")
			(net "GND")
			(options
				(clearance outline)
				(anchor circle)
			)
			(primitives
				(gr_poly
					(pts
						(arc
							(start -0.2032 0.2794)
							(mid -0.239121 0.264521)
							(end -0.254 0.2286)
						)
						(arc
							(start -0.254 -0.2286)
							(mid -0.239121 -0.264521)
							(end -0.2032 -0.2794)
						)
						(arc
							(start 0.2032 -0.2794)
							(mid 0.239121 -0.264521)
							(end 0.254 -0.2286)
						)
						(arc
							(start 0.254 0.2286)
							(mid 0.239121 0.264521)
							(end 0.2032 0.2794)
						)
					)
					(width 0)
					(fill yes)
				)
			)
		)
		(pad "2" smd custom
			(at 0 0.4318)
			(size 0.127 0.127)
			(layers "B.Cu" "B.Mask" "B.Paste")
			(net "M_A_R_RESET#")
			(options
				(clearance outline)
				(anchor circle)
			)
			(primitives
				(gr_poly
					(pts
						(arc
							(start -0.2032 0.2794)
							(mid -0.239121 0.264521)
							(end -0.254 0.2286)
						)
						(arc
							(start -0.254 -0.2286)
							(mid -0.239121 -0.264521)
							(end -0.2032 -0.2794)
						)
						(arc
							(start 0.2032 -0.2794)
							(mid 0.239121 -0.264521)
							(end 0.254 -0.2286)
						)
						(arc
							(start 0.254 0.2286)
							(mid 0.239121 0.264521)
							(end 0.2032 0.2794)
						)
					)
					(width 0)
					(fill yes)
				)
			)
		)
	)
	(footprint ""
		(layer "B.Cu")
		(at 25.4 -15.494)
		(property "Reference" "TP50"
			(at 0 0 0)
			(layer "B.SilkS")
			(hide yes)
			(effects
				(font
					(size 1.27 1.27)
				)
				(justify mirror)
			)
		)
		(property "Value" "TPAD32-GP"
			(at 0 -3.166364 0)
			(unlocked yes)
			(layer "B.Fab")
			(hide yes)
			(effects
				(font
					(size 1.016 1.016)
					(thickness 0.1524)
				)
				(justify mirror)
			)
		)
		(property "Device Type" "TPAD32"
			(at 0 -4.690618 0)
			(unlocked yes)
			(layer "B.Fab")
			(hide yes)
			(effects
				(font
					(size 1.016 1.016)
					(thickness 0.1524)
				)
				(justify mirror)
			)
		)
		(duplicate_pad_numbers_are_jumpers no)
		(fp_poly
			(pts
				(arc
					(start 0.7112 0)
					(mid -0.7112 0)
					(end 0.7112 0)
				)
			)
			(stroke
				(width 0)
				(type default)
			)
			(fill no)
			(layer "B.CrtYd")
		)
		(fp_poly
			(pts
				(arc
					(start 0.7112 0)
					(mid -0.7112 0)
					(end 0.7112 0)
				)
			)
			(stroke
				(width 0)
				(type default)
			)
			(fill no)
			(layer "B.Fab")
		)
		(pad "1" smd circle
			(at 0 0 180)
			(size 0.8128 0.8128)
			(layers "B.Cu" "B.Mask" "B.Paste")
			(net "XDP_SOC_CPU_TCK")
		)
	)
	(footprint ""
		(layer "B.Cu")
		(at 30.226 -12.7)
		(property "Reference" "C270"
			(at 0 0 0)
			(layer "B.SilkS")
			(hide yes)
			(effects
				(font
					(size 1.27 1.27)
				)
				(justify mirror)
			)
		)
		(property "Value" "SCD1U16V2KX-3GP"
			(at -1.1811 -2.7051 0)
			(unlocked yes)
			(layer "B.Fab")
			(hide yes)
			(effects
				(font
					(size 1.016 1.016)
					(thickness 0.1524)
				)
				(justify mirror)
			)
		)
		(property "Device Type" "C402H22"
			(at -1.1811 -4.2291 0)
			(unlocked yes)
			(layer "B.Fab")
			(hide yes)
			(effects
				(font
					(size 1.016 1.016)
					(thickness 0.1524)
				)
				(justify mirror)
			)
		)
		(duplicate_pad_numbers_are_jumpers no)
		(fp_rect
			(start 0.381 0.7366)
			(end -0.381 -0.7366)
			(stroke
				(width 0)
				(type default)
			)
			(fill no)
			(layer "B.CrtYd")
		)
		(fp_rect
			(start 0.381 0.7366)
			(end -0.381 -0.7366)
			(stroke
				(width 0)
				(type default)
			)
			(fill no)
			(layer "B.Fab")
		)
		(pad "1" smd custom
			(at 0 -0.4572 180)
			(size 0.1143 0.1143)
			(layers "B.Cu" "B.Mask" "B.Paste")
			(net "P2E_CPU_ETH10G_C_TX_DP8")
			(options
				(clearance outline)
				(anchor circle)
			)
			(primitives
				(gr_poly
					(pts
						(arc
							(start -0.254 0.1778)
							(mid -0.239121 0.213721)
							(end -0.2032 0.2286)
						)
						(arc
							(start 0.2032 0.2286)
							(mid 0.239121 0.213721)
							(end 0.254 0.1778)
						)
						(arc
							(start 0.254 -0.1778)
							(mid 0.239121 -0.213721)
							(end 0.2032 -0.2286)
						)
						(arc
							(start -0.2032 -0.2286)
							(mid -0.239121 -0.213721)
							(end -0.254 -0.1778)
						)
					)
					(width 0)
					(fill yes)
				)
			)
		)
		(pad "2" smd custom
			(at 0 0.4572 180)
			(size 0.1143 0.1143)
			(layers "B.Cu" "B.Mask" "B.Paste")
			(net "P2E_CPU_ETH10G_TX_DP8")
			(options
				(clearance outline)
				(anchor circle)
			)
			(primitives
				(gr_poly
					(pts
						(arc
							(start -0.254 0.1778)
							(mid -0.239121 0.213721)
							(end -0.2032 0.2286)
						)
						(arc
							(start 0.2032 0.2286)
							(mid 0.239121 0.213721)
							(end 0.254 0.1778)
						)
						(arc
							(start 0.254 -0.1778)
							(mid 0.239121 -0.213721)
							(end 0.2032 -0.2286)
						)
						(arc
							(start -0.2032 -0.2286)
							(mid -0.239121 -0.213721)
							(end -0.254 -0.1778)
						)
					)
					(width 0)
					(fill yes)
				)
			)
		)
	)
	(footprint ""
		(layer "B.Cu")
		(at 95.885 -36.83)
		(property "Reference" "R333"
			(at 0 0 0)
			(layer "B.SilkS")
			(hide yes)
			(effects
				(font
					(size 1.27 1.27)
				)
				(justify mirror)
			)
		)
		(property "Value" "100KR2F-L1-GP"
			(at -0.064008 -3.993896 0)
			(unlocked yes)
			(layer "B.Fab")
			(hide yes)
			(effects
				(font
					(size 1.016 1.016)
					(thickness 0.1524)
				)
				(justify mirror)
			)
		)
		(property "Device Type" "R402H16"
			(at -0.064008 -5.517896 0)
			(unlocked yes)
			(layer "B.Fab")
			(hide yes)
			(effects
				(font
					(size 1.016 1.016)
					(thickness 0.1524)
				)
				(justify mirror)
			)
		)
		(duplicate_pad_numbers_are_jumpers no)
		(fp_rect
			(start 0.381 0.8382)
			(end -0.381 -0.8382)
			(stroke
				(width 0)
				(type default)
			)
			(fill no)
			(layer "B.CrtYd")
		)
		(fp_rect
			(start 0.381 0.8382)
			(end -0.381 -0.8382)
			(stroke
				(width 0)
				(type default)
			)
			(fill no)
			(layer "B.Fab")
		)
		(pad "1" smd custom
			(at 0 -0.4318 180)
			(size 0.127 0.127)
			(layers "B.Cu" "B.Mask" "B.Paste")
			(net "VSSRAMCPUSI1_SENSE")
			(options
				(clearance outline)
				(anchor circle)
			)
			(primitives
				(gr_poly
					(pts
						(arc
							(start -0.2032 0.2794)
							(mid -0.239121 0.264521)
							(end -0.254 0.2286)
						)
						(arc
							(start -0.254 -0.2286)
							(mid -0.239121 -0.264521)
							(end -0.2032 -0.2794)
						)
						(arc
							(start 0.2032 -0.2794)
							(mid 0.239121 -0.264521)
							(end 0.254 -0.2286)
						)
						(arc
							(start 0.254 0.2286)
							(mid 0.239121 0.264521)
							(end 0.2032 0.2794)
						)
					)
					(width 0)
					(fill yes)
				)
			)
		)
		(pad "2" smd custom
			(at 0 0.4318 180)
			(size 0.127 0.127)
			(layers "B.Cu" "B.Mask" "B.Paste")
			(net "GND")
			(options
				(clearance outline)
				(anchor circle)
			)
			(primitives
				(gr_poly
					(pts
						(arc
							(start -0.2032 0.2794)
							(mid -0.239121 0.264521)
							(end -0.254 0.2286)
						)
						(arc
							(start -0.254 -0.2286)
							(mid -0.239121 -0.264521)
							(end -0.2032 -0.2794)
						)
						(arc
							(start 0.2032 -0.2794)
							(mid 0.239121 -0.264521)
							(end 0.254 -0.2286)
						)
						(arc
							(start 0.254 0.2286)
							(mid 0.239121 0.264521)
							(end 0.2032 0.2794)
						)
					)
					(width 0)
					(fill yes)
				)
			)
		)
	)
	(footprint ""
		(layer "B.Cu")
		(at 90.424 -46.101 180)
		(property "Reference" "C146"
			(at 0 0 0)
			(layer "B.SilkS")
			(hide yes)
			(effects
				(font
					(size 1.27 1.27)
				)
				(justify mirror)
			)
		)
		(property "Value" "SC1U10V2KX-1GP"
			(at -1.1811 -2.7051 180)
			(unlocked yes)
			(layer "B.Fab")
			(hide yes)
			(effects
				(font
					(size 1.016 1.016)
					(thickness 0.1524)
				)
				(justify mirror)
			)
		)
		(property "Device Type" "C402H22"
			(at -1.1811 -4.2291 180)
			(unlocked yes)
			(layer "B.Fab")
			(hide yes)
			(effects
				(font
					(size 1.016 1.016)
					(thickness 0.1524)
				)
				(justify mirror)
			)
		)
		(duplicate_pad_numbers_are_jumpers no)
		(fp_rect
			(start 0.381 0.7366)
			(end -0.381 -0.7366)
			(stroke
				(width 0)
				(type default)
			)
			(fill no)
			(layer "B.CrtYd")
		)
		(fp_rect
			(start 0.381 0.7366)
			(end -0.381 -0.7366)
			(stroke
				(width 0)
				(type default)
			)
			(fill no)
			(layer "B.Fab")
		)
		(pad "1" smd custom
			(at 0 -0.4572)
			(size 0.1143 0.1143)
			(layers "B.Cu" "B.Mask" "B.Paste")
			(net "P3V3_CPU")
			(options
				(clearance outline)
				(anchor circle)
			)
			(primitives
				(gr_poly
					(pts
						(arc
							(start -0.254 0.1778)
							(mid -0.239121 0.213721)
							(end -0.2032 0.2286)
						)
						(arc
							(start 0.2032 0.2286)
							(mid 0.239121 0.213721)
							(end 0.254 0.1778)
						)
						(arc
							(start 0.254 -0.1778)
							(mid 0.239121 -0.213721)
							(end 0.2032 -0.2286)
						)
						(arc
							(start -0.2032 -0.2286)
							(mid -0.239121 -0.213721)
							(end -0.254 -0.1778)
						)
					)
					(width 0)
					(fill yes)
				)
			)
		)
		(pad "2" smd custom
			(at 0 0.4572)
			(size 0.1143 0.1143)
			(layers "B.Cu" "B.Mask" "B.Paste")
			(net "GND")
			(options
				(clearance outline)
				(anchor circle)
			)
			(primitives
				(gr_poly
					(pts
						(arc
							(start -0.254 0.1778)
							(mid -0.239121 0.213721)
							(end -0.2032 0.2286)
						)
						(arc
							(start 0.2032 0.2286)
							(mid 0.239121 0.213721)
							(end 0.254 0.1778)
						)
						(arc
							(start 0.254 -0.1778)
							(mid 0.239121 -0.213721)
							(end 0.2032 -0.2286)
						)
						(arc
							(start -0.2032 -0.2286)
							(mid -0.239121 -0.213721)
							(end -0.254 -0.1778)
						)
					)
					(width 0)
					(fill yes)
				)
			)
		)
	)
	(footprint ""
		(layer "B.Cu")
		(at 98.171 -43.18)
		(property "Reference" "C157"
			(at 0 0 0)
			(layer "B.SilkS")
			(hide yes)
			(effects
				(font
					(size 1.27 1.27)
				)
				(justify mirror)
			)
		)
		(property "Value" "SC1U10V2KX-1GP"
			(at -1.1811 -2.7051 0)
			(unlocked yes)
			(layer "B.Fab")
			(hide yes)
			(effects
				(font
					(size 1.016 1.016)
					(thickness 0.1524)
				)
				(justify mirror)
			)
		)
		(property "Device Type" "C402H22"
			(at -1.1811 -4.2291 0)
			(unlocked yes)
			(layer "B.Fab")
			(hide yes)
			(effects
				(font
					(size 1.016 1.016)
					(thickness 0.1524)
				)
				(justify mirror)
			)
		)
		(duplicate_pad_numbers_are_jumpers no)
		(fp_rect
			(start 0.381 0.7366)
			(end -0.381 -0.7366)
			(stroke
				(width 0)
				(type default)
			)
			(fill no)
			(layer "B.CrtYd")
		)
		(fp_rect
			(start 0.381 0.7366)
			(end -0.381 -0.7366)
			(stroke
				(width 0)
				(type default)
			)
			(fill no)
			(layer "B.Fab")
		)
		(pad "1" smd custom
			(at 0 -0.4572 180)
			(size 0.1143 0.1143)
			(layers "B.Cu" "B.Mask" "B.Paste")
			(net "P1V35")
			(options
				(clearance outline)
				(anchor circle)
			)
			(primitives
				(gr_poly
					(pts
						(arc
							(start -0.254 0.1778)
							(mid -0.239121 0.213721)
							(end -0.2032 0.2286)
						)
						(arc
							(start 0.2032 0.2286)
							(mid 0.239121 0.213721)
							(end 0.254 0.1778)
						)
						(arc
							(start 0.254 -0.1778)
							(mid 0.239121 -0.213721)
							(end 0.2032 -0.2286)
						)
						(arc
							(start -0.2032 -0.2286)
							(mid -0.239121 -0.213721)
							(end -0.254 -0.1778)
						)
					)
					(width 0)
					(fill yes)
				)
			)
		)
		(pad "2" smd custom
			(at 0 0.4572 180)
			(size 0.1143 0.1143)
			(layers "B.Cu" "B.Mask" "B.Paste")
			(net "GND")
			(options
				(clearance outline)
				(anchor circle)
			)
			(primitives
				(gr_poly
					(pts
						(arc
							(start -0.254 0.1778)
							(mid -0.239121 0.213721)
							(end -0.2032 0.2286)
						)
						(arc
							(start 0.2032 0.2286)
							(mid 0.239121 0.213721)
							(end 0.254 0.1778)
						)
						(arc
							(start 0.254 -0.1778)
							(mid 0.239121 -0.213721)
							(end 0.2032 -0.2286)
						)
						(arc
							(start -0.2032 -0.2286)
							(mid -0.239121 -0.213721)
							(end -0.254 -0.1778)
						)
					)
					(width 0)
					(fill yes)
				)
			)
		)
	)
	(footprint ""
		(layer "B.Cu")
		(at 133.35 -59.944 180)
		(property "Reference" "R231"
			(at 0 0 0)
			(layer "B.SilkS")
			(hide yes)
			(effects
				(font
					(size 1.27 1.27)
				)
				(justify mirror)
			)
		)
		(property "Value" "4K7R2F-GP"
			(at -0.064008 -3.993896 180)
			(unlocked yes)
			(layer "B.Fab")
			(hide yes)
			(effects
				(font
					(size 1.016 1.016)
					(thickness 0.1524)
				)
				(justify mirror)
			)
		)
		(property "Device Type" "R402H16"
			(at -0.064008 -5.517896 180)
			(unlocked yes)
			(layer "B.Fab")
			(hide yes)
			(effects
				(font
					(size 1.016 1.016)
					(thickness 0.1524)
				)
				(justify mirror)
			)
		)
		(duplicate_pad_numbers_are_jumpers no)
		(fp_rect
			(start 0.381 0.8382)
			(end -0.381 -0.8382)
			(stroke
				(width 0)
				(type default)
			)
			(fill no)
			(layer "B.CrtYd")
		)
		(fp_rect
			(start 0.381 0.8382)
			(end -0.381 -0.8382)
			(stroke
				(width 0)
				(type default)
			)
			(fill no)
			(layer "B.Fab")
		)
		(pad "1" smd custom
			(at 0 -0.4318)
			(size 0.127 0.127)
			(layers "B.Cu" "B.Mask" "B.Paste")
			(net "P3V3_STBY")
			(options
				(clearance outline)
				(anchor circle)
			)
			(primitives
				(gr_poly
					(pts
						(arc
							(start -0.2032 0.2794)
							(mid -0.239121 0.264521)
							(end -0.254 0.2286)
						)
						(arc
							(start -0.254 -0.2286)
							(mid -0.239121 -0.264521)
							(end -0.2032 -0.2794)
						)
						(arc
							(start 0.2032 -0.2794)
							(mid 0.239121 -0.264521)
							(end 0.254 -0.2286)
						)
						(arc
							(start 0.254 0.2286)
							(mid 0.239121 0.264521)
							(end 0.2032 0.2794)
						)
					)
					(width 0)
					(fill yes)
				)
			)
		)
		(pad "2" smd custom
			(at 0 0.4318)
			(size 0.127 0.127)
			(layers "B.Cu" "B.Mask" "B.Paste")
			(net "CHA_0_SA0")
			(options
				(clearance outline)
				(anchor circle)
			)
			(primitives
				(gr_poly
					(pts
						(arc
							(start -0.2032 0.2794)
							(mid -0.239121 0.264521)
							(end -0.254 0.2286)
						)
						(arc
							(start -0.254 -0.2286)
							(mid -0.239121 -0.264521)
							(end -0.2032 -0.2794)
						)
						(arc
							(start 0.2032 -0.2794)
							(mid 0.239121 -0.264521)
							(end 0.254 -0.2286)
						)
						(arc
							(start 0.254 0.2286)
							(mid 0.239121 0.264521)
							(end 0.2032 0.2794)
						)
					)
					(width 0)
					(fill yes)
				)
			)
		)
	)
	(footprint ""
		(layer "B.Cu")
		(at 96.647 -18.050002 180)
		(property "Reference" "C258"
			(at 0 0 0)
			(layer "B.SilkS")
			(hide yes)
			(effects
				(font
					(size 1.27 1.27)
				)
				(justify mirror)
			)
		)
		(property "Value" "SC1U25V3KX-GP"
			(at 0 -2.8194 180)
			(unlocked yes)
			(layer "B.Fab")
			(hide yes)
			(effects
				(font
					(size 1.016 1.016)
					(thickness 0.1524)
				)
				(justify mirror)
			)
		)
		(property "Device Type" "C603H36"
			(at 0 -4.3434 180)
			(unlocked yes)
			(layer "B.Fab")
			(hide yes)
			(effects
				(font
					(size 1.016 1.016)
					(thickness 0.1524)
				)
				(justify mirror)
			)
		)
		(duplicate_pad_numbers_are_jumpers no)
		(fp_line
			(start 0.4064 0)
			(end -0.4064 0)
			(stroke
				(width 0.2286)
				(type default)
			)
			(layer "B.SilkS")
		)
		(fp_rect
			(start 0.635 1.1811)
			(end -0.635 -1.1811)
			(stroke
				(width 0)
				(type default)
			)
			(fill no)
			(layer "B.CrtYd")
		)
		(fp_rect
			(start 0.635 1.1811)
			(end -0.635 -1.1811)
			(stroke
				(width 0)
				(type default)
			)
			(fill no)
			(layer "B.Fab")
		)
		(pad "1" smd custom
			(at 0 -0.6604)
			(size 0.19685 0.19685)
			(layers "B.Cu" "B.Mask" "B.Paste")
			(net "VCCACKDDR1")
			(options
				(clearance outline)
				(anchor circle)
			)
			(primitives
				(gr_poly
					(pts
						(arc
							(start 0.508 0.2921)
							(mid 0.478242 0.363942)
							(end 0.4064 0.3937)
						)
						(arc
							(start -0.4064 0.3937)
							(mid -0.478242 0.363942)
							(end -0.508 0.2921)
						)
						(arc
							(start -0.508 -0.2921)
							(mid -0.478242 -0.363942)
							(end -0.4064 -0.3937)
						)
						(arc
							(start 0.4064 -0.3937)
							(mid 0.478242 -0.363942)
							(end 0.508 -0.2921)
						)
					)
					(width 0)
					(fill yes)
				)
			)
		)
		(pad "2" smd custom
			(at 0 0.6604)
			(size 0.19685 0.19685)
			(layers "B.Cu" "B.Mask" "B.Paste")
			(net "GND")
			(options
				(clearance outline)
				(anchor circle)
			)
			(primitives
				(gr_poly
					(pts
						(arc
							(start 0.508 0.2921)
							(mid 0.478242 0.363942)
							(end 0.4064 0.3937)
						)
						(arc
							(start -0.4064 0.3937)
							(mid -0.478242 0.363942)
							(end -0.508 0.2921)
						)
						(arc
							(start -0.508 -0.2921)
							(mid -0.478242 -0.363942)
							(end -0.4064 -0.3937)
						)
						(arc
							(start 0.4064 -0.3937)
							(mid 0.478242 -0.363942)
							(end 0.508 -0.2921)
						)
					)
					(width 0)
					(fill yes)
				)
			)
		)
	)
	(footprint ""
		(layer "B.Cu")
		(at 89.154 -26.289 -90)
		(property "Reference" "C224"
			(at 0 0 90)
			(layer "B.SilkS")
			(hide yes)
			(effects
				(font
					(size 1.27 1.27)
				)
				(justify mirror)
			)
		)
		(property "Value" "SC1U10V2KX-1GP"
			(at -1.1811 -2.7051 270)
			(unlocked yes)
			(layer "B.Fab")
			(hide yes)
			(effects
				(font
					(size 1.016 1.016)
					(thickness 0.1524)
				)
				(justify mirror)
			)
		)
		(property "Device Type" "C402H22"
			(at -1.1811 -4.2291 270)
			(unlocked yes)
			(layer "B.Fab")
			(hide yes)
			(effects
				(font
					(size 1.016 1.016)
					(thickness 0.1524)
				)
				(justify mirror)
			)
		)
		(duplicate_pad_numbers_are_jumpers no)
		(fp_rect
			(start 0.381 0.7366)
			(end -0.381 -0.7366)
			(stroke
				(width 0)
				(type default)
			)
			(fill no)
			(layer "B.CrtYd")
		)
		(fp_rect
			(start 0.381 0.7366)
			(end -0.381 -0.7366)
			(stroke
				(width 0)
				(type default)
			)
			(fill no)
			(layer "B.Fab")
		)
		(pad "1" smd custom
			(at 0 -0.4572 90)
			(size 0.1143 0.1143)
			(layers "B.Cu" "B.Mask" "B.Paste")
			(net "P1V0")
			(options
				(clearance outline)
				(anchor circle)
			)
			(primitives
				(gr_poly
					(pts
						(arc
							(start -0.254 0.1778)
							(mid -0.239121 0.213721)
							(end -0.2032 0.2286)
						)
						(arc
							(start 0.2032 0.2286)
							(mid 0.239121 0.213721)
							(end 0.254 0.1778)
						)
						(arc
							(start 0.254 -0.1778)
							(mid 0.239121 -0.213721)
							(end 0.2032 -0.2286)
						)
						(arc
							(start -0.2032 -0.2286)
							(mid -0.239121 -0.213721)
							(end -0.254 -0.1778)
						)
					)
					(width 0)
					(fill yes)
				)
			)
		)
		(pad "2" smd custom
			(at 0 0.4572 90)
			(size 0.1143 0.1143)
			(layers "B.Cu" "B.Mask" "B.Paste")
			(net "GND")
			(options
				(clearance outline)
				(anchor circle)
			)
			(primitives
				(gr_poly
					(pts
						(arc
							(start -0.254 0.1778)
							(mid -0.239121 0.213721)
							(end -0.2032 0.2286)
						)
						(arc
							(start 0.2032 0.2286)
							(mid 0.239121 0.213721)
							(end 0.254 0.1778)
						)
						(arc
							(start 0.254 -0.1778)
							(mid 0.239121 -0.213721)
							(end 0.2032 -0.2286)
						)
						(arc
							(start -0.2032 -0.2286)
							(mid -0.239121 -0.213721)
							(end -0.254 -0.1778)
						)
					)
					(width 0)
					(fill yes)
				)
			)
		)
	)
	(footprint ""
		(layer "B.Cu")
		(at 53.467 -17.272 -90)
		(property "Reference" "C304"
			(at 0 0 90)
			(layer "B.SilkS")
			(hide yes)
			(effects
				(font
					(size 1.27 1.27)
				)
				(justify mirror)
			)
		)
		(property "Value" "SCD1U16V2KX-3GP"
			(at -1.8923 -1.2065 270)
			(unlocked yes)
			(layer "B.Fab")
			(hide yes)
			(effects
				(font
					(size 1.016 1.016)
					(thickness 0.1524)
				)
				(justify mirror)
			)
		)
		(property "Device Type" "C402H22"
			(at -1.8923 -2.7305 270)
			(unlocked yes)
			(layer "B.Fab")
			(hide yes)
			(effects
				(font
					(size 1.016 1.016)
					(thickness 0.1524)
				)
				(justify mirror)
			)
		)
		(duplicate_pad_numbers_are_jumpers no)
		(fp_rect
			(start 0.381 0.7366)
			(end -0.381 -0.7366)
			(stroke
				(width 0)
				(type default)
			)
			(fill no)
			(layer "B.CrtYd")
		)
		(fp_rect
			(start 0.381 0.7366)
			(end -0.381 -0.7366)
			(stroke
				(width 0)
				(type default)
			)
			(fill no)
			(layer "B.Fab")
		)
		(pad "1" smd custom
			(at 0 -0.4572 90)
			(size 0.1143 0.1143)
			(layers "B.Cu" "B.Mask" "B.Paste")
			(net "P3V3")
			(options
				(clearance outline)
				(anchor circle)
			)
			(primitives
				(gr_poly
					(pts
						(arc
							(start -0.254 0.1778)
							(mid -0.239121 0.213721)
							(end -0.2032 0.2286)
						)
						(arc
							(start 0.2032 0.2286)
							(mid 0.239121 0.213721)
							(end 0.254 0.1778)
						)
						(arc
							(start 0.254 -0.1778)
							(mid 0.239121 -0.213721)
							(end 0.2032 -0.2286)
						)
						(arc
							(start -0.2032 -0.2286)
							(mid -0.239121 -0.213721)
							(end -0.254 -0.1778)
						)
					)
					(width 0)
					(fill yes)
				)
			)
		)
		(pad "2" smd custom
			(at 0 0.4572 90)
			(size 0.1143 0.1143)
			(layers "B.Cu" "B.Mask" "B.Paste")
			(net "GND")
			(options
				(clearance outline)
				(anchor circle)
			)
			(primitives
				(gr_poly
					(pts
						(arc
							(start -0.254 0.1778)
							(mid -0.239121 0.213721)
							(end -0.2032 0.2286)
						)
						(arc
							(start 0.2032 0.2286)
							(mid 0.239121 0.213721)
							(end 0.254 0.1778)
						)
						(arc
							(start 0.254 -0.1778)
							(mid 0.239121 -0.213721)
							(end 0.2032 -0.2286)
						)
						(arc
							(start -0.2032 -0.2286)
							(mid -0.239121 -0.213721)
							(end -0.254 -0.1778)
						)
					)
					(width 0)
					(fill yes)
				)
			)
		)
	)
	(footprint ""
		(layer "B.Cu")
		(at 131.445 -56.388 180)
		(property "Reference" "PC142"
			(at 0 0 0)
			(layer "B.SilkS")
			(hide yes)
			(effects
				(font
					(size 1.27 1.27)
				)
				(justify mirror)
			)
		)
		(property "Value" "SC10U6D3V3MX-GP"
			(at 0 -2.8194 180)
			(unlocked yes)
			(layer "B.Fab")
			(hide yes)
			(effects
				(font
					(size 1.016 1.016)
					(thickness 0.1524)
				)
				(justify mirror)
			)
		)
		(property "Device Type" "C603H38"
			(at 0 -4.3434 180)
			(unlocked yes)
			(layer "B.Fab")
			(hide yes)
			(effects
				(font
					(size 1.016 1.016)
					(thickness 0.1524)
				)
				(justify mirror)
			)
		)
		(duplicate_pad_numbers_are_jumpers no)
		(fp_line
			(start 0.4064 0)
			(end -0.4064 0)
			(stroke
				(width 0.2286)
				(type default)
			)
			(layer "B.SilkS")
		)
		(fp_rect
			(start 0.635 1.1811)
			(end -0.635 -1.1811)
			(stroke
				(width 0)
				(type default)
			)
			(fill no)
			(layer "B.CrtYd")
		)
		(fp_rect
			(start 0.635 1.1811)
			(end -0.635 -1.1811)
			(stroke
				(width 0)
				(type default)
			)
			(fill no)
			(layer "B.Fab")
		)
		(pad "1" smd custom
			(at 0 -0.6604)
			(size 0.19685 0.19685)
			(layers "B.Cu" "B.Mask" "B.Paste")
			(net "GND")
			(options
				(clearance outline)
				(anchor circle)
			)
			(primitives
				(gr_poly
					(pts
						(arc
							(start 0.508 0.2921)
							(mid 0.478242 0.363942)
							(end 0.4064 0.3937)
						)
						(arc
							(start -0.4064 0.3937)
							(mid -0.478242 0.363942)
							(end -0.508 0.2921)
						)
						(arc
							(start -0.508 -0.2921)
							(mid -0.478242 -0.363942)
							(end -0.4064 -0.3937)
						)
						(arc
							(start 0.4064 -0.3937)
							(mid 0.478242 -0.363942)
							(end 0.508 -0.2921)
						)
					)
					(width 0)
					(fill yes)
				)
			)
		)
		(pad "2" smd custom
			(at 0 0.6604)
			(size 0.19685 0.19685)
			(layers "B.Cu" "B.Mask" "B.Paste")
			(net "PV_VTT_DDR_A")
			(options
				(clearance outline)
				(anchor circle)
			)
			(primitives
				(gr_poly
					(pts
						(arc
							(start 0.508 0.2921)
							(mid 0.478242 0.363942)
							(end 0.4064 0.3937)
						)
						(arc
							(start -0.4064 0.3937)
							(mid -0.478242 0.363942)
							(end -0.508 0.2921)
						)
						(arc
							(start -0.508 -0.2921)
							(mid -0.478242 -0.363942)
							(end -0.4064 -0.3937)
						)
						(arc
							(start 0.4064 -0.3937)
							(mid 0.478242 -0.363942)
							(end 0.508 -0.2921)
						)
					)
					(width 0)
					(fill yes)
				)
			)
		)
	)
	(footprint ""
		(layer "B.Cu")
		(at 43.942 -54.102 90)
		(property "Reference" "R126"
			(at 0 0 90)
			(layer "B.SilkS")
			(hide yes)
			(effects
				(font
					(size 1.27 1.27)
				)
				(justify mirror)
			)
		)
		(property "Value" "0R2J-2-GP"
			(at -1.7907 -1.1176 90)
			(unlocked yes)
			(layer "B.Fab")
			(hide yes)
			(effects
				(font
					(size 1.016 1.016)
					(thickness 0.1524)
				)
				(justify mirror)
			)
		)
		(property "Device Type" "R402H16"
			(at -1.7907 -2.6416 90)
			(unlocked yes)
			(layer "B.Fab")
			(hide yes)
			(effects
				(font
					(size 1.016 1.016)
					(thickness 0.1524)
				)
				(justify mirror)
			)
		)
		(duplicate_pad_numbers_are_jumpers no)
		(fp_rect
			(start 0.381 0.8382)
			(end -0.381 -0.8382)
			(stroke
				(width 0)
				(type default)
			)
			(fill no)
			(layer "B.CrtYd")
		)
		(fp_rect
			(start 0.381 0.8382)
			(end -0.381 -0.8382)
			(stroke
				(width 0)
				(type default)
			)
			(fill no)
			(layer "B.Fab")
		)
		(pad "1" smd custom
			(at 0 -0.4318 270)
			(size 0.127 0.127)
			(layers "B.Cu" "B.Mask" "B.Paste")
			(net "CLKGEN_VSEL_PCI")
			(options
				(clearance outline)
				(anchor circle)
			)
			(primitives
				(gr_poly
					(pts
						(arc
							(start -0.2032 0.2794)
							(mid -0.239121 0.264521)
							(end -0.254 0.2286)
						)
						(arc
							(start -0.254 -0.2286)
							(mid -0.239121 -0.264521)
							(end -0.2032 -0.2794)
						)
						(arc
							(start 0.2032 -0.2794)
							(mid 0.239121 -0.264521)
							(end 0.254 -0.2286)
						)
						(arc
							(start 0.254 0.2286)
							(mid 0.239121 0.264521)
							(end 0.2032 0.2794)
						)
					)
					(width 0)
					(fill yes)
				)
			)
		)
		(pad "2" smd custom
			(at 0 0.4318 270)
			(size 0.127 0.127)
			(layers "B.Cu" "B.Mask" "B.Paste")
			(net "GND")
			(options
				(clearance outline)
				(anchor circle)
			)
			(primitives
				(gr_poly
					(pts
						(arc
							(start -0.2032 0.2794)
							(mid -0.239121 0.264521)
							(end -0.254 0.2286)
						)
						(arc
							(start -0.254 -0.2286)
							(mid -0.239121 -0.264521)
							(end -0.2032 -0.2794)
						)
						(arc
							(start 0.2032 -0.2794)
							(mid 0.239121 -0.264521)
							(end 0.254 -0.2286)
						)
						(arc
							(start 0.254 0.2286)
							(mid 0.239121 0.264521)
							(end 0.2032 0.2794)
						)
					)
					(width 0)
					(fill yes)
				)
			)
		)
	)
	(footprint ""
		(layer "B.Cu")
		(at 8.509 -25.146 -90)
		(property "Reference" "PC89"
			(at 0 0 90)
			(layer "B.SilkS")
			(hide yes)
			(effects
				(font
					(size 1.27 1.27)
				)
				(justify mirror)
			)
		)
		(property "Value" "SC1U16V2KX-GP"
			(at -1.8923 -1.2065 270)
			(unlocked yes)
			(layer "B.Fab")
			(hide yes)
			(effects
				(font
					(size 1.016 1.016)
					(thickness 0.1524)
				)
				(justify mirror)
			)
		)
		(property "Device Type" "C402H22"
			(at -1.8923 -2.7305 270)
			(unlocked yes)
			(layer "B.Fab")
			(hide yes)
			(effects
				(font
					(size 1.016 1.016)
					(thickness 0.1524)
				)
				(justify mirror)
			)
		)
		(duplicate_pad_numbers_are_jumpers no)
		(fp_rect
			(start 0.381 0.7366)
			(end -0.381 -0.7366)
			(stroke
				(width 0)
				(type default)
			)
			(fill no)
			(layer "B.CrtYd")
		)
		(fp_rect
			(start 0.381 0.7366)
			(end -0.381 -0.7366)
			(stroke
				(width 0)
				(type default)
			)
			(fill no)
			(layer "B.Fab")
		)
		(pad "1" smd custom
			(at 0 -0.4572 90)
			(size 0.1143 0.1143)
			(layers "B.Cu" "B.Mask" "B.Paste")
			(net "P1V0_VREG")
			(options
				(clearance outline)
				(anchor circle)
			)
			(primitives
				(gr_poly
					(pts
						(arc
							(start -0.254 0.1778)
							(mid -0.239121 0.213721)
							(end -0.2032 0.2286)
						)
						(arc
							(start 0.2032 0.2286)
							(mid 0.239121 0.213721)
							(end 0.254 0.1778)
						)
						(arc
							(start 0.254 -0.1778)
							(mid 0.239121 -0.213721)
							(end 0.2032 -0.2286)
						)
						(arc
							(start -0.2032 -0.2286)
							(mid -0.239121 -0.213721)
							(end -0.254 -0.1778)
						)
					)
					(width 0)
					(fill yes)
				)
			)
		)
		(pad "2" smd custom
			(at 0 0.4572 90)
			(size 0.1143 0.1143)
			(layers "B.Cu" "B.Mask" "B.Paste")
			(net "GND")
			(options
				(clearance outline)
				(anchor circle)
			)
			(primitives
				(gr_poly
					(pts
						(arc
							(start -0.254 0.1778)
							(mid -0.239121 0.213721)
							(end -0.2032 0.2286)
						)
						(arc
							(start 0.2032 0.2286)
							(mid 0.239121 0.213721)
							(end 0.254 0.1778)
						)
						(arc
							(start 0.254 -0.1778)
							(mid 0.239121 -0.213721)
							(end 0.2032 -0.2286)
						)
						(arc
							(start -0.2032 -0.2286)
							(mid -0.239121 -0.213721)
							(end -0.254 -0.1778)
						)
					)
					(width 0)
					(fill yes)
				)
			)
		)
	)
	(footprint ""
		(layer "B.Cu")
		(at 81.28 -27.051 90)
		(property "Reference" "R409"
			(at 0 0 90)
			(layer "B.SilkS")
			(hide yes)
			(effects
				(font
					(size 1.27 1.27)
				)
				(justify mirror)
			)
		)
		(property "Value" "4K7R2F-GP"
			(at -1.7907 -1.1176 90)
			(unlocked yes)
			(layer "B.Fab")
			(hide yes)
			(effects
				(font
					(size 1.016 1.016)
					(thickness 0.1524)
				)
				(justify mirror)
			)
		)
		(property "Device Type" "R402H16"
			(at -1.7907 -2.6416 90)
			(unlocked yes)
			(layer "B.Fab")
			(hide yes)
			(effects
				(font
					(size 1.016 1.016)
					(thickness 0.1524)
				)
				(justify mirror)
			)
		)
		(duplicate_pad_numbers_are_jumpers no)
		(fp_rect
			(start 0.381 0.8382)
			(end -0.381 -0.8382)
			(stroke
				(width 0)
				(type default)
			)
			(fill no)
			(layer "B.CrtYd")
		)
		(fp_rect
			(start 0.381 0.8382)
			(end -0.381 -0.8382)
			(stroke
				(width 0)
				(type default)
			)
			(fill no)
			(layer "B.Fab")
		)
		(pad "1" smd custom
			(at 0 -0.4318 270)
			(size 0.127 0.127)
			(layers "B.Cu" "B.Mask" "B.Paste")
			(net "P3V3_CPU")
			(options
				(clearance outline)
				(anchor circle)
			)
			(primitives
				(gr_poly
					(pts
						(arc
							(start -0.2032 0.2794)
							(mid -0.239121 0.264521)
							(end -0.254 0.2286)
						)
						(arc
							(start -0.254 -0.2286)
							(mid -0.239121 -0.264521)
							(end -0.2032 -0.2794)
						)
						(arc
							(start 0.2032 -0.2794)
							(mid 0.239121 -0.264521)
							(end 0.254 -0.2286)
						)
						(arc
							(start 0.254 0.2286)
							(mid 0.239121 0.264521)
							(end 0.2032 0.2794)
						)
					)
					(width 0)
					(fill yes)
				)
			)
		)
		(pad "2" smd custom
			(at 0 0.4318 270)
			(size 0.127 0.127)
			(layers "B.Cu" "B.Mask" "B.Paste")
			(net "BD_REV_2")
			(options
				(clearance outline)
				(anchor circle)
			)
			(primitives
				(gr_poly
					(pts
						(arc
							(start -0.2032 0.2794)
							(mid -0.239121 0.264521)
							(end -0.254 0.2286)
						)
						(arc
							(start -0.254 -0.2286)
							(mid -0.239121 -0.264521)
							(end -0.2032 -0.2794)
						)
						(arc
							(start 0.2032 -0.2794)
							(mid 0.239121 -0.264521)
							(end 0.254 -0.2286)
						)
						(arc
							(start 0.254 0.2286)
							(mid 0.239121 0.264521)
							(end 0.2032 0.2794)
						)
					)
					(width 0)
					(fill yes)
				)
			)
		)
	)
	(footprint ""
		(layer "B.Cu")
		(at 39.6494 -46.863)
		(property "Reference" "C68"
			(at 0 0 0)
			(layer "B.SilkS")
			(hide yes)
			(effects
				(font
					(size 1.27 1.27)
				)
				(justify mirror)
			)
		)
		(property "Value" "SC10U6D3V3MX-GP"
			(at 0.0254 -2.0193 0)
			(unlocked yes)
			(layer "B.Fab")
			(hide yes)
			(effects
				(font
					(size 1.016 1.016)
					(thickness 0.1524)
				)
				(justify mirror)
			)
		)
		(property "Device Type" "C603H38"
			(at 0.0254 -3.5433 0)
			(unlocked yes)
			(layer "B.Fab")
			(hide yes)
			(effects
				(font
					(size 1.016 1.016)
					(thickness 0.1524)
				)
				(justify mirror)
			)
		)
		(duplicate_pad_numbers_are_jumpers no)
		(fp_line
			(start 0.4064 0)
			(end -0.4064 0)
			(stroke
				(width 0.2286)
				(type default)
			)
			(layer "B.SilkS")
		)
		(fp_rect
			(start 0.635 1.1811)
			(end -0.635 -1.1811)
			(stroke
				(width 0)
				(type default)
			)
			(fill no)
			(layer "B.CrtYd")
		)
		(fp_rect
			(start 0.635 1.1811)
			(end -0.635 -1.1811)
			(stroke
				(width 0)
				(type default)
			)
			(fill no)
			(layer "B.Fab")
		)
		(pad "1" smd custom
			(at 0 -0.6604 180)
			(size 0.19685 0.19685)
			(layers "B.Cu" "B.Mask" "B.Paste")
			(net "P3V3_CLK_XTAL")
			(options
				(clearance outline)
				(anchor circle)
			)
			(primitives
				(gr_poly
					(pts
						(arc
							(start 0.508 0.2921)
							(mid 0.478242 0.363942)
							(end 0.4064 0.3937)
						)
						(arc
							(start -0.4064 0.3937)
							(mid -0.478242 0.363942)
							(end -0.508 0.2921)
						)
						(arc
							(start -0.508 -0.2921)
							(mid -0.478242 -0.363942)
							(end -0.4064 -0.3937)
						)
						(arc
							(start 0.4064 -0.3937)
							(mid 0.478242 -0.363942)
							(end 0.508 -0.2921)
						)
					)
					(width 0)
					(fill yes)
				)
			)
		)
		(pad "2" smd custom
			(at 0 0.6604 180)
			(size 0.19685 0.19685)
			(layers "B.Cu" "B.Mask" "B.Paste")
			(net "GND")
			(options
				(clearance outline)
				(anchor circle)
			)
			(primitives
				(gr_poly
					(pts
						(arc
							(start 0.508 0.2921)
							(mid 0.478242 0.363942)
							(end 0.4064 0.3937)
						)
						(arc
							(start -0.4064 0.3937)
							(mid -0.478242 0.363942)
							(end -0.508 0.2921)
						)
						(arc
							(start -0.508 -0.2921)
							(mid -0.478242 -0.363942)
							(end -0.4064 -0.3937)
						)
						(arc
							(start 0.4064 -0.3937)
							(mid 0.478242 -0.363942)
							(end 0.508 -0.2921)
						)
					)
					(width 0)
					(fill yes)
				)
			)
		)
	)
	(footprint ""
		(layer "B.Cu")
		(at 142.748 -45.466 -90)
		(property "Reference" "C192"
			(at 0 0 90)
			(layer "B.SilkS")
			(hide yes)
			(effects
				(font
					(size 1.27 1.27)
				)
				(justify mirror)
			)
		)
		(property "Value" "SCD1U10V2KX-5GP"
			(at -1.1811 -2.7051 270)
			(unlocked yes)
			(layer "B.Fab")
			(hide yes)
			(effects
				(font
					(size 1.016 1.016)
					(thickness 0.1524)
				)
				(justify mirror)
			)
		)
		(property "Device Type" "C402H22"
			(at -1.1811 -4.2291 270)
			(unlocked yes)
			(layer "B.Fab")
			(hide yes)
			(effects
				(font
					(size 1.016 1.016)
					(thickness 0.1524)
				)
				(justify mirror)
			)
		)
		(duplicate_pad_numbers_are_jumpers no)
		(fp_rect
			(start 0.381 0.7366)
			(end -0.381 -0.7366)
			(stroke
				(width 0)
				(type default)
			)
			(fill no)
			(layer "B.CrtYd")
		)
		(fp_rect
			(start 0.381 0.7366)
			(end -0.381 -0.7366)
			(stroke
				(width 0)
				(type default)
			)
			(fill no)
			(layer "B.Fab")
		)
		(pad "1" smd custom
			(at 0 -0.4572 90)
			(size 0.1143 0.1143)
			(layers "B.Cu" "B.Mask" "B.Paste")
			(net "P3V3_STBY")
			(options
				(clearance outline)
				(anchor circle)
			)
			(primitives
				(gr_poly
					(pts
						(arc
							(start -0.254 0.1778)
							(mid -0.239121 0.213721)
							(end -0.2032 0.2286)
						)
						(arc
							(start 0.2032 0.2286)
							(mid 0.239121 0.213721)
							(end 0.254 0.1778)
						)
						(arc
							(start 0.254 -0.1778)
							(mid 0.239121 -0.213721)
							(end 0.2032 -0.2286)
						)
						(arc
							(start -0.2032 -0.2286)
							(mid -0.239121 -0.213721)
							(end -0.254 -0.1778)
						)
					)
					(width 0)
					(fill yes)
				)
			)
		)
		(pad "2" smd custom
			(at 0 0.4572 90)
			(size 0.1143 0.1143)
			(layers "B.Cu" "B.Mask" "B.Paste")
			(net "GND")
			(options
				(clearance outline)
				(anchor circle)
			)
			(primitives
				(gr_poly
					(pts
						(arc
							(start -0.254 0.1778)
							(mid -0.239121 0.213721)
							(end -0.2032 0.2286)
						)
						(arc
							(start 0.2032 0.2286)
							(mid 0.239121 0.213721)
							(end 0.254 0.1778)
						)
						(arc
							(start 0.254 -0.1778)
							(mid 0.239121 -0.213721)
							(end 0.2032 -0.2286)
						)
						(arc
							(start -0.2032 -0.2286)
							(mid -0.239121 -0.213721)
							(end -0.254 -0.1778)
						)
					)
					(width 0)
					(fill yes)
				)
			)
		)
	)
	(footprint ""
		(layer "B.Cu")
		(at 100.33 -68.326 180)
		(property "Reference" "PC122"
			(at 0 0 0)
			(layer "B.SilkS")
			(hide yes)
			(effects
				(font
					(size 1.27 1.27)
				)
				(justify mirror)
			)
		)
		(property "Value" "SCD015U25V2KX-GP"
			(at -1.1811 -2.7051 180)
			(unlocked yes)
			(layer "B.Fab")
			(hide yes)
			(effects
				(font
					(size 1.016 1.016)
					(thickness 0.1524)
				)
				(justify mirror)
			)
		)
		(property "Device Type" "C402H22"
			(at -1.1811 -4.2291 180)
			(unlocked yes)
			(layer "B.Fab")
			(hide yes)
			(effects
				(font
					(size 1.016 1.016)
					(thickness 0.1524)
				)
				(justify mirror)
			)
		)
		(duplicate_pad_numbers_are_jumpers no)
		(fp_rect
			(start 0.381 0.7366)
			(end -0.381 -0.7366)
			(stroke
				(width 0)
				(type default)
			)
			(fill no)
			(layer "B.CrtYd")
		)
		(fp_rect
			(start 0.381 0.7366)
			(end -0.381 -0.7366)
			(stroke
				(width 0)
				(type default)
			)
			(fill no)
			(layer "B.Fab")
		)
		(pad "1" smd custom
			(at 0 -0.4572)
			(size 0.1143 0.1143)
			(layers "B.Cu" "B.Mask" "B.Paste")
			(net "VR_P1V1_SS")
			(options
				(clearance outline)
				(anchor circle)
			)
			(primitives
				(gr_poly
					(pts
						(arc
							(start -0.254 0.1778)
							(mid -0.239121 0.213721)
							(end -0.2032 0.2286)
						)
						(arc
							(start 0.2032 0.2286)
							(mid 0.239121 0.213721)
							(end 0.254 0.1778)
						)
						(arc
							(start 0.254 -0.1778)
							(mid 0.239121 -0.213721)
							(end 0.2032 -0.2286)
						)
						(arc
							(start -0.2032 -0.2286)
							(mid -0.239121 -0.213721)
							(end -0.254 -0.1778)
						)
					)
					(width 0)
					(fill yes)
				)
			)
		)
		(pad "2" smd custom
			(at 0 0.4572)
			(size 0.1143 0.1143)
			(layers "B.Cu" "B.Mask" "B.Paste")
			(net "GND")
			(options
				(clearance outline)
				(anchor circle)
			)
			(primitives
				(gr_poly
					(pts
						(arc
							(start -0.254 0.1778)
							(mid -0.239121 0.213721)
							(end -0.2032 0.2286)
						)
						(arc
							(start 0.2032 0.2286)
							(mid 0.239121 0.213721)
							(end 0.254 0.1778)
						)
						(arc
							(start 0.254 -0.1778)
							(mid 0.239121 -0.213721)
							(end 0.2032 -0.2286)
						)
						(arc
							(start -0.2032 -0.2286)
							(mid -0.239121 -0.213721)
							(end -0.254 -0.1778)
						)
					)
					(width 0)
					(fill yes)
				)
			)
		)
	)
	(footprint ""
		(layer "B.Cu")
		(at 95.5802 -40.8686 -90)
		(property "Reference" "TP28"
			(at 0 0 90)
			(layer "B.SilkS")
			(hide yes)
			(effects
				(font
					(size 1.27 1.27)
				)
				(justify mirror)
			)
		)
		(property "Value" "TPAD24"
			(at 0 -2.9972 270)
			(unlocked yes)
			(layer "B.Fab")
			(hide yes)
			(effects
				(font
					(size 1.016 1.016)
					(thickness 0.1524)
				)
				(justify mirror)
			)
		)
		(property "Device Type" "TPAD24"
			(at 0 -4.5212 270)
			(unlocked yes)
			(layer "B.Fab")
			(hide yes)
			(effects
				(font
					(size 1.016 1.016)
					(thickness 0.1524)
				)
				(justify mirror)
			)
		)
		(duplicate_pad_numbers_are_jumpers no)
		(fp_poly
			(pts
				(arc
					(start 0 -0.3048)
					(mid 0 0.3048)
					(end 0 -0.3048)
				)
			)
			(stroke
				(width 0)
				(type default)
			)
			(fill no)
			(layer "B.CrtYd")
		)
		(fp_poly
			(pts
				(arc
					(start 0 -0.6096)
					(mid 0 0.6096)
					(end 0 -0.6096)
				)
			)
			(stroke
				(width 0)
				(type default)
			)
			(fill no)
			(layer "B.Fab")
		)
		(pad "1" smd circle
			(at 0 0 90)
			(size 0.6096 0.6096)
			(layers "B.Cu" "B.Mask" "B.Paste")
			(net "VCCCORE6VIDSI0GT_1P03")
		)
	)
	(footprint ""
		(layer "B.Cu")
		(at 25.4 -46.101 -90)
		(property "Reference" "PC133"
			(at 0 0 90)
			(layer "B.SilkS")
			(hide yes)
			(effects
				(font
					(size 1.27 1.27)
				)
				(justify mirror)
			)
		)
		(property "Value" "SC10U6D3V5KX-4GP"
			(at 0 -4.9022 270)
			(unlocked yes)
			(layer "B.Fab")
			(hide yes)
			(effects
				(font
					(size 1.016 1.016)
					(thickness 0.1524)
				)
				(justify mirror)
			)
		)
		(property "Device Type" "C805H58"
			(at 0 -6.8072 270)
			(unlocked yes)
			(layer "B.Fab")
			(hide yes)
			(effects
				(font
					(size 1.016 1.016)
					(thickness 0.1524)
				)
				(justify mirror)
			)
		)
		(duplicate_pad_numbers_are_jumpers no)
		(fp_line
			(start -0.6096 0)
			(end 0.6096 0)
			(stroke
				(width 0.3048)
				(type default)
			)
			(layer "B.SilkS")
		)
		(fp_poly
			(pts
				(xy 0.9017 1.4351) (xy -0.9017 1.4351) (xy -0.9017 -1.4351) (xy 0.9017 -1.4351)
			)
			(stroke
				(width 0)
				(type default)
			)
			(fill no)
			(layer "B.CrtYd")
		)
		(fp_poly
			(pts
				(xy -0.9017 1.4351) (xy -0.9017 -1.4351) (xy 0.9017 -1.4351) (xy 0.9017 1.4351)
			)
			(stroke
				(width 0)
				(type default)
			)
			(fill no)
			(layer "B.Fab")
		)
		(pad "1" smd rect
			(at 0 -0.8382 90)
			(size 1.5494 0.9398)
			(layers "B.Cu" "B.Mask" "B.Paste")
			(net "P1V5_STBY_OUT")
		)
		(pad "2" smd rect
			(at 0 0.8382 90)
			(size 1.5494 0.9398)
			(layers "B.Cu" "B.Mask" "B.Paste")
			(net "GND")
		)
	)
	(footprint ""
		(layer "B.Cu")
		(at 104.14 -27.321002)
		(property "Reference" "C242"
			(at 0 0 0)
			(layer "B.SilkS")
			(hide yes)
			(effects
				(font
					(size 1.27 1.27)
				)
				(justify mirror)
			)
		)
		(property "Value" "SC1U10V2KX-1GP"
			(at -1.1811 -2.7051 0)
			(unlocked yes)
			(layer "B.Fab")
			(hide yes)
			(effects
				(font
					(size 1.016 1.016)
					(thickness 0.1524)
				)
				(justify mirror)
			)
		)
		(property "Device Type" "C402H22"
			(at -1.1811 -4.2291 0)
			(unlocked yes)
			(layer "B.Fab")
			(hide yes)
			(effects
				(font
					(size 1.016 1.016)
					(thickness 0.1524)
				)
				(justify mirror)
			)
		)
		(duplicate_pad_numbers_are_jumpers no)
		(fp_rect
			(start 0.381 0.7366)
			(end -0.381 -0.7366)
			(stroke
				(width 0)
				(type default)
			)
			(fill no)
			(layer "B.CrtYd")
		)
		(fp_rect
			(start 0.381 0.7366)
			(end -0.381 -0.7366)
			(stroke
				(width 0)
				(type default)
			)
			(fill no)
			(layer "B.Fab")
		)
		(pad "1" smd custom
			(at 0 -0.4572 180)
			(size 0.1143 0.1143)
			(layers "B.Cu" "B.Mask" "B.Paste")
			(net "PV_VDDR")
			(options
				(clearance outline)
				(anchor circle)
			)
			(primitives
				(gr_poly
					(pts
						(arc
							(start -0.254 0.1778)
							(mid -0.239121 0.213721)
							(end -0.2032 0.2286)
						)
						(arc
							(start 0.2032 0.2286)
							(mid 0.239121 0.213721)
							(end 0.254 0.1778)
						)
						(arc
							(start 0.254 -0.1778)
							(mid 0.239121 -0.213721)
							(end 0.2032 -0.2286)
						)
						(arc
							(start -0.2032 -0.2286)
							(mid -0.239121 -0.213721)
							(end -0.254 -0.1778)
						)
					)
					(width 0)
					(fill yes)
				)
			)
		)
		(pad "2" smd custom
			(at 0 0.4572 180)
			(size 0.1143 0.1143)
			(layers "B.Cu" "B.Mask" "B.Paste")
			(net "GND")
			(options
				(clearance outline)
				(anchor circle)
			)
			(primitives
				(gr_poly
					(pts
						(arc
							(start -0.254 0.1778)
							(mid -0.239121 0.213721)
							(end -0.2032 0.2286)
						)
						(arc
							(start 0.2032 0.2286)
							(mid 0.239121 0.213721)
							(end 0.254 0.1778)
						)
						(arc
							(start 0.254 -0.1778)
							(mid 0.239121 -0.213721)
							(end 0.2032 -0.2286)
						)
						(arc
							(start -0.2032 -0.2286)
							(mid -0.239121 -0.213721)
							(end -0.254 -0.1778)
						)
					)
					(width 0)
					(fill yes)
				)
			)
		)
	)
	(footprint ""
		(layer "B.Cu")
		(at 94.615 -37.084 90)
		(property "Reference" "C187"
			(at 0 0 90)
			(layer "B.SilkS")
			(hide yes)
			(effects
				(font
					(size 1.27 1.27)
				)
				(justify mirror)
			)
		)
		(property "Value" "SC1U10V2KX-1GP"
			(at -1.1811 -2.7051 90)
			(unlocked yes)
			(layer "B.Fab")
			(hide yes)
			(effects
				(font
					(size 1.016 1.016)
					(thickness 0.1524)
				)
				(justify mirror)
			)
		)
		(property "Device Type" "C402H22"
			(at -1.1811 -4.2291 90)
			(unlocked yes)
			(layer "B.Fab")
			(hide yes)
			(effects
				(font
					(size 1.016 1.016)
					(thickness 0.1524)
				)
				(justify mirror)
			)
		)
		(duplicate_pad_numbers_are_jumpers no)
		(fp_rect
			(start 0.381 0.7366)
			(end -0.381 -0.7366)
			(stroke
				(width 0)
				(type default)
			)
			(fill no)
			(layer "B.CrtYd")
		)
		(fp_rect
			(start 0.381 0.7366)
			(end -0.381 -0.7366)
			(stroke
				(width 0)
				(type default)
			)
			(fill no)
			(layer "B.Fab")
		)
		(pad "1" smd custom
			(at 0 -0.4572 270)
			(size 0.1143 0.1143)
			(layers "B.Cu" "B.Mask" "B.Paste")
			(net "PVNN")
			(options
				(clearance outline)
				(anchor circle)
			)
			(primitives
				(gr_poly
					(pts
						(arc
							(start -0.254 0.1778)
							(mid -0.239121 0.213721)
							(end -0.2032 0.2286)
						)
						(arc
							(start 0.2032 0.2286)
							(mid 0.239121 0.213721)
							(end 0.254 0.1778)
						)
						(arc
							(start 0.254 -0.1778)
							(mid 0.239121 -0.213721)
							(end 0.2032 -0.2286)
						)
						(arc
							(start -0.2032 -0.2286)
							(mid -0.239121 -0.213721)
							(end -0.254 -0.1778)
						)
					)
					(width 0)
					(fill yes)
				)
			)
		)
		(pad "2" smd custom
			(at 0 0.4572 270)
			(size 0.1143 0.1143)
			(layers "B.Cu" "B.Mask" "B.Paste")
			(net "GND")
			(options
				(clearance outline)
				(anchor circle)
			)
			(primitives
				(gr_poly
					(pts
						(arc
							(start -0.254 0.1778)
							(mid -0.239121 0.213721)
							(end -0.2032 0.2286)
						)
						(arc
							(start 0.2032 0.2286)
							(mid 0.239121 0.213721)
							(end 0.254 0.1778)
						)
						(arc
							(start 0.254 -0.1778)
							(mid 0.239121 -0.213721)
							(end 0.2032 -0.2286)
						)
						(arc
							(start -0.2032 -0.2286)
							(mid -0.239121 -0.213721)
							(end -0.254 -0.1778)
						)
					)
					(width 0)
					(fill yes)
				)
			)
		)
	)
	(footprint ""
		(layer "B.Cu")
		(at 197.993 -43.434 -90)
		(property "Reference" "R156"
			(at 0 0 90)
			(layer "B.SilkS")
			(hide yes)
			(effects
				(font
					(size 1.27 1.27)
				)
				(justify mirror)
			)
		)
		(property "Value" "300R2F-GP"
			(at -0.064008 -3.993896 270)
			(unlocked yes)
			(layer "B.Fab")
			(hide yes)
			(effects
				(font
					(size 1.016 1.016)
					(thickness 0.1524)
				)
				(justify mirror)
			)
		)
		(property "Device Type" "R402H16"
			(at -0.064008 -5.517896 270)
			(unlocked yes)
			(layer "B.Fab")
			(hide yes)
			(effects
				(font
					(size 1.016 1.016)
					(thickness 0.1524)
				)
				(justify mirror)
			)
		)
		(duplicate_pad_numbers_are_jumpers no)
		(fp_rect
			(start 0.381 0.8382)
			(end -0.381 -0.8382)
			(stroke
				(width 0)
				(type default)
			)
			(fill no)
			(layer "B.CrtYd")
		)
		(fp_rect
			(start 0.381 0.8382)
			(end -0.381 -0.8382)
			(stroke
				(width 0)
				(type default)
			)
			(fill no)
			(layer "B.Fab")
		)
		(pad "1" smd custom
			(at 0 -0.4318 90)
			(size 0.127 0.127)
			(layers "B.Cu" "B.Mask" "B.Paste")
			(net "PORT80_R_BIT7")
			(options
				(clearance outline)
				(anchor circle)
			)
			(primitives
				(gr_poly
					(pts
						(arc
							(start -0.2032 0.2794)
							(mid -0.239121 0.264521)
							(end -0.254 0.2286)
						)
						(arc
							(start -0.254 -0.2286)
							(mid -0.239121 -0.264521)
							(end -0.2032 -0.2794)
						)
						(arc
							(start 0.2032 -0.2794)
							(mid 0.239121 -0.264521)
							(end 0.254 -0.2286)
						)
						(arc
							(start 0.254 0.2286)
							(mid 0.239121 0.264521)
							(end 0.2032 0.2794)
						)
					)
					(width 0)
					(fill yes)
				)
			)
		)
		(pad "2" smd custom
			(at 0 0.4318 90)
			(size 0.127 0.127)
			(layers "B.Cu" "B.Mask" "B.Paste")
			(net "P3V3_STBY")
			(options
				(clearance outline)
				(anchor circle)
			)
			(primitives
				(gr_poly
					(pts
						(arc
							(start -0.2032 0.2794)
							(mid -0.239121 0.264521)
							(end -0.254 0.2286)
						)
						(arc
							(start -0.254 -0.2286)
							(mid -0.239121 -0.264521)
							(end -0.2032 -0.2794)
						)
						(arc
							(start 0.2032 -0.2794)
							(mid 0.239121 -0.264521)
							(end 0.254 -0.2286)
						)
						(arc
							(start 0.254 0.2286)
							(mid 0.239121 0.264521)
							(end 0.2032 0.2794)
						)
					)
					(width 0)
					(fill yes)
				)
			)
		)
	)
	(footprint ""
		(layer "B.Cu")
		(at 69.088 -37.846 180)
		(property "Reference" "U15"
			(at 0 0 0)
			(layer "B.SilkS")
			(hide yes)
			(effects
				(font
					(size 1.27 1.27)
				)
				(justify mirror)
			)
		)
		(property "Value" "74LVC1G08GW-1-GP"
			(at 2.3368 -8.6868 180)
			(unlocked yes)
			(layer "B.Fab")
			(hide yes)
			(effects
				(font
					(size 1.016 1.016)
					(thickness 0.1524)
				)
				(justify mirror)
			)
		)
		(property "Device Type" "SC70-5H44"
			(at 2.3114 -10.414 180)
			(unlocked yes)
			(layer "B.Fab")
			(hide yes)
			(effects
				(font
					(size 1.016 1.016)
					(thickness 0.1524)
				)
				(justify mirror)
			)
		)
		(duplicate_pad_numbers_are_jumpers no)
		(fp_line
			(start 1.0033 0.3302)
			(end 1.0033 -0.3302)
			(stroke
				(width 0.1524)
				(type default)
			)
			(layer "B.SilkS")
		)
		(fp_line
			(start 1.0033 -0.3302)
			(end -1.0033 -0.3302)
			(stroke
				(width 0.1524)
				(type default)
			)
			(layer "B.SilkS")
		)
		(fp_line
			(start -1.0033 0.3302)
			(end 1.0033 0.3302)
			(stroke
				(width 0.1524)
				(type default)
			)
			(layer "B.SilkS")
		)
		(fp_line
			(start -1.0033 -0.3302)
			(end -1.0033 0.3302)
			(stroke
				(width 0.1524)
				(type default)
			)
			(layer "B.SilkS")
		)
		(fp_poly
			(pts
				(xy 1.0033 1.4859) (xy 1.0033 0.8001) (xy 1.1811 0.8001) (xy 1.1811 -0.8001) (xy 1.0033 -0.8001)
				(xy 1.0033 -1.4859) (xy -1.0033 -1.4859) (xy -1.0033 -0.8001) (xy -1.1811 -0.8001) (xy -1.1811 0.8001)
				(xy -1.0033 0.8001) (xy -1.0033 1.4859) (xy -0.2921 1.4859) (xy -0.2921 0.8001) (xy 0.2921 0.8001)
				(xy 0.2921 1.4859)
			)
			(stroke
				(width 0)
				(type default)
			)
			(fill no)
			(layer "B.CrtYd")
		)
		(fp_poly
			(pts
				(xy 1.0033 1.4859) (xy 1.0033 0.8001) (xy 1.1811 0.8001) (xy 1.1811 -0.8001) (xy 1.0033 -0.8001)
				(xy 1.0033 -1.4859) (xy -1.0033 -1.4859) (xy -1.0033 -0.8001) (xy -1.1811 -0.8001) (xy -1.1811 0.8001)
				(xy -1.0033 0.8001) (xy -1.0033 1.4859) (xy -0.2921 1.4859) (xy -0.2921 0.8001) (xy 0.2921 0.8001)
				(xy 0.2921 1.4859)
			)
			(stroke
				(width 0)
				(type default)
			)
			(fill no)
			(layer "B.Fab")
		)
		(pad "1" smd rect
			(at -0.65024 -0.93472)
			(size 0.3556 0.762)
			(layers "B.Cu" "B.Mask" "B.Paste")
			(net "PMU_SLP_INB_S3#")
		)
		(pad "2" smd rect
			(at 0 -0.93472)
			(size 0.3556 0.762)
			(layers "B.Cu" "B.Mask" "B.Paste")
			(net "PMU_SLP_INA_DDRVTT#")
		)
		(pad "3" smd rect
			(at 0.65024 -0.93472)
			(size 0.3556 0.762)
			(layers "B.Cu" "B.Mask" "B.Paste")
			(net "GND")
		)
		(pad "4" smd rect
			(at 0.65024 0.93472)
			(size 0.3556 0.762)
			(layers "B.Cu" "B.Mask" "B.Paste")
			(net "PVTT_DDR_EN")
		)
		(pad "5" smd rect
			(at -0.65024 0.93472)
			(size 0.3556 0.762)
			(layers "B.Cu" "B.Mask" "B.Paste")
			(net "P3V3_STBY")
		)
	)
	(footprint ""
		(layer "B.Cu")
		(at 6.604 -32.131)
		(property "Reference" "PR204"
			(at 0 0 0)
			(layer "B.SilkS")
			(hide yes)
			(effects
				(font
					(size 1.27 1.27)
				)
				(justify mirror)
			)
		)
		(property "Value" "475KR2F-GP"
			(at -1.7907 -1.1176 0)
			(unlocked yes)
			(layer "B.Fab")
			(hide yes)
			(effects
				(font
					(size 1.016 1.016)
					(thickness 0.1524)
				)
				(justify mirror)
			)
		)
		(property "Device Type" "R402H16"
			(at -1.7907 -2.6416 0)
			(unlocked yes)
			(layer "B.Fab")
			(hide yes)
			(effects
				(font
					(size 1.016 1.016)
					(thickness 0.1524)
				)
				(justify mirror)
			)
		)
		(duplicate_pad_numbers_are_jumpers no)
		(fp_rect
			(start 0.381 0.8382)
			(end -0.381 -0.8382)
			(stroke
				(width 0)
				(type default)
			)
			(fill no)
			(layer "B.CrtYd")
		)
		(fp_rect
			(start 0.381 0.8382)
			(end -0.381 -0.8382)
			(stroke
				(width 0)
				(type default)
			)
			(fill no)
			(layer "B.Fab")
		)
		(pad "1" smd custom
			(at 0 -0.4318 180)
			(size 0.127 0.127)
			(layers "B.Cu" "B.Mask" "B.Paste")
			(net "P3V3_STBY_MODE")
			(options
				(clearance outline)
				(anchor circle)
			)
			(primitives
				(gr_poly
					(pts
						(arc
							(start -0.2032 0.2794)
							(mid -0.239121 0.264521)
							(end -0.254 0.2286)
						)
						(arc
							(start -0.254 -0.2286)
							(mid -0.239121 -0.264521)
							(end -0.2032 -0.2794)
						)
						(arc
							(start 0.2032 -0.2794)
							(mid 0.239121 -0.264521)
							(end 0.254 -0.2286)
						)
						(arc
							(start 0.254 0.2286)
							(mid 0.239121 0.264521)
							(end 0.2032 0.2794)
						)
					)
					(width 0)
					(fill yes)
				)
			)
		)
		(pad "2" smd custom
			(at 0 0.4318 180)
			(size 0.127 0.127)
			(layers "B.Cu" "B.Mask" "B.Paste")
			(net "P3V3_STBY_PG")
			(options
				(clearance outline)
				(anchor circle)
			)
			(primitives
				(gr_poly
					(pts
						(arc
							(start -0.2032 0.2794)
							(mid -0.239121 0.264521)
							(end -0.254 0.2286)
						)
						(arc
							(start -0.254 -0.2286)
							(mid -0.239121 -0.264521)
							(end -0.2032 -0.2794)
						)
						(arc
							(start 0.2032 -0.2794)
							(mid 0.239121 -0.264521)
							(end 0.254 -0.2286)
						)
						(arc
							(start 0.254 0.2286)
							(mid 0.239121 0.264521)
							(end 0.2032 0.2794)
						)
					)
					(width 0)
					(fill yes)
				)
			)
		)
	)
	(footprint ""
		(layer "B.Cu")
		(at 189.357 -27.94 180)
		(property "Reference" "PR216"
			(at 0 0 0)
			(layer "B.SilkS")
			(hide yes)
			(effects
				(font
					(size 1.27 1.27)
				)
				(justify mirror)
			)
		)
		(property "Value" "10KR2F-2-GP"
			(at -1.7907 -1.1176 180)
			(unlocked yes)
			(layer "B.Fab")
			(hide yes)
			(effects
				(font
					(size 1.016 1.016)
					(thickness 0.1524)
				)
				(justify mirror)
			)
		)
		(property "Device Type" "R402H16"
			(at -1.7907 -2.6416 180)
			(unlocked yes)
			(layer "B.Fab")
			(hide yes)
			(effects
				(font
					(size 1.016 1.016)
					(thickness 0.1524)
				)
				(justify mirror)
			)
		)
		(duplicate_pad_numbers_are_jumpers no)
		(fp_rect
			(start 0.381 0.8382)
			(end -0.381 -0.8382)
			(stroke
				(width 0)
				(type default)
			)
			(fill no)
			(layer "B.CrtYd")
		)
		(fp_rect
			(start 0.381 0.8382)
			(end -0.381 -0.8382)
			(stroke
				(width 0)
				(type default)
			)
			(fill no)
			(layer "B.Fab")
		)
		(pad "1" smd custom
			(at 0 -0.4318)
			(size 0.127 0.127)
			(layers "B.Cu" "B.Mask" "B.Paste")
			(net "VR_PVDDRA_ISUMP1_R")
			(options
				(clearance outline)
				(anchor circle)
			)
			(primitives
				(gr_poly
					(pts
						(arc
							(start -0.2032 0.2794)
							(mid -0.239121 0.264521)
							(end -0.254 0.2286)
						)
						(arc
							(start -0.254 -0.2286)
							(mid -0.239121 -0.264521)
							(end -0.2032 -0.2794)
						)
						(arc
							(start 0.2032 -0.2794)
							(mid 0.239121 -0.264521)
							(end 0.254 -0.2286)
						)
						(arc
							(start 0.254 0.2286)
							(mid 0.239121 0.264521)
							(end 0.2032 0.2794)
						)
					)
					(width 0)
					(fill yes)
				)
			)
		)
		(pad "2" smd custom
			(at 0 0.4318)
			(size 0.127 0.127)
			(layers "B.Cu" "B.Mask" "B.Paste")
			(net "VR_PVDDRA_ISUMN1")
			(options
				(clearance outline)
				(anchor circle)
			)
			(primitives
				(gr_poly
					(pts
						(arc
							(start -0.2032 0.2794)
							(mid -0.239121 0.264521)
							(end -0.254 0.2286)
						)
						(arc
							(start -0.254 -0.2286)
							(mid -0.239121 -0.264521)
							(end -0.2032 -0.2794)
						)
						(arc
							(start 0.2032 -0.2794)
							(mid 0.239121 -0.264521)
							(end 0.254 -0.2286)
						)
						(arc
							(start 0.254 0.2286)
							(mid 0.239121 0.264521)
							(end 0.2032 0.2794)
						)
					)
					(width 0)
					(fill yes)
				)
			)
		)
	)
	(footprint ""
		(layer "B.Cu")
		(at 46.1264 -28.321)
		(property "Reference" "R438"
			(at 0 0 0)
			(layer "B.SilkS")
			(hide yes)
			(effects
				(font
					(size 1.27 1.27)
				)
				(justify mirror)
			)
		)
		(property "Value" "4K7R2F-GP"
			(at -1.7907 -1.1176 0)
			(unlocked yes)
			(layer "B.Fab")
			(hide yes)
			(effects
				(font
					(size 1.016 1.016)
					(thickness 0.1524)
				)
				(justify mirror)
			)
		)
		(property "Device Type" "R402H16"
			(at -1.7907 -2.6416 0)
			(unlocked yes)
			(layer "B.Fab")
			(hide yes)
			(effects
				(font
					(size 1.016 1.016)
					(thickness 0.1524)
				)
				(justify mirror)
			)
		)
		(duplicate_pad_numbers_are_jumpers no)
		(fp_rect
			(start 0.381 0.8382)
			(end -0.381 -0.8382)
			(stroke
				(width 0)
				(type default)
			)
			(fill no)
			(layer "B.CrtYd")
		)
		(fp_rect
			(start 0.381 0.8382)
			(end -0.381 -0.8382)
			(stroke
				(width 0)
				(type default)
			)
			(fill no)
			(layer "B.Fab")
		)
		(pad "1" smd custom
			(at 0 -0.4318 180)
			(size 0.127 0.127)
			(layers "B.Cu" "B.Mask" "B.Paste")
			(net "P3V3")
			(options
				(clearance outline)
				(anchor circle)
			)
			(primitives
				(gr_poly
					(pts
						(arc
							(start -0.2032 0.2794)
							(mid -0.239121 0.264521)
							(end -0.254 0.2286)
						)
						(arc
							(start -0.254 -0.2286)
							(mid -0.239121 -0.264521)
							(end -0.2032 -0.2794)
						)
						(arc
							(start 0.2032 -0.2794)
							(mid 0.239121 -0.264521)
							(end 0.254 -0.2286)
						)
						(arc
							(start 0.254 0.2286)
							(mid 0.239121 0.264521)
							(end 0.2032 0.2794)
						)
					)
					(width 0)
					(fill yes)
				)
			)
		)
		(pad "2" smd custom
			(at 0 0.4318 180)
			(size 0.127 0.127)
			(layers "B.Cu" "B.Mask" "B.Paste")
			(net "CLKBUFF_OE6#")
			(options
				(clearance outline)
				(anchor circle)
			)
			(primitives
				(gr_poly
					(pts
						(arc
							(start -0.2032 0.2794)
							(mid -0.239121 0.264521)
							(end -0.254 0.2286)
						)
						(arc
							(start -0.254 -0.2286)
							(mid -0.239121 -0.264521)
							(end -0.2032 -0.2794)
						)
						(arc
							(start 0.2032 -0.2794)
							(mid 0.239121 -0.264521)
							(end 0.254 -0.2286)
						)
						(arc
							(start 0.254 0.2286)
							(mid 0.239121 0.264521)
							(end 0.2032 0.2794)
						)
					)
					(width 0)
					(fill yes)
				)
			)
		)
	)
	(footprint ""
		(layer "B.Cu")
		(at 130.81 -25.273 180)
		(property "Reference" "Q2"
			(at 0 0 0)
			(layer "B.SilkS")
			(hide yes)
			(effects
				(font
					(size 1.27 1.27)
				)
				(justify mirror)
			)
		)
		(property "Value" "MMBT3904TT1G-GP"
			(at 0 -9.7282 180)
			(unlocked yes)
			(layer "B.Fab")
			(hide yes)
			(effects
				(font
					(size 1.016 1.016)
					(thickness 0.1524)
				)
				(justify mirror)
			)
		)
		(property "Device Type" "SC75CBE1D6H36"
			(at 0 -11.6332 180)
			(unlocked yes)
			(layer "B.Fab")
			(hide yes)
			(effects
				(font
					(size 1.016 1.016)
					(thickness 0.1524)
				)
				(justify mirror)
			)
		)
		(duplicate_pad_numbers_are_jumpers no)
		(fp_poly
			(pts
				(xy -0.381 -1.1938) (xy 0.381 -1.1938) (xy 0.381 -0.6604) (xy 1.0541 -0.6604) (xy 1.0541 0.6604)
				(xy 0.889 0.6604) (xy 0.889 1.1938) (xy -0.889 1.1938) (xy -0.889 0.6604) (xy -1.0541 0.6604) (xy -1.0541 -0.6604)
				(xy -0.381 -0.6604)
			)
			(stroke
				(width 0)
				(type default)
			)
			(fill no)
			(layer "B.CrtYd")
		)
		(fp_poly
			(pts
				(xy -0.381 -1.1938) (xy 0.381 -1.1938) (xy 0.381 -0.6604) (xy 1.0541 -0.6604) (xy 1.0541 0.6604)
				(xy 0.889 0.6604) (xy 0.889 1.1938) (xy -0.889 1.1938) (xy -0.889 0.6604) (xy -1.0541 0.6604) (xy -1.0541 -0.6604)
				(xy -0.381 -0.6604)
			)
			(stroke
				(width 0)
				(type default)
			)
			(fill no)
			(layer "B.Fab")
		)
		(pad "B" smd custom
			(at 0.508 0.6604)
			(size 0.127 0.127)
			(layers "B.Cu" "B.Mask" "B.Paste")
			(net "H_THERMTRIP_N_R")
			(options
				(clearance outline)
				(anchor circle)
			)
			(primitives
				(gr_poly
					(pts
						(arc
							(start -0.0508 -0.4064)
							(mid -0.194484 -0.346884)
							(end -0.254 -0.2032)
						)
						(arc
							(start -0.254 0.2032)
							(mid -0.194484 0.346884)
							(end -0.0508 0.4064)
						)
						(arc
							(start 0.0508 0.4064)
							(mid 0.194484 0.346884)
							(end 0.254 0.2032)
						)
						(arc
							(start 0.254 -0.2032)
							(mid 0.194484 -0.346884)
							(end 0.0508 -0.4064)
						)
					)
					(width 0)
					(fill yes)
				)
			)
		)
		(pad "C" smd custom
			(at 0 -0.6604)
			(size 0.127 0.127)
			(layers "B.Cu" "B.Mask" "B.Paste")
			(net "CPU_THERMTRIP_LVC#")
			(options
				(clearance outline)
				(anchor circle)
			)
			(primitives
				(gr_poly
					(pts
						(arc
							(start -0.0508 -0.4064)
							(mid -0.194484 -0.346884)
							(end -0.254 -0.2032)
						)
						(arc
							(start -0.254 0.2032)
							(mid -0.194484 0.346884)
							(end -0.0508 0.4064)
						)
						(arc
							(start 0.0508 0.4064)
							(mid 0.194484 0.346884)
							(end 0.254 0.2032)
						)
						(arc
							(start 0.254 -0.2032)
							(mid 0.194484 -0.346884)
							(end 0.0508 -0.4064)
						)
					)
					(width 0)
					(fill yes)
				)
			)
		)
		(pad "E" smd custom
			(at -0.508 0.6604)
			(size 0.127 0.127)
			(layers "B.Cu" "B.Mask" "B.Paste")
			(net "CPU_THERMTRIP#")
			(options
				(clearance outline)
				(anchor circle)
			)
			(primitives
				(gr_poly
					(pts
						(arc
							(start -0.0508 -0.4064)
							(mid -0.194484 -0.346884)
							(end -0.254 -0.2032)
						)
						(arc
							(start -0.254 0.2032)
							(mid -0.194484 0.346884)
							(end -0.0508 0.4064)
						)
						(arc
							(start 0.0508 0.4064)
							(mid 0.194484 0.346884)
							(end 0.254 0.2032)
						)
						(arc
							(start 0.254 -0.2032)
							(mid 0.194484 -0.346884)
							(end 0.0508 -0.4064)
						)
					)
					(width 0)
					(fill yes)
				)
			)
		)
	)
	(footprint ""
		(layer "B.Cu")
		(at 20.193 -12.7)
		(property "Reference" "C287"
			(at 0 0 0)
			(layer "B.SilkS")
			(hide yes)
			(effects
				(font
					(size 1.27 1.27)
				)
				(justify mirror)
			)
		)
		(property "Value" "SCD1U16V2KX-3GP"
			(at -1.1811 -2.7051 0)
			(unlocked yes)
			(layer "B.Fab")
			(hide yes)
			(effects
				(font
					(size 1.016 1.016)
					(thickness 0.1524)
				)
				(justify mirror)
			)
		)
		(property "Device Type" "C402H22"
			(at -1.1811 -4.2291 0)
			(unlocked yes)
			(layer "B.Fab")
			(hide yes)
			(effects
				(font
					(size 1.016 1.016)
					(thickness 0.1524)
				)
				(justify mirror)
			)
		)
		(duplicate_pad_numbers_are_jumpers no)
		(fp_rect
			(start 0.381 0.7366)
			(end -0.381 -0.7366)
			(stroke
				(width 0)
				(type default)
			)
			(fill no)
			(layer "B.CrtYd")
		)
		(fp_rect
			(start 0.381 0.7366)
			(end -0.381 -0.7366)
			(stroke
				(width 0)
				(type default)
			)
			(fill no)
			(layer "B.Fab")
		)
		(pad "1" smd custom
			(at 0 -0.4572 180)
			(size 0.1143 0.1143)
			(layers "B.Cu" "B.Mask" "B.Paste")
			(net "P2E_CPU_ETH10G_C_TX_DN11")
			(options
				(clearance outline)
				(anchor circle)
			)
			(primitives
				(gr_poly
					(pts
						(arc
							(start -0.254 0.1778)
							(mid -0.239121 0.213721)
							(end -0.2032 0.2286)
						)
						(arc
							(start 0.2032 0.2286)
							(mid 0.239121 0.213721)
							(end 0.254 0.1778)
						)
						(arc
							(start 0.254 -0.1778)
							(mid 0.239121 -0.213721)
							(end 0.2032 -0.2286)
						)
						(arc
							(start -0.2032 -0.2286)
							(mid -0.239121 -0.213721)
							(end -0.254 -0.1778)
						)
					)
					(width 0)
					(fill yes)
				)
			)
		)
		(pad "2" smd custom
			(at 0 0.4572 180)
			(size 0.1143 0.1143)
			(layers "B.Cu" "B.Mask" "B.Paste")
			(net "P2E_CPU_ETH10G_TX_DN11")
			(options
				(clearance outline)
				(anchor circle)
			)
			(primitives
				(gr_poly
					(pts
						(arc
							(start -0.254 0.1778)
							(mid -0.239121 0.213721)
							(end -0.2032 0.2286)
						)
						(arc
							(start 0.2032 0.2286)
							(mid 0.239121 0.213721)
							(end 0.254 0.1778)
						)
						(arc
							(start 0.254 -0.1778)
							(mid 0.239121 -0.213721)
							(end 0.2032 -0.2286)
						)
						(arc
							(start -0.2032 -0.2286)
							(mid -0.239121 -0.213721)
							(end -0.254 -0.1778)
						)
					)
					(width 0)
					(fill yes)
				)
			)
		)
	)
	(footprint ""
		(layer "B.Cu")
		(at 144.399 -44.704 -90)
		(property "Reference" "R493"
			(at 0 0 90)
			(layer "B.SilkS")
			(hide yes)
			(effects
				(font
					(size 1.27 1.27)
				)
				(justify mirror)
			)
		)
		(property "Value" "1KR2F-3-GP"
			(at -1.7907 -1.1176 270)
			(unlocked yes)
			(layer "B.Fab")
			(hide yes)
			(effects
				(font
					(size 1.016 1.016)
					(thickness 0.1524)
				)
				(justify mirror)
			)
		)
		(property "Device Type" "R402H16"
			(at -1.7907 -2.6416 270)
			(unlocked yes)
			(layer "B.Fab")
			(hide yes)
			(effects
				(font
					(size 1.016 1.016)
					(thickness 0.1524)
				)
				(justify mirror)
			)
		)
		(duplicate_pad_numbers_are_jumpers no)
		(fp_rect
			(start 0.381 0.8382)
			(end -0.381 -0.8382)
			(stroke
				(width 0)
				(type default)
			)
			(fill no)
			(layer "B.CrtYd")
		)
		(fp_rect
			(start 0.381 0.8382)
			(end -0.381 -0.8382)
			(stroke
				(width 0)
				(type default)
			)
			(fill no)
			(layer "B.Fab")
		)
		(pad "1" smd custom
			(at 0 -0.4318 90)
			(size 0.127 0.127)
			(layers "B.Cu" "B.Mask" "B.Paste")
			(net "JTAG_PLD_TDI")
			(options
				(clearance outline)
				(anchor circle)
			)
			(primitives
				(gr_poly
					(pts
						(arc
							(start -0.2032 0.2794)
							(mid -0.239121 0.264521)
							(end -0.254 0.2286)
						)
						(arc
							(start -0.254 -0.2286)
							(mid -0.239121 -0.264521)
							(end -0.2032 -0.2794)
						)
						(arc
							(start 0.2032 -0.2794)
							(mid 0.239121 -0.264521)
							(end 0.254 -0.2286)
						)
						(arc
							(start 0.254 0.2286)
							(mid 0.239121 0.264521)
							(end 0.2032 0.2794)
						)
					)
					(width 0)
					(fill yes)
				)
			)
		)
		(pad "2" smd custom
			(at 0 0.4318 90)
			(size 0.127 0.127)
			(layers "B.Cu" "B.Mask" "B.Paste")
			(net "GND")
			(options
				(clearance outline)
				(anchor circle)
			)
			(primitives
				(gr_poly
					(pts
						(arc
							(start -0.2032 0.2794)
							(mid -0.239121 0.264521)
							(end -0.254 0.2286)
						)
						(arc
							(start -0.254 -0.2286)
							(mid -0.239121 -0.264521)
							(end -0.2032 -0.2794)
						)
						(arc
							(start 0.2032 -0.2794)
							(mid 0.239121 -0.264521)
							(end 0.254 -0.2286)
						)
						(arc
							(start 0.254 0.2286)
							(mid 0.239121 0.264521)
							(end 0.2032 0.2794)
						)
					)
					(width 0)
					(fill yes)
				)
			)
		)
	)
	(footprint ""
		(layer "B.Cu")
		(at 204.3176 -42.3418 90)
		(property "Reference" "C349"
			(at 0 0 90)
			(layer "B.SilkS")
			(hide yes)
			(effects
				(font
					(size 1.27 1.27)
				)
				(justify mirror)
			)
		)
		(property "Value" "SCD1U16V2KX-3GP"
			(at -1.8923 -1.2065 90)
			(unlocked yes)
			(layer "B.Fab")
			(hide yes)
			(effects
				(font
					(size 1.016 1.016)
					(thickness 0.1524)
				)
				(justify mirror)
			)
		)
		(property "Device Type" "C402H22"
			(at -1.8923 -2.7305 90)
			(unlocked yes)
			(layer "B.Fab")
			(hide yes)
			(effects
				(font
					(size 1.016 1.016)
					(thickness 0.1524)
				)
				(justify mirror)
			)
		)
		(duplicate_pad_numbers_are_jumpers no)
		(fp_rect
			(start 0.381 0.7366)
			(end -0.381 -0.7366)
			(stroke
				(width 0)
				(type default)
			)
			(fill no)
			(layer "B.CrtYd")
		)
		(fp_rect
			(start 0.381 0.7366)
			(end -0.381 -0.7366)
			(stroke
				(width 0)
				(type default)
			)
			(fill no)
			(layer "B.Fab")
		)
		(pad "1" smd custom
			(at 0 -0.4572 270)
			(size 0.1143 0.1143)
			(layers "B.Cu" "B.Mask" "B.Paste")
			(net "PV_VDDR")
			(options
				(clearance outline)
				(anchor circle)
			)
			(primitives
				(gr_poly
					(pts
						(arc
							(start -0.254 0.1778)
							(mid -0.239121 0.213721)
							(end -0.2032 0.2286)
						)
						(arc
							(start 0.2032 0.2286)
							(mid 0.239121 0.213721)
							(end 0.254 0.1778)
						)
						(arc
							(start 0.254 -0.1778)
							(mid 0.239121 -0.213721)
							(end 0.2032 -0.2286)
						)
						(arc
							(start -0.2032 -0.2286)
							(mid -0.239121 -0.213721)
							(end -0.254 -0.1778)
						)
					)
					(width 0)
					(fill yes)
				)
			)
		)
		(pad "2" smd custom
			(at 0 0.4572 270)
			(size 0.1143 0.1143)
			(layers "B.Cu" "B.Mask" "B.Paste")
			(net "GND")
			(options
				(clearance outline)
				(anchor circle)
			)
			(primitives
				(gr_poly
					(pts
						(arc
							(start -0.254 0.1778)
							(mid -0.239121 0.213721)
							(end -0.2032 0.2286)
						)
						(arc
							(start 0.2032 0.2286)
							(mid 0.239121 0.213721)
							(end 0.254 0.1778)
						)
						(arc
							(start 0.254 -0.1778)
							(mid 0.239121 -0.213721)
							(end 0.2032 -0.2286)
						)
						(arc
							(start -0.2032 -0.2286)
							(mid -0.239121 -0.213721)
							(end -0.254 -0.1778)
						)
					)
					(width 0)
					(fill yes)
				)
			)
		)
	)
	(footprint ""
		(layer "B.Cu")
		(at 15.875 -64.643 90)
		(property "Reference" "C30"
			(at 0 0 90)
			(layer "B.SilkS")
			(hide yes)
			(effects
				(font
					(size 1.27 1.27)
				)
				(justify mirror)
			)
		)
		(property "Value" "SC1U6D3V2KX-GP"
			(at -1.8923 -1.2065 90)
			(unlocked yes)
			(layer "B.Fab")
			(hide yes)
			(effects
				(font
					(size 1.016 1.016)
					(thickness 0.1524)
				)
				(justify mirror)
			)
		)
		(property "Device Type" "C402H22"
			(at -1.8923 -2.7305 90)
			(unlocked yes)
			(layer "B.Fab")
			(hide yes)
			(effects
				(font
					(size 1.016 1.016)
					(thickness 0.1524)
				)
				(justify mirror)
			)
		)
		(duplicate_pad_numbers_are_jumpers no)
		(fp_rect
			(start 0.381 0.7366)
			(end -0.381 -0.7366)
			(stroke
				(width 0)
				(type default)
			)
			(fill no)
			(layer "B.CrtYd")
		)
		(fp_rect
			(start 0.381 0.7366)
			(end -0.381 -0.7366)
			(stroke
				(width 0)
				(type default)
			)
			(fill no)
			(layer "B.Fab")
		)
		(pad "1" smd custom
			(at 0 -0.4572 270)
			(size 0.1143 0.1143)
			(layers "B.Cu" "B.Mask" "B.Paste")
			(net "P3V3")
			(options
				(clearance outline)
				(anchor circle)
			)
			(primitives
				(gr_poly
					(pts
						(arc
							(start -0.254 0.1778)
							(mid -0.239121 0.213721)
							(end -0.2032 0.2286)
						)
						(arc
							(start 0.2032 0.2286)
							(mid 0.239121 0.213721)
							(end 0.254 0.1778)
						)
						(arc
							(start 0.254 -0.1778)
							(mid 0.239121 -0.213721)
							(end 0.2032 -0.2286)
						)
						(arc
							(start -0.2032 -0.2286)
							(mid -0.239121 -0.213721)
							(end -0.254 -0.1778)
						)
					)
					(width 0)
					(fill yes)
				)
			)
		)
		(pad "2" smd custom
			(at 0 0.4572 270)
			(size 0.1143 0.1143)
			(layers "B.Cu" "B.Mask" "B.Paste")
			(net "GND")
			(options
				(clearance outline)
				(anchor circle)
			)
			(primitives
				(gr_poly
					(pts
						(arc
							(start -0.254 0.1778)
							(mid -0.239121 0.213721)
							(end -0.2032 0.2286)
						)
						(arc
							(start 0.2032 0.2286)
							(mid 0.239121 0.213721)
							(end 0.254 0.1778)
						)
						(arc
							(start 0.254 -0.1778)
							(mid 0.239121 -0.213721)
							(end 0.2032 -0.2286)
						)
						(arc
							(start -0.2032 -0.2286)
							(mid -0.239121 -0.213721)
							(end -0.254 -0.1778)
						)
					)
					(width 0)
					(fill yes)
				)
			)
		)
	)
	(footprint ""
		(layer "B.Cu")
		(at 29.464 -12.7)
		(property "Reference" "C271"
			(at 0 0 0)
			(layer "B.SilkS")
			(hide yes)
			(effects
				(font
					(size 1.27 1.27)
				)
				(justify mirror)
			)
		)
		(property "Value" "SCD1U16V2KX-3GP"
			(at -1.1811 -2.7051 0)
			(unlocked yes)
			(layer "B.Fab")
			(hide yes)
			(effects
				(font
					(size 1.016 1.016)
					(thickness 0.1524)
				)
				(justify mirror)
			)
		)
		(property "Device Type" "C402H22"
			(at -1.1811 -4.2291 0)
			(unlocked yes)
			(layer "B.Fab")
			(hide yes)
			(effects
				(font
					(size 1.016 1.016)
					(thickness 0.1524)
				)
				(justify mirror)
			)
		)
		(duplicate_pad_numbers_are_jumpers no)
		(fp_rect
			(start 0.381 0.7366)
			(end -0.381 -0.7366)
			(stroke
				(width 0)
				(type default)
			)
			(fill no)
			(layer "B.CrtYd")
		)
		(fp_rect
			(start 0.381 0.7366)
			(end -0.381 -0.7366)
			(stroke
				(width 0)
				(type default)
			)
			(fill no)
			(layer "B.Fab")
		)
		(pad "1" smd custom
			(at 0 -0.4572 180)
			(size 0.1143 0.1143)
			(layers "B.Cu" "B.Mask" "B.Paste")
			(net "P2E_CPU_ETH10G_C_TX_DN8")
			(options
				(clearance outline)
				(anchor circle)
			)
			(primitives
				(gr_poly
					(pts
						(arc
							(start -0.254 0.1778)
							(mid -0.239121 0.213721)
							(end -0.2032 0.2286)
						)
						(arc
							(start 0.2032 0.2286)
							(mid 0.239121 0.213721)
							(end 0.254 0.1778)
						)
						(arc
							(start 0.254 -0.1778)
							(mid 0.239121 -0.213721)
							(end 0.2032 -0.2286)
						)
						(arc
							(start -0.2032 -0.2286)
							(mid -0.239121 -0.213721)
							(end -0.254 -0.1778)
						)
					)
					(width 0)
					(fill yes)
				)
			)
		)
		(pad "2" smd custom
			(at 0 0.4572 180)
			(size 0.1143 0.1143)
			(layers "B.Cu" "B.Mask" "B.Paste")
			(net "P2E_CPU_ETH10G_TX_DN8")
			(options
				(clearance outline)
				(anchor circle)
			)
			(primitives
				(gr_poly
					(pts
						(arc
							(start -0.254 0.1778)
							(mid -0.239121 0.213721)
							(end -0.2032 0.2286)
						)
						(arc
							(start 0.2032 0.2286)
							(mid 0.239121 0.213721)
							(end 0.254 0.1778)
						)
						(arc
							(start 0.254 -0.1778)
							(mid 0.239121 -0.213721)
							(end 0.2032 -0.2286)
						)
						(arc
							(start -0.2032 -0.2286)
							(mid -0.239121 -0.213721)
							(end -0.254 -0.1778)
						)
					)
					(width 0)
					(fill yes)
				)
			)
		)
	)
	(footprint ""
		(layer "B.Cu")
		(at 203.4794 -60.706 90)
		(property "Reference" "PC155"
			(at 0 0 90)
			(layer "B.SilkS")
			(hide yes)
			(effects
				(font
					(size 1.27 1.27)
				)
				(justify mirror)
			)
		)
		(property "Value" "SC22U6D3V5MX-2GP"
			(at 0 -4.9022 90)
			(unlocked yes)
			(layer "B.Fab")
			(hide yes)
			(effects
				(font
					(size 1.016 1.016)
					(thickness 0.1524)
				)
				(justify mirror)
			)
		)
		(property "Device Type" "C805H58"
			(at 0 -6.8072 90)
			(unlocked yes)
			(layer "B.Fab")
			(hide yes)
			(effects
				(font
					(size 1.016 1.016)
					(thickness 0.1524)
				)
				(justify mirror)
			)
		)
		(duplicate_pad_numbers_are_jumpers no)
		(fp_line
			(start -0.6096 0)
			(end 0.6096 0)
			(stroke
				(width 0.3048)
				(type default)
			)
			(layer "B.SilkS")
		)
		(fp_poly
			(pts
				(xy 0.9017 1.4351) (xy -0.9017 1.4351) (xy -0.9017 -1.4351) (xy 0.9017 -1.4351)
			)
			(stroke
				(width 0)
				(type default)
			)
			(fill no)
			(layer "B.CrtYd")
		)
		(fp_poly
			(pts
				(xy -0.9017 1.4351) (xy -0.9017 -1.4351) (xy 0.9017 -1.4351) (xy 0.9017 1.4351)
			)
			(stroke
				(width 0)
				(type default)
			)
			(fill no)
			(layer "B.Fab")
		)
		(pad "1" smd rect
			(at 0 -0.8382 270)
			(size 1.5494 0.9398)
			(layers "B.Cu" "B.Mask" "B.Paste")
			(net "PV_VDDR")
		)
		(pad "2" smd rect
			(at 0 0.8382 270)
			(size 1.5494 0.9398)
			(layers "B.Cu" "B.Mask" "B.Paste")
			(net "GND")
		)
	)
	(footprint ""
		(layer "B.Cu")
		(at 156.9212 -59.6646)
		(property "Reference" "C99"
			(at 0 0 0)
			(layer "B.SilkS")
			(hide yes)
			(effects
				(font
					(size 1.27 1.27)
				)
				(justify mirror)
			)
		)
		(property "Value" "SC1U10V2KX-1GP"
			(at -1.8923 -1.2065 0)
			(unlocked yes)
			(layer "B.Fab")
			(hide yes)
			(effects
				(font
					(size 1.016 1.016)
					(thickness 0.1524)
				)
				(justify mirror)
			)
		)
		(property "Device Type" "C402H22"
			(at -1.8923 -2.7305 0)
			(unlocked yes)
			(layer "B.Fab")
			(hide yes)
			(effects
				(font
					(size 1.016 1.016)
					(thickness 0.1524)
				)
				(justify mirror)
			)
		)
		(duplicate_pad_numbers_are_jumpers no)
		(fp_rect
			(start 0.381 0.7366)
			(end -0.381 -0.7366)
			(stroke
				(width 0)
				(type default)
			)
			(fill no)
			(layer "B.CrtYd")
		)
		(fp_rect
			(start 0.381 0.7366)
			(end -0.381 -0.7366)
			(stroke
				(width 0)
				(type default)
			)
			(fill no)
			(layer "B.Fab")
		)
		(pad "1" smd custom
			(at 0 -0.4572 180)
			(size 0.1143 0.1143)
			(layers "B.Cu" "B.Mask" "B.Paste")
			(net "PV_VDDR")
			(options
				(clearance outline)
				(anchor circle)
			)
			(primitives
				(gr_poly
					(pts
						(arc
							(start -0.254 0.1778)
							(mid -0.239121 0.213721)
							(end -0.2032 0.2286)
						)
						(arc
							(start 0.2032 0.2286)
							(mid 0.239121 0.213721)
							(end 0.254 0.1778)
						)
						(arc
							(start 0.254 -0.1778)
							(mid 0.239121 -0.213721)
							(end 0.2032 -0.2286)
						)
						(arc
							(start -0.2032 -0.2286)
							(mid -0.239121 -0.213721)
							(end -0.254 -0.1778)
						)
					)
					(width 0)
					(fill yes)
				)
			)
		)
		(pad "2" smd custom
			(at 0 0.4572 180)
			(size 0.1143 0.1143)
			(layers "B.Cu" "B.Mask" "B.Paste")
			(net "GND")
			(options
				(clearance outline)
				(anchor circle)
			)
			(primitives
				(gr_poly
					(pts
						(arc
							(start -0.254 0.1778)
							(mid -0.239121 0.213721)
							(end -0.2032 0.2286)
						)
						(arc
							(start 0.2032 0.2286)
							(mid 0.239121 0.213721)
							(end 0.254 0.1778)
						)
						(arc
							(start 0.254 -0.1778)
							(mid 0.239121 -0.213721)
							(end 0.2032 -0.2286)
						)
						(arc
							(start -0.2032 -0.2286)
							(mid -0.239121 -0.213721)
							(end -0.254 -0.1778)
						)
					)
					(width 0)
					(fill yes)
				)
			)
		)
	)
	(footprint ""
		(layer "B.Cu")
		(at 197.104 -70.104 -90)
		(property "Reference" "Q13"
			(at 0 0 90)
			(layer "B.SilkS")
			(hide yes)
			(effects
				(font
					(size 1.27 1.27)
				)
				(justify mirror)
			)
		)
		(property "Value" "2N7002A-7-GP"
			(at 4.3561 -5.7912 270)
			(unlocked yes)
			(layer "B.Fab")
			(hide yes)
			(effects
				(font
					(size 1.016 1.016)
					(thickness 0.1524)
				)
				(justify mirror)
			)
		)
		(property "Device Type" "SOT23DGS2D4H48"
			(at 4.3561 -7.3152 270)
			(unlocked yes)
			(layer "B.Fab")
			(hide yes)
			(effects
				(font
					(size 1.016 1.016)
					(thickness 0.1524)
				)
				(justify mirror)
			)
		)
		(duplicate_pad_numbers_are_jumpers no)
		(fp_line
			(start -1.7145 0.4445)
			(end -1.7145 -0.4445)
			(stroke
				(width 0.1524)
				(type default)
			)
			(layer "B.SilkS")
		)
		(fp_line
			(start 1.7145 0.4445)
			(end -1.7145 0.4445)
			(stroke
				(width 0.1524)
				(type default)
			)
			(layer "B.SilkS")
		)
		(fp_line
			(start -1.7145 -0.4445)
			(end 1.7145 -0.4445)
			(stroke
				(width 0.1524)
				(type default)
			)
			(layer "B.SilkS")
		)
		(fp_line
			(start 1.7145 -0.4445)
			(end 1.7145 0.4445)
			(stroke
				(width 0.1524)
				(type default)
			)
			(layer "B.SilkS")
		)
		(fp_poly
			(pts
				(xy 1.4224 1.5621) (xy 1.4224 0.9017) (xy 1.7145 0.9017) (xy 1.7145 -0.9017) (xy 0.4699 -0.9017)
				(xy 0.4699 -1.5621) (xy -0.4699 -1.5621) (xy -0.4699 -0.9017) (xy -1.7145 -0.9017) (xy -1.7145 0.9017)
				(xy -1.4224 0.9017) (xy -1.4224 1.5621) (xy -0.4826 1.5621) (xy -0.4826 0.9017) (xy 0.4826 0.9017)
				(xy 0.4826 1.5621)
			)
			(stroke
				(width 0)
				(type default)
			)
			(fill no)
			(layer "B.CrtYd")
		)
		(fp_poly
			(pts
				(xy 1.4224 1.5621) (xy 1.4224 0.9017) (xy 1.7145 0.9017) (xy 1.7145 -0.9017) (xy 0.4699 -0.9017)
				(xy 0.4699 -1.5621) (xy -0.4699 -1.5621) (xy -0.4699 -0.9017) (xy -1.7145 -0.9017) (xy -1.7145 0.9017)
				(xy -1.4224 0.9017) (xy -1.4224 1.5621) (xy -0.4826 1.5621) (xy -0.4826 0.9017) (xy 0.4826 0.9017)
				(xy 0.4826 1.5621)
			)
			(stroke
				(width 0)
				(type default)
			)
			(fill no)
			(layer "B.Fab")
		)
		(pad "D" smd custom
			(at 0 -1.069086 90)
			(size 0.17145 0.17145)
			(layers "B.Cu" "B.Mask" "B.Paste")
			(net "PWR_STATUS_LED_D")
			(options
				(clearance outline)
				(anchor circle)
			)
			(primitives
				(gr_poly
					(pts
						(arc
							(start -0.1397 -0.3683)
							(mid -0.283384 -0.308784)
							(end -0.3429 -0.1651)
						)
						(arc
							(start -0.3429 0.1651)
							(mid -0.283384 0.308784)
							(end -0.1397 0.3683)
						)
						(arc
							(start 0.1397 0.3683)
							(mid 0.283384 0.308784)
							(end 0.3429 0.1651)
						)
						(arc
							(start 0.3429 -0.1651)
							(mid 0.283384 -0.308784)
							(end 0.1397 -0.3683)
						)
					)
					(width 0)
					(fill yes)
				)
			)
		)
		(pad "G" smd custom
			(at 0.94996 1.069086 90)
			(size 0.17145 0.17145)
			(layers "B.Cu" "B.Mask" "B.Paste")
			(net "PWR_STATUS_LED_EN")
			(options
				(clearance outline)
				(anchor circle)
			)
			(primitives
				(gr_poly
					(pts
						(arc
							(start -0.1397 -0.3683)
							(mid -0.283384 -0.308784)
							(end -0.3429 -0.1651)
						)
						(arc
							(start -0.3429 0.1651)
							(mid -0.283384 0.308784)
							(end -0.1397 0.3683)
						)
						(arc
							(start 0.1397 0.3683)
							(mid 0.283384 0.308784)
							(end 0.3429 0.1651)
						)
						(arc
							(start 0.3429 -0.1651)
							(mid 0.283384 -0.308784)
							(end 0.1397 -0.3683)
						)
					)
					(width 0)
					(fill yes)
				)
			)
		)
		(pad "S" smd custom
			(at -0.94996 1.069086 90)
			(size 0.17145 0.17145)
			(layers "B.Cu" "B.Mask" "B.Paste")
			(net "GND")
			(options
				(clearance outline)
				(anchor circle)
			)
			(primitives
				(gr_poly
					(pts
						(arc
							(start -0.1397 -0.3683)
							(mid -0.283384 -0.308784)
							(end -0.3429 -0.1651)
						)
						(arc
							(start -0.3429 0.1651)
							(mid -0.283384 0.308784)
							(end -0.1397 0.3683)
						)
						(arc
							(start 0.1397 0.3683)
							(mid 0.283384 0.308784)
							(end 0.3429 0.1651)
						)
						(arc
							(start 0.3429 -0.1651)
							(mid 0.283384 -0.308784)
							(end 0.1397 -0.3683)
						)
					)
					(width 0)
					(fill yes)
				)
			)
		)
	)
	(footprint ""
		(layer "B.Cu")
		(at 87.58936 -26.07056)
		(property "Reference" "R377"
			(at 0 0 0)
			(layer "B.SilkS")
			(hide yes)
			(effects
				(font
					(size 1.27 1.27)
				)
				(justify mirror)
			)
		)
		(property "Value" "1KR2F-3-GP"
			(at -0.064008 -3.993896 0)
			(unlocked yes)
			(layer "B.Fab")
			(hide yes)
			(effects
				(font
					(size 1.016 1.016)
					(thickness 0.1524)
				)
				(justify mirror)
			)
		)
		(property "Device Type" "R402H16"
			(at -0.064008 -5.517896 0)
			(unlocked yes)
			(layer "B.Fab")
			(hide yes)
			(effects
				(font
					(size 1.016 1.016)
					(thickness 0.1524)
				)
				(justify mirror)
			)
		)
		(duplicate_pad_numbers_are_jumpers no)
		(fp_rect
			(start 0.381 0.8382)
			(end -0.381 -0.8382)
			(stroke
				(width 0)
				(type default)
			)
			(fill no)
			(layer "B.CrtYd")
		)
		(fp_rect
			(start 0.381 0.8382)
			(end -0.381 -0.8382)
			(stroke
				(width 0)
				(type default)
			)
			(fill no)
			(layer "B.Fab")
		)
		(pad "1" smd custom
			(at 0 -0.4318 180)
			(size 0.127 0.127)
			(layers "B.Cu" "B.Mask" "B.Paste")
			(net "BD_REV_0")
			(options
				(clearance outline)
				(anchor circle)
			)
			(primitives
				(gr_poly
					(pts
						(arc
							(start -0.2032 0.2794)
							(mid -0.239121 0.264521)
							(end -0.254 0.2286)
						)
						(arc
							(start -0.254 -0.2286)
							(mid -0.239121 -0.264521)
							(end -0.2032 -0.2794)
						)
						(arc
							(start 0.2032 -0.2794)
							(mid 0.239121 -0.264521)
							(end 0.254 -0.2286)
						)
						(arc
							(start 0.254 0.2286)
							(mid 0.239121 0.264521)
							(end 0.2032 0.2794)
						)
					)
					(width 0)
					(fill yes)
				)
			)
		)
		(pad "2" smd custom
			(at 0 0.4318 180)
			(size 0.127 0.127)
			(layers "B.Cu" "B.Mask" "B.Paste")
			(net "GND")
			(options
				(clearance outline)
				(anchor circle)
			)
			(primitives
				(gr_poly
					(pts
						(arc
							(start -0.2032 0.2794)
							(mid -0.239121 0.264521)
							(end -0.254 0.2286)
						)
						(arc
							(start -0.254 -0.2286)
							(mid -0.239121 -0.264521)
							(end -0.2032 -0.2794)
						)
						(arc
							(start 0.2032 -0.2794)
							(mid 0.239121 -0.264521)
							(end 0.254 -0.2286)
						)
						(arc
							(start 0.254 0.2286)
							(mid 0.239121 0.264521)
							(end 0.2032 0.2794)
						)
					)
					(width 0)
					(fill yes)
				)
			)
		)
	)
	(footprint ""
		(layer "B.Cu")
		(at 90.424 -43.2562 180)
		(property "Reference" "R47"
			(at 0 0 0)
			(layer "B.SilkS")
			(hide yes)
			(effects
				(font
					(size 1.27 1.27)
				)
				(justify mirror)
			)
		)
		(property "Value" "51R2F-2-GP"
			(at -0.064008 -3.993896 180)
			(unlocked yes)
			(layer "B.Fab")
			(hide yes)
			(effects
				(font
					(size 1.016 1.016)
					(thickness 0.1524)
				)
				(justify mirror)
			)
		)
		(property "Device Type" "R402H16"
			(at -0.064008 -5.517896 180)
			(unlocked yes)
			(layer "B.Fab")
			(hide yes)
			(effects
				(font
					(size 1.016 1.016)
					(thickness 0.1524)
				)
				(justify mirror)
			)
		)
		(duplicate_pad_numbers_are_jumpers no)
		(fp_rect
			(start 0.381 0.8382)
			(end -0.381 -0.8382)
			(stroke
				(width 0)
				(type default)
			)
			(fill no)
			(layer "B.CrtYd")
		)
		(fp_rect
			(start 0.381 0.8382)
			(end -0.381 -0.8382)
			(stroke
				(width 0)
				(type default)
			)
			(fill no)
			(layer "B.Fab")
		)
		(pad "1" smd custom
			(at 0 -0.4318)
			(size 0.127 0.127)
			(layers "B.Cu" "B.Mask" "B.Paste")
			(net "CTBTRIGINOUT")
			(options
				(clearance outline)
				(anchor circle)
			)
			(primitives
				(gr_poly
					(pts
						(arc
							(start -0.2032 0.2794)
							(mid -0.239121 0.264521)
							(end -0.254 0.2286)
						)
						(arc
							(start -0.254 -0.2286)
							(mid -0.239121 -0.264521)
							(end -0.2032 -0.2794)
						)
						(arc
							(start 0.2032 -0.2794)
							(mid 0.239121 -0.264521)
							(end 0.254 -0.2286)
						)
						(arc
							(start 0.254 0.2286)
							(mid 0.239121 0.264521)
							(end 0.2032 0.2794)
						)
					)
					(width 0)
					(fill yes)
				)
			)
		)
		(pad "2" smd custom
			(at 0 0.4318)
			(size 0.127 0.127)
			(layers "B.Cu" "B.Mask" "B.Paste")
			(net "GND")
			(options
				(clearance outline)
				(anchor circle)
			)
			(primitives
				(gr_poly
					(pts
						(arc
							(start -0.2032 0.2794)
							(mid -0.239121 0.264521)
							(end -0.254 0.2286)
						)
						(arc
							(start -0.254 -0.2286)
							(mid -0.239121 -0.264521)
							(end -0.2032 -0.2794)
						)
						(arc
							(start 0.2032 -0.2794)
							(mid 0.239121 -0.264521)
							(end 0.254 -0.2286)
						)
						(arc
							(start 0.254 0.2286)
							(mid 0.239121 0.264521)
							(end 0.2032 0.2794)
						)
					)
					(width 0)
					(fill yes)
				)
			)
		)
	)
	(footprint ""
		(layer "B.Cu")
		(at 110.617 -47.879 90)
		(property "Reference" "C142"
			(at 0 0 90)
			(layer "B.SilkS")
			(hide yes)
			(effects
				(font
					(size 1.27 1.27)
				)
				(justify mirror)
			)
		)
		(property "Value" "SC1U10V2KX-1GP"
			(at -1.1811 -2.7051 90)
			(unlocked yes)
			(layer "B.Fab")
			(hide yes)
			(effects
				(font
					(size 1.016 1.016)
					(thickness 0.1524)
				)
				(justify mirror)
			)
		)
		(property "Device Type" "C402H22"
			(at -1.1811 -4.2291 90)
			(unlocked yes)
			(layer "B.Fab")
			(hide yes)
			(effects
				(font
					(size 1.016 1.016)
					(thickness 0.1524)
				)
				(justify mirror)
			)
		)
		(duplicate_pad_numbers_are_jumpers no)
		(fp_rect
			(start 0.381 0.7366)
			(end -0.381 -0.7366)
			(stroke
				(width 0)
				(type default)
			)
			(fill no)
			(layer "B.CrtYd")
		)
		(fp_rect
			(start 0.381 0.7366)
			(end -0.381 -0.7366)
			(stroke
				(width 0)
				(type default)
			)
			(fill no)
			(layer "B.Fab")
		)
		(pad "1" smd custom
			(at 0 -0.4572 270)
			(size 0.1143 0.1143)
			(layers "B.Cu" "B.Mask" "B.Paste")
			(net "PV_VDDR")
			(options
				(clearance outline)
				(anchor circle)
			)
			(primitives
				(gr_poly
					(pts
						(arc
							(start -0.254 0.1778)
							(mid -0.239121 0.213721)
							(end -0.2032 0.2286)
						)
						(arc
							(start 0.2032 0.2286)
							(mid 0.239121 0.213721)
							(end 0.254 0.1778)
						)
						(arc
							(start 0.254 -0.1778)
							(mid 0.239121 -0.213721)
							(end 0.2032 -0.2286)
						)
						(arc
							(start -0.2032 -0.2286)
							(mid -0.239121 -0.213721)
							(end -0.254 -0.1778)
						)
					)
					(width 0)
					(fill yes)
				)
			)
		)
		(pad "2" smd custom
			(at 0 0.4572 270)
			(size 0.1143 0.1143)
			(layers "B.Cu" "B.Mask" "B.Paste")
			(net "GND")
			(options
				(clearance outline)
				(anchor circle)
			)
			(primitives
				(gr_poly
					(pts
						(arc
							(start -0.254 0.1778)
							(mid -0.239121 0.213721)
							(end -0.2032 0.2286)
						)
						(arc
							(start 0.2032 0.2286)
							(mid 0.239121 0.213721)
							(end 0.254 0.1778)
						)
						(arc
							(start 0.254 -0.1778)
							(mid 0.239121 -0.213721)
							(end 0.2032 -0.2286)
						)
						(arc
							(start -0.2032 -0.2286)
							(mid -0.239121 -0.213721)
							(end -0.254 -0.1778)
						)
					)
					(width 0)
					(fill yes)
				)
			)
		)
	)
	(gr_line
		(start 1.9304 -67.178682)
		(end 2.164842 -66.94424)
		(stroke
			(width 0.06985)
			(type default)
		)
		(layer "F.Cu")
	)
	(gr_line
		(start 1.9304 -66.221102)
		(end 2.164842 -66.455544)
		(stroke
			(width 0.06985)
			(type default)
		)
		(layer "F.Cu")
	)
	(gr_line
		(start 1.9304 -64.178688)
		(end 2.164842 -63.944246)
		(stroke
			(width 0.06985)
			(type default)
		)
		(layer "F.Cu")
	)
	(gr_line
		(start 1.9304 -63.221108)
		(end 2.164842 -63.45555)
		(stroke
			(width 0.06985)
			(type default)
		)
		(layer "F.Cu")
	)
	(gr_line
		(start 1.9304 -61.178694)
		(end 2.164842 -60.944252)
		(stroke
			(width 0.06985)
			(type default)
		)
		(layer "F.Cu")
	)
	(gr_line
		(start 1.9304 -60.221114)
		(end 2.164842 -60.455556)
		(stroke
			(width 0.06985)
			(type default)
		)
		(layer "F.Cu")
	)
	(gr_line
		(start 3.32486 -59.664346)
		(end 3.559302 -59.429904)
		(stroke
			(width 0.06985)
			(type default)
		)
		(layer "F.Cu")
	)
	(gr_line
		(start 3.32486 -58.706766)
		(end 3.559302 -58.941208)
		(stroke
			(width 0.06985)
			(type default)
		)
		(layer "F.Cu")
	)
	(gr_line
		(start 3.45186 -65.664334)
		(end 3.686302 -65.429892)
		(stroke
			(width 0.06985)
			(type default)
		)
		(layer "F.Cu")
	)
	(gr_line
		(start 3.45186 -64.706754)
		(end 3.686302 -64.941196)
		(stroke
			(width 0.06985)
			(type default)
		)
		(layer "F.Cu")
	)
	(gr_line
		(start 3.45186 -62.66434)
		(end 3.686302 -62.429898)
		(stroke
			(width 0.06985)
			(type default)
		)
		(layer "F.Cu")
	)
	(gr_line
		(start 3.45186 -61.70676)
		(end 3.686302 -61.941202)
		(stroke
			(width 0.06985)
			(type default)
		)
		(layer "F.Cu")
	)
	(gr_line
		(start 7.851648 -65.204848)
		(end 8.0518 -65.405)
		(stroke
			(width 0.06985)
			(type default)
		)
		(layer "F.Cu")
	)
	(gr_line
		(start 7.851648 -64.716152)
		(end 8.0518 -64.516)
		(stroke
			(width 0.06985)
			(type default)
		)
		(layer "F.Cu")
	)
	(gr_line
		(start 7.851648 -63.426848)
		(end 8.0518 -63.627)
		(stroke
			(width 0.06985)
			(type default)
		)
		(layer "F.Cu")
	)
	(gr_line
		(start 7.851648 -62.938152)
		(end 8.0518 -62.738)
		(stroke
			(width 0.06985)
			(type default)
		)
		(layer "F.Cu")
	)
	(gr_line
		(start 7.851648 -61.648848)
		(end 8.0518 -61.849)
		(stroke
			(width 0.06985)
			(type default)
		)
		(layer "F.Cu")
	)
	(gr_line
		(start 7.851648 -61.160152)
		(end 8.0518 -60.96)
		(stroke
			(width 0.06985)
			(type default)
		)
		(layer "F.Cu")
	)
	(gr_line
		(start 7.851648 -59.870848)
		(end 8.0518 -60.071)
		(stroke
			(width 0.06985)
			(type default)
		)
		(layer "F.Cu")
	)
	(gr_line
		(start 7.851648 -59.382152)
		(end 8.0518 -59.182)
		(stroke
			(width 0.06985)
			(type default)
		)
		(layer "F.Cu")
	)
	(gr_line
		(start 7.851648 -58.092848)
		(end 8.0518 -58.293)
		(stroke
			(width 0.06985)
			(type default)
		)
		(layer "F.Cu")
	)
	(gr_line
		(start 7.851648 -57.604152)
		(end 8.0518 -57.404)
		(stroke
			(width 0.06985)
			(type default)
		)
		(layer "F.Cu")
	)
	(gr_line
		(start 7.851648 -56.314848)
		(end 8.0518 -56.515)
		(stroke
			(width 0.06985)
			(type default)
		)
		(layer "F.Cu")
	)
	(gr_line
		(start 7.851648 -55.826152)
		(end 8.0518 -55.626)
		(stroke
			(width 0.06985)
			(type default)
		)
		(layer "F.Cu")
	)
	(gr_line
		(start 8.128 -51.6128)
		(end 8.378952 -51.361848)
		(stroke
			(width 0.06985)
			(type default)
		)
		(layer "F.Cu")
	)
	(gr_line
		(start 8.128 -50.6222)
		(end 8.378952 -50.873152)
		(stroke
			(width 0.06985)
			(type default)
		)
		(layer "F.Cu")
	)
	(gr_line
		(start 8.8392 -53.8988)
		(end 9.090152 -53.647848)
		(stroke
			(width 0.06985)
			(type default)
		)
		(layer "F.Cu")
	)
	(gr_line
		(start 8.8392 -52.9082)
		(end 9.090152 -53.159152)
		(stroke
			(width 0.06985)
			(type default)
		)
		(layer "F.Cu")
	)
	(gr_line
		(start 8.9662 -65.405)
		(end 9.6266 -65.405)
		(stroke
			(width 0.06985)
			(type default)
		)
		(layer "F.Cu")
	)
	(gr_line
		(start 8.9662 -64.516)
		(end 9.6266 -64.516)
		(stroke
			(width 0.06985)
			(type default)
		)
		(layer "F.Cu")
	)
	(gr_line
		(start 8.9662 -63.627)
		(end 9.652 -63.627)
		(stroke
			(width 0.06985)
			(type default)
		)
		(layer "F.Cu")
	)
	(gr_line
		(start 8.9662 -62.738)
		(end 9.6266 -62.738)
		(stroke
			(width 0.06985)
			(type default)
		)
		(layer "F.Cu")
	)
	(gr_line
		(start 8.9662 -61.849)
		(end 9.6266 -61.849)
		(stroke
			(width 0.06985)
			(type default)
		)
		(layer "F.Cu")
	)
	(gr_line
		(start 8.9662 -60.96)
		(end 9.6266 -60.96)
		(stroke
			(width 0.06985)
			(type default)
		)
		(layer "F.Cu")
	)
	(gr_line
		(start 8.9662 -60.071)
		(end 9.652 -60.071)
		(stroke
			(width 0.06985)
			(type default)
		)
		(layer "F.Cu")
	)
	(gr_line
		(start 8.9662 -59.182)
		(end 9.6266 -59.182)
		(stroke
			(width 0.06985)
			(type default)
		)
		(layer "F.Cu")
	)
	(gr_line
		(start 8.9662 -58.293)
		(end 9.6266 -58.293)
		(stroke
			(width 0.06985)
			(type default)
		)
		(layer "F.Cu")
	)
	(gr_line
		(start 8.9662 -57.404)
		(end 9.6266 -57.404)
		(stroke
			(width 0.06985)
			(type default)
		)
		(layer "F.Cu")
	)
	(gr_line
		(start 8.9662 -56.515)
		(end 9.6266 -56.515)
		(stroke
			(width 0.06985)
			(type default)
		)
		(layer "F.Cu")
	)
	(gr_line
		(start 8.9662 -55.626)
		(end 9.6266 -55.626)
		(stroke
			(width 0.06985)
			(type default)
		)
		(layer "F.Cu")
	)
	(gr_line
		(start 9.5504 -51.7398)
		(end 10.2108 -51.7398)
		(stroke
			(width 0.06985)
			(type default)
		)
		(layer "F.Cu")
	)
	(gr_line
		(start 9.5504 -50.4952)
		(end 10.2108 -50.4952)
		(stroke
			(width 0.06985)
			(type default)
		)
		(layer "F.Cu")
	)
	(gr_line
		(start 10.2616 -54.0258)
		(end 10.922 -54.0258)
		(stroke
			(width 0.06985)
			(type default)
		)
		(layer "F.Cu")
	)
	(gr_line
		(start 10.2616 -52.7812)
		(end 10.922 -52.7812)
		(stroke
			(width 0.06985)
			(type default)
		)
		(layer "F.Cu")
	)
	(gr_line
		(start 10.772648 -51.336448)
		(end 10.9728 -51.5366)
		(stroke
			(width 0.06985)
			(type default)
		)
		(layer "F.Cu")
	)
	(gr_line
		(start 10.772648 -50.847752)
		(end 10.9728 -50.6476)
		(stroke
			(width 0.06985)
			(type default)
		)
		(layer "F.Cu")
	)
	(gr_line
		(start 10.9728 -51.5366)
		(end 10.9728 -51.7398)
		(stroke
			(width 0.06985)
			(type default)
		)
		(layer "F.Cu")
	)
	(gr_line
		(start 10.9728 -50.4952)
		(end 10.9728 -50.6476)
		(stroke
			(width 0.06985)
			(type default)
		)
		(layer "F.Cu")
	)
	(gr_line
		(start 11.483848 -53.622448)
		(end 11.684 -53.8226)
		(stroke
			(width 0.06985)
			(type default)
		)
		(layer "F.Cu")
	)
	(gr_line
		(start 11.483848 -53.133752)
		(end 11.684 -52.9336)
		(stroke
			(width 0.06985)
			(type default)
		)
		(layer "F.Cu")
	)
	(gr_line
		(start 11.684 -53.8226)
		(end 11.684 -54.0258)
		(stroke
			(width 0.06985)
			(type default)
		)
		(layer "F.Cu")
	)
	(gr_line
		(start 11.684 -52.7812)
		(end 11.684 -52.9336)
		(stroke
			(width 0.06985)
			(type default)
		)
		(layer "F.Cu")
	)
	(gr_line
		(start 11.8872 -51.4604)
		(end 11.8872 -51.7398)
		(stroke
			(width 0.06985)
			(type default)
		)
		(layer "F.Cu")
	)
	(gr_line
		(start 11.8872 -51.4604)
		(end 11.963654 -51.383946)
		(stroke
			(width 0.06985)
			(type default)
		)
		(layer "F.Cu")
	)
	(gr_line
		(start 11.8872 -50.81905)
		(end 11.963654 -50.895504)
		(stroke
			(width 0.06985)
			(type default)
		)
		(layer "F.Cu")
	)
	(gr_line
		(start 11.8872 -50.4952)
		(end 11.8872 -50.81905)
		(stroke
			(width 0.06985)
			(type default)
		)
		(layer "F.Cu")
	)
	(gr_line
		(start 12.5984 -53.86451)
		(end 12.5984 -54.0258)
		(stroke
			(width 0.06985)
			(type default)
		)
		(layer "F.Cu")
	)
	(gr_line
		(start 12.5984 -53.86451)
		(end 12.718034 -53.744876)
		(stroke
			(width 0.06985)
			(type default)
		)
		(layer "F.Cu")
	)
	(gr_line
		(start 12.5984 -53.1368)
		(end 12.718034 -53.256434)
		(stroke
			(width 0.06985)
			(type default)
		)
		(layer "F.Cu")
	)
	(gr_line
		(start 12.5984 -52.7812)
		(end 12.5984 -53.1368)
		(stroke
			(width 0.06985)
			(type default)
		)
		(layer "F.Cu")
	)
	(gr_line
		(start 12.937998 -48.383698)
		(end 13.17244 -48.61814)
		(stroke
			(width 0.06985)
			(type default)
		)
		(layer "F.Cu")
	)
	(gr_line
		(start 12.937998 -47.895002)
		(end 13.17244 -47.66056)
		(stroke
			(width 0.06985)
			(type default)
		)
		(layer "F.Cu")
	)
	(gr_line
		(start 13.68044 -52.04714)
		(end 13.87856 -52.24526)
		(stroke
			(width 0.06985)
			(type default)
		)
		(layer "F.Cu")
	)
	(gr_line
		(start 13.68044 -51.62804)
		(end 13.68044 -52.04714)
		(stroke
			(width 0.06985)
			(type default)
		)
		(layer "F.Cu")
	)
	(gr_line
		(start 13.68044 -51.62804)
		(end 13.87856 -51.42992)
		(stroke
			(width 0.06985)
			(type default)
		)
		(layer "F.Cu")
	)
	(gr_line
		(start 13.68044 -50.80762)
		(end 13.87856 -51.00574)
		(stroke
			(width 0.06985)
			(type default)
		)
		(layer "F.Cu")
	)
	(gr_line
		(start 13.68044 -50.38852)
		(end 13.68044 -50.80762)
		(stroke
			(width 0.06985)
			(type default)
		)
		(layer "F.Cu")
	)
	(gr_line
		(start 13.68044 -50.38852)
		(end 13.87856 -50.1904)
		(stroke
			(width 0.06985)
			(type default)
		)
		(layer "F.Cu")
	)
	(gr_line
		(start 14.15288 -46.83252)
		(end 14.373352 -47.052992)
		(stroke
			(width 0.06985)
			(type default)
		)
		(layer "F.Cu")
	)
	(gr_line
		(start 14.224 -51.77282)
		(end 14.224 -51.90236)
		(stroke
			(width 0.06985)
			(type default)
		)
		(layer "F.Cu")
	)
	(gr_line
		(start 14.224 -50.5333)
		(end 14.224 -50.66284)
		(stroke
			(width 0.06985)
			(type default)
		)
		(layer "F.Cu")
	)
	(gr_line
		(start 14.861794 -47.052992)
		(end 15.082266 -46.83252)
		(stroke
			(width 0.06985)
			(type default)
		)
		(layer "F.Cu")
	)
	(gr_line
		(start 19.349974 -7.977378)
		(end 19.60245 -8.229854)
		(stroke
			(width 0.06985)
			(type default)
		)
		(layer "F.Cu")
	)
	(gr_line
		(start 19.349974 -6.195568)
		(end 19.349974 -7.977378)
		(stroke
			(width 0.06985)
			(type default)
		)
		(layer "F.Cu")
	)
	(gr_line
		(start 19.408394 -10.250678)
		(end 19.623786 -10.035286)
		(stroke
			(width 0.06985)
			(type default)
		)
		(layer "F.Cu")
	)
	(gr_line
		(start 20.091146 -8.229854)
		(end 20.349972 -7.971028)
		(stroke
			(width 0.06985)
			(type default)
		)
		(layer "F.Cu")
	)
	(gr_line
		(start 20.112482 -10.035286)
		(end 20.327874 -10.250678)
		(stroke
			(width 0.06985)
			(type default)
		)
		(layer "F.Cu")
	)
	(gr_line
		(start 20.349972 -6.195568)
		(end 20.349972 -7.971028)
		(stroke
			(width 0.06985)
			(type default)
		)
		(layer "F.Cu")
	)
	(gr_line
		(start 21.263102 -55.118)
		(end 21.263102 -55.547006)
		(stroke
			(width 0.0635)
			(type default)
		)
		(layer "F.Cu")
	)
	(gr_line
		(start 21.263102 -55.118)
		(end 21.345144 -55.035958)
		(stroke
			(width 0.0635)
			(type default)
		)
		(layer "F.Cu")
	)
	(gr_line
		(start 21.662898 -54.991)
		(end 21.662898 -55.547006)
		(stroke
			(width 0.0635)
			(type default)
		)
		(layer "F.Cu")
	)
	(gr_line
		(start 22.606 -52.6034)
		(end 22.7838 -52.4256)
		(stroke
			(width 0.0635)
			(type default)
		)
		(layer "F.Cu")
	)
	(gr_line
		(start 22.606 -52.6034)
		(end 22.907244 -52.904644)
		(stroke
			(width 0.0635)
			(type default)
		)
		(layer "F.Cu")
	)
	(gr_line
		(start 22.733 -51.816)
		(end 22.7838 -51.8668)
		(stroke
			(width 0.0635)
			(type default)
		)
		(layer "F.Cu")
	)
	(gr_line
		(start 22.7838 -51.8668)
		(end 22.7838 -52.4256)
		(stroke
			(width 0.0635)
			(type default)
		)
		(layer "F.Cu")
	)
	(gr_line
		(start 23.269956 -52.904644)
		(end 23.5458 -52.6288)
		(stroke
			(width 0.0635)
			(type default)
		)
		(layer "F.Cu")
	)
	(gr_line
		(start 23.349966 -8.027924)
		(end 23.5966 -8.274558)
		(stroke
			(width 0.06985)
			(type default)
		)
		(layer "F.Cu")
	)
	(gr_line
		(start 23.349966 -6.195568)
		(end 23.349966 -8.027924)
		(stroke
			(width 0.06985)
			(type default)
		)
		(layer "F.Cu")
	)
	(gr_line
		(start 23.3934 -52.4764)
		(end 23.5204 -52.6034)
		(stroke
			(width 0.0635)
			(type default)
		)
		(layer "F.Cu")
	)
	(gr_line
		(start 23.3934 -52.021232)
		(end 23.3934 -52.4764)
		(stroke
			(width 0.0635)
			(type default)
		)
		(layer "F.Cu")
	)
	(gr_line
		(start 23.3934 -52.021232)
		(end 23.5966 -51.818032)
		(stroke
			(width 0.0635)
			(type default)
		)
		(layer "F.Cu")
	)
	(gr_line
		(start 23.408386 -10.250678)
		(end 23.623778 -10.035286)
		(stroke
			(width 0.06985)
			(type default)
		)
		(layer "F.Cu")
	)
	(gr_line
		(start 23.5204 -52.6034)
		(end 23.5458 -52.6288)
		(stroke
			(width 0.0635)
			(type default)
		)
		(layer "F.Cu")
	)
	(gr_line
		(start 24.085042 -8.274558)
		(end 24.349964 -8.009636)
		(stroke
			(width 0.06985)
			(type default)
		)
		(layer "F.Cu")
	)
	(gr_line
		(start 24.112474 -10.035286)
		(end 24.327866 -10.250678)
		(stroke
			(width 0.06985)
			(type default)
		)
		(layer "F.Cu")
	)
	(gr_line
		(start 24.349964 -6.195568)
		(end 24.349964 -8.009636)
		(stroke
			(width 0.06985)
			(type default)
		)
		(layer "F.Cu")
	)
	(gr_line
		(start 27.349958 -8.002778)
		(end 27.592782 -8.245602)
		(stroke
			(width 0.06985)
			(type default)
		)
		(layer "F.Cu")
	)
	(gr_line
		(start 27.349958 -6.195568)
		(end 27.349958 -8.002778)
		(stroke
			(width 0.06985)
			(type default)
		)
		(layer "F.Cu")
	)
	(gr_line
		(start 27.408378 -10.250678)
		(end 27.62377 -10.035286)
		(stroke
			(width 0.06985)
			(type default)
		)
		(layer "F.Cu")
	)
	(gr_line
		(start 28.081478 -8.245602)
		(end 28.349956 -7.977124)
		(stroke
			(width 0.06985)
			(type default)
		)
		(layer "F.Cu")
	)
	(gr_line
		(start 28.112466 -10.035286)
		(end 28.327858 -10.250678)
		(stroke
			(width 0.06985)
			(type default)
		)
		(layer "F.Cu")
	)
	(gr_line
		(start 28.349956 -6.195568)
		(end 28.349956 -7.977124)
		(stroke
			(width 0.06985)
			(type default)
		)
		(layer "F.Cu")
	)
	(gr_line
		(start 31.34995 -7.977124)
		(end 31.618428 -8.245602)
		(stroke
			(width 0.06985)
			(type default)
		)
		(layer "F.Cu")
	)
	(gr_line
		(start 31.34995 -6.195568)
		(end 31.34995 -7.977124)
		(stroke
			(width 0.06985)
			(type default)
		)
		(layer "F.Cu")
	)
	(gr_line
		(start 31.40837 -10.250678)
		(end 31.623762 -10.035286)
		(stroke
			(width 0.06985)
			(type default)
		)
		(layer "F.Cu")
	)
	(gr_line
		(start 32.107124 -8.245602)
		(end 32.349948 -8.002778)
		(stroke
			(width 0.06985)
			(type default)
		)
		(layer "F.Cu")
	)
	(gr_line
		(start 32.112458 -10.035286)
		(end 32.32785 -10.250678)
		(stroke
			(width 0.06985)
			(type default)
		)
		(layer "F.Cu")
	)
	(gr_line
		(start 32.349948 -6.195568)
		(end 32.349948 -8.002778)
		(stroke
			(width 0.06985)
			(type default)
		)
		(layer "F.Cu")
	)
	(gr_line
		(start 35.349942 -8.447024)
		(end 35.60572 -8.702802)
		(stroke
			(width 0.06985)
			(type default)
		)
		(layer "F.Cu")
	)
	(gr_line
		(start 35.349942 -6.195568)
		(end 35.349942 -8.447024)
		(stroke
			(width 0.06985)
			(type default)
		)
		(layer "F.Cu")
	)
	(gr_line
		(start 35.408362 -10.250678)
		(end 35.623754 -10.035286)
		(stroke
			(width 0.06985)
			(type default)
		)
		(layer "F.Cu")
	)
	(gr_line
		(start 36.094416 -8.702802)
		(end 36.34994 -8.447278)
		(stroke
			(width 0.06985)
			(type default)
		)
		(layer "F.Cu")
	)
	(gr_line
		(start 36.11245 -10.035286)
		(end 36.327842 -10.250678)
		(stroke
			(width 0.06985)
			(type default)
		)
		(layer "F.Cu")
	)
	(gr_line
		(start 36.34994 -6.195568)
		(end 36.34994 -8.447278)
		(stroke
			(width 0.06985)
			(type default)
		)
		(layer "F.Cu")
	)
	(gr_line
		(start 36.37788 -30.05455)
		(end 37.34435 -30.05455)
		(stroke
			(width 0.06985)
			(type default)
		)
		(layer "F.Cu")
	)
	(gr_line
		(start 36.37788 -29.55544)
		(end 37.41674 -29.55544)
		(stroke
			(width 0.06985)
			(type default)
		)
		(layer "F.Cu")
	)
	(gr_line
		(start 37.34435 -30.05455)
		(end 37.385752 -30.013148)
		(stroke
			(width 0.06985)
			(type default)
		)
		(layer "F.Cu")
	)
	(gr_line
		(start 38.082728 -30.013148)
		(end 38.27018 -30.2006)
		(stroke
			(width 0.06985)
			(type default)
		)
		(layer "F.Cu")
	)
	(gr_line
		(start 38.082728 -29.524452)
		(end 38.27018 -29.337)
		(stroke
			(width 0.06985)
			(type default)
		)
		(layer "F.Cu")
	)
	(gr_line
		(start 39.349934 -8.447278)
		(end 39.605458 -8.702802)
		(stroke
			(width 0.06985)
			(type default)
		)
		(layer "F.Cu")
	)
	(gr_line
		(start 39.349934 -6.195568)
		(end 39.349934 -8.447278)
		(stroke
			(width 0.06985)
			(type default)
		)
		(layer "F.Cu")
	)
	(gr_line
		(start 39.408354 -10.250678)
		(end 39.623746 -10.035286)
		(stroke
			(width 0.06985)
			(type default)
		)
		(layer "F.Cu")
	)
	(gr_line
		(start 40.094154 -8.702802)
		(end 40.349932 -8.447024)
		(stroke
			(width 0.06985)
			(type default)
		)
		(layer "F.Cu")
	)
	(gr_line
		(start 40.112442 -10.035286)
		(end 40.327834 -10.250678)
		(stroke
			(width 0.06985)
			(type default)
		)
		(layer "F.Cu")
	)
	(gr_line
		(start 40.349932 -6.195568)
		(end 40.349932 -8.447024)
		(stroke
			(width 0.06985)
			(type default)
		)
		(layer "F.Cu")
	)
	(gr_line
		(start 43.349926 -8.447024)
		(end 43.605704 -8.702802)
		(stroke
			(width 0.06985)
			(type default)
		)
		(layer "F.Cu")
	)
	(gr_line
		(start 43.349926 -6.195568)
		(end 43.349926 -8.447024)
		(stroke
			(width 0.06985)
			(type default)
		)
		(layer "F.Cu")
	)
	(gr_line
		(start 43.408346 -10.250678)
		(end 43.623738 -10.035286)
		(stroke
			(width 0.06985)
			(type default)
		)
		(layer "F.Cu")
	)
	(gr_line
		(start 44.0944 -8.702802)
		(end 44.349924 -8.447278)
		(stroke
			(width 0.06985)
			(type default)
		)
		(layer "F.Cu")
	)
	(gr_line
		(start 44.112434 -10.035286)
		(end 44.327826 -10.250678)
		(stroke
			(width 0.06985)
			(type default)
		)
		(layer "F.Cu")
	)
	(gr_line
		(start 44.349924 -6.195568)
		(end 44.349924 -8.447278)
		(stroke
			(width 0.06985)
			(type default)
		)
		(layer "F.Cu")
	)
	(gr_line
		(start 47.349918 -8.447024)
		(end 47.605696 -8.702802)
		(stroke
			(width 0.06985)
			(type default)
		)
		(layer "F.Cu")
	)
	(gr_line
		(start 47.349918 -6.195568)
		(end 47.349918 -8.447024)
		(stroke
			(width 0.06985)
			(type default)
		)
		(layer "F.Cu")
	)
	(gr_line
		(start 47.408338 -10.250678)
		(end 47.62373 -10.035286)
		(stroke
			(width 0.06985)
			(type default)
		)
		(layer "F.Cu")
	)
	(gr_line
		(start 48.094392 -8.702802)
		(end 48.349916 -8.447278)
		(stroke
			(width 0.06985)
			(type default)
		)
		(layer "F.Cu")
	)
	(gr_line
		(start 48.112426 -10.035286)
		(end 48.327818 -10.250678)
		(stroke
			(width 0.06985)
			(type default)
		)
		(layer "F.Cu")
	)
	(gr_line
		(start 48.349916 -6.195568)
		(end 48.349916 -8.447278)
		(stroke
			(width 0.06985)
			(type default)
		)
		(layer "F.Cu")
	)
	(gr_line
		(start 49.38903 -10.26033)
		(end 49.605438 -10.476738)
		(stroke
			(width 0.06985)
			(type default)
		)
		(layer "F.Cu")
	)
	(gr_line
		(start 49.4538 -13.1572)
		(end 49.4538 -13.8176)
		(stroke
			(width 0.06985)
			(type default)
		)
		(layer "F.Cu")
	)
	(gr_line
		(start 49.4538 -12.2428)
		(end 49.590452 -12.106148)
		(stroke
			(width 0.06985)
			(type default)
		)
		(layer "F.Cu")
	)
	(gr_line
		(start 50.079148 -12.106148)
		(end 50.2158 -12.2428)
		(stroke
			(width 0.06985)
			(type default)
		)
		(layer "F.Cu")
	)
	(gr_line
		(start 50.094134 -10.476738)
		(end 50.310542 -10.26033)
		(stroke
			(width 0.06985)
			(type default)
		)
		(layer "F.Cu")
	)
	(gr_line
		(start 50.2158 -13.1572)
		(end 50.2158 -13.8176)
		(stroke
			(width 0.06985)
			(type default)
		)
		(layer "F.Cu")
	)
	(gr_line
		(start 51.34991 -8.447278)
		(end 51.605434 -8.702802)
		(stroke
			(width 0.06985)
			(type default)
		)
		(layer "F.Cu")
	)
	(gr_line
		(start 51.34991 -6.195568)
		(end 51.34991 -8.447278)
		(stroke
			(width 0.06985)
			(type default)
		)
		(layer "F.Cu")
	)
	(gr_line
		(start 52.09413 -8.702802)
		(end 52.349908 -8.447024)
		(stroke
			(width 0.06985)
			(type default)
		)
		(layer "F.Cu")
	)
	(gr_line
		(start 52.1462 -13.9446)
		(end 52.2224 -13.8684)
		(stroke
			(width 0.06985)
			(type default)
		)
		(layer "F.Cu")
	)
	(gr_line
		(start 52.2224 -13.2842)
		(end 52.2224 -13.8684)
		(stroke
			(width 0.06985)
			(type default)
		)
		(layer "F.Cu")
	)
	(gr_line
		(start 52.2224 -12.3698)
		(end 52.359052 -12.233148)
		(stroke
			(width 0.06985)
			(type default)
		)
		(layer "F.Cu")
	)
	(gr_line
		(start 52.349908 -6.195568)
		(end 52.349908 -8.447024)
		(stroke
			(width 0.06985)
			(type default)
		)
		(layer "F.Cu")
	)
	(gr_line
		(start 52.847748 -12.233148)
		(end 52.9844 -12.3698)
		(stroke
			(width 0.06985)
			(type default)
		)
		(layer "F.Cu")
	)
	(gr_line
		(start 52.9844 -13.9192)
		(end 53.0098 -13.9446)
		(stroke
			(width 0.06985)
			(type default)
		)
		(layer "F.Cu")
	)
	(gr_line
		(start 52.9844 -13.2842)
		(end 52.9844 -13.9192)
		(stroke
			(width 0.06985)
			(type default)
		)
		(layer "F.Cu")
	)
	(gr_line
		(start 59.078114 -10.936478)
		(end 59.293506 -10.721086)
		(stroke
			(width 0.06985)
			(type default)
		)
		(layer "F.Cu")
	)
	(gr_line
		(start 59.349894 -8.447024)
		(end 59.605672 -8.702802)
		(stroke
			(width 0.06985)
			(type default)
		)
		(layer "F.Cu")
	)
	(gr_line
		(start 59.349894 -6.195568)
		(end 59.349894 -8.447024)
		(stroke
			(width 0.06985)
			(type default)
		)
		(layer "F.Cu")
	)
	(gr_line
		(start 59.782202 -10.721086)
		(end 59.997594 -10.936478)
		(stroke
			(width 0.06985)
			(type default)
		)
		(layer "F.Cu")
	)
	(gr_line
		(start 60.094368 -8.702802)
		(end 60.349892 -8.447278)
		(stroke
			(width 0.06985)
			(type default)
		)
		(layer "F.Cu")
	)
	(gr_line
		(start 60.349892 -6.195568)
		(end 60.349892 -8.447278)
		(stroke
			(width 0.06985)
			(type default)
		)
		(layer "F.Cu")
	)
	(gr_line
		(start 63.349886 -8.447278)
		(end 63.60541 -8.702802)
		(stroke
			(width 0.06985)
			(type default)
		)
		(layer "F.Cu")
	)
	(gr_line
		(start 63.349886 -6.195568)
		(end 63.349886 -8.447278)
		(stroke
			(width 0.06985)
			(type default)
		)
		(layer "F.Cu")
	)
	(gr_line
		(start 63.627 -14.0462)
		(end 63.627 -14.7066)
		(stroke
			(width 0.06985)
			(type default)
		)
		(layer "F.Cu")
	)
	(gr_line
		(start 63.627 -13.1318)
		(end 63.763652 -12.995148)
		(stroke
			(width 0.06985)
			(type default)
		)
		(layer "F.Cu")
	)
	(gr_line
		(start 63.83655 -11.51509)
		(end 63.83655 -11.557508)
		(stroke
			(width 0.06985)
			(type default)
		)
		(layer "F.Cu")
	)
	(gr_line
		(start 64.021208 -11.17219)
		(end 64.021208 -11.214608)
		(stroke
			(width 0.06985)
			(type default)
		)
		(layer "F.Cu")
	)
	(gr_line
		(start 64.094106 -8.702802)
		(end 64.349884 -8.447024)
		(stroke
			(width 0.06985)
			(type default)
		)
		(layer "F.Cu")
	)
	(gr_line
		(start 64.252348 -12.995148)
		(end 64.389 -13.1318)
		(stroke
			(width 0.06985)
			(type default)
		)
		(layer "F.Cu")
	)
	(gr_line
		(start 64.349884 -6.195568)
		(end 64.349884 -8.447024)
		(stroke
			(width 0.06985)
			(type default)
		)
		(layer "F.Cu")
	)
	(gr_line
		(start 64.389 -14.0462)
		(end 64.389 -14.7066)
		(stroke
			(width 0.06985)
			(type default)
		)
		(layer "F.Cu")
	)
	(gr_line
		(start 67.34556 -10.28446)
		(end 67.580002 -10.050018)
		(stroke
			(width 0.06985)
			(type default)
		)
		(layer "F.Cu")
	)
	(gr_line
		(start 67.349878 -8.447278)
		(end 67.605402 -8.702802)
		(stroke
			(width 0.06985)
			(type default)
		)
		(layer "F.Cu")
	)
	(gr_line
		(start 67.349878 -6.195568)
		(end 67.349878 -8.447278)
		(stroke
			(width 0.06985)
			(type default)
		)
		(layer "F.Cu")
	)
	(gr_line
		(start 68.068698 -10.050018)
		(end 68.30314 -10.28446)
		(stroke
			(width 0.06985)
			(type default)
		)
		(layer "F.Cu")
	)
	(gr_line
		(start 68.094098 -8.702802)
		(end 68.349876 -8.447024)
		(stroke
			(width 0.06985)
			(type default)
		)
		(layer "F.Cu")
	)
	(gr_line
		(start 68.349876 -6.195568)
		(end 68.349876 -8.447024)
		(stroke
			(width 0.06985)
			(type default)
		)
		(layer "F.Cu")
	)
	(gr_line
		(start 69.13499 -28.405074)
		(end 69.33438 -28.205684)
		(stroke
			(width 0.06985)
			(type default)
		)
		(layer "F.Cu")
	)
	(gr_line
		(start 69.1388 -27.521408)
		(end 69.33438 -27.716988)
		(stroke
			(width 0.06985)
			(type default)
		)
		(layer "F.Cu")
	)
	(gr_line
		(start 71.0311 -27.12212)
		(end 71.0311 -27.25166)
		(stroke
			(width 0.06985)
			(type default)
		)
		(layer "F.Cu")
	)
	(gr_line
		(start 71.34987 -8.447278)
		(end 71.605394 -8.702802)
		(stroke
			(width 0.06985)
			(type default)
		)
		(layer "F.Cu")
	)
	(gr_line
		(start 71.34987 -6.195568)
		(end 71.34987 -8.447278)
		(stroke
			(width 0.06985)
			(type default)
		)
		(layer "F.Cu")
	)
	(gr_line
		(start 71.370952 -10.28446)
		(end 71.605394 -10.050018)
		(stroke
			(width 0.06985)
			(type default)
		)
		(layer "F.Cu")
	)
	(gr_line
		(start 71.37654 -27.59456)
		(end 71.57466 -27.39644)
		(stroke
			(width 0.06985)
			(type default)
		)
		(layer "F.Cu")
	)
	(gr_line
		(start 71.37654 -26.77922)
		(end 71.57466 -26.97734)
		(stroke
			(width 0.06985)
			(type default)
		)
		(layer "F.Cu")
	)
	(gr_line
		(start 71.57466 -26.97734)
		(end 71.57466 -27.39644)
		(stroke
			(width 0.06985)
			(type default)
		)
		(layer "F.Cu")
	)
	(gr_line
		(start 72.09409 -10.050018)
		(end 72.328532 -10.28446)
		(stroke
			(width 0.06985)
			(type default)
		)
		(layer "F.Cu")
	)
	(gr_line
		(start 72.09409 -8.702802)
		(end 72.349868 -8.447024)
		(stroke
			(width 0.06985)
			(type default)
		)
		(layer "F.Cu")
	)
	(gr_line
		(start 72.18807 -28.23083)
		(end 72.38619 -28.03271)
		(stroke
			(width 0.06985)
			(type default)
		)
		(layer "F.Cu")
	)
	(gr_line
		(start 72.349868 -6.195568)
		(end 72.349868 -8.447024)
		(stroke
			(width 0.06985)
			(type default)
		)
		(layer "F.Cu")
	)
	(gr_line
		(start 72.38619 -28.03271)
		(end 72.80529 -28.03271)
		(stroke
			(width 0.06985)
			(type default)
		)
		(layer "F.Cu")
	)
	(gr_line
		(start 72.53097 -28.57627)
		(end 72.66051 -28.57627)
		(stroke
			(width 0.06985)
			(type default)
		)
		(layer "F.Cu")
	)
	(gr_line
		(start 72.80529 -28.03271)
		(end 73.00341 -28.23083)
		(stroke
			(width 0.06985)
			(type default)
		)
		(layer "F.Cu")
	)
	(gr_line
		(start 73.42759 -28.23083)
		(end 73.62571 -28.03271)
		(stroke
			(width 0.06985)
			(type default)
		)
		(layer "F.Cu")
	)
	(gr_line
		(start 73.62571 -28.03271)
		(end 74.04481 -28.03271)
		(stroke
			(width 0.06985)
			(type default)
		)
		(layer "F.Cu")
	)
	(gr_line
		(start 73.77049 -28.57627)
		(end 73.90003 -28.57627)
		(stroke
			(width 0.06985)
			(type default)
		)
		(layer "F.Cu")
	)
	(gr_line
		(start 74.04481 -28.03271)
		(end 74.24293 -28.23083)
		(stroke
			(width 0.06985)
			(type default)
		)
		(layer "F.Cu")
	)
	(gr_line
		(start 75.349862 -8.447278)
		(end 75.605386 -8.702802)
		(stroke
			(width 0.06985)
			(type default)
		)
		(layer "F.Cu")
	)
	(gr_line
		(start 75.349862 -6.195568)
		(end 75.349862 -8.447278)
		(stroke
			(width 0.06985)
			(type default)
		)
		(layer "F.Cu")
	)
	(gr_line
		(start 75.370944 -10.28446)
		(end 75.605386 -10.050018)
		(stroke
			(width 0.06985)
			(type default)
		)
		(layer "F.Cu")
	)
	(gr_line
		(start 75.51928 -30.20568)
		(end 75.61072 -30.29712)
		(stroke
			(width 0.06985)
			(type default)
		)
		(layer "F.Cu")
	)
	(gr_line
		(start 75.520804 -29.718762)
		(end 75.801474 -29.718762)
		(stroke
			(width 0.06985)
			(type default)
		)
		(layer "F.Cu")
	)
	(gr_line
		(start 75.801474 -29.718762)
		(end 76.097638 -30.01518)
		(stroke
			(width 0.06985)
			(type default)
		)
		(layer "F.Cu")
	)
	(gr_line
		(start 76.094082 -10.050018)
		(end 76.328524 -10.28446)
		(stroke
			(width 0.06985)
			(type default)
		)
		(layer "F.Cu")
	)
	(gr_line
		(start 76.094082 -8.702802)
		(end 76.34986 -8.447024)
		(stroke
			(width 0.06985)
			(type default)
		)
		(layer "F.Cu")
	)
	(gr_line
		(start 76.097638 -30.01518)
		(end 76.097638 -30.295596)
		(stroke
			(width 0.06985)
			(type default)
		)
		(layer "F.Cu")
	)
	(gr_line
		(start 76.34986 -6.195568)
		(end 76.34986 -8.447024)
		(stroke
			(width 0.06985)
			(type default)
		)
		(layer "F.Cu")
	)
	(gr_line
		(start 76.395834 -31.082234)
		(end 76.487274 -31.173674)
		(stroke
			(width 0.06985)
			(type default)
		)
		(layer "F.Cu")
	)
	(gr_line
		(start 76.397358 -30.595316)
		(end 76.677774 -30.595316)
		(stroke
			(width 0.06985)
			(type default)
		)
		(layer "F.Cu")
	)
	(gr_line
		(start 76.5302 -48.00092)
		(end 76.794614 -48.265334)
		(stroke
			(width 0.0508)
			(type default)
		)
		(layer "F.Cu")
	)
	(gr_line
		(start 76.5302 -47.9298)
		(end 76.5302 -48.00092)
		(stroke
			(width 0.0508)
			(type default)
		)
		(layer "F.Cu")
	)
	(gr_line
		(start 76.677774 -30.595316)
		(end 76.974192 -30.89148)
		(stroke
			(width 0.06985)
			(type default)
		)
		(layer "F.Cu")
	)
	(gr_line
		(start 76.974192 -30.89148)
		(end 76.974192 -31.17215)
		(stroke
			(width 0.06985)
			(type default)
		)
		(layer "F.Cu")
	)
	(gr_line
		(start 77.08392 -48.0314)
		(end 77.08392 -48.263556)
		(stroke
			(width 0.0508)
			(type default)
		)
		(layer "F.Cu")
	)
	(gr_line
		(start 77.272134 -31.958534)
		(end 77.363574 -32.049974)
		(stroke
			(width 0.06985)
			(type default)
		)
		(layer "F.Cu")
	)
	(gr_line
		(start 77.273658 -31.471616)
		(end 77.554328 -31.471616)
		(stroke
			(width 0.06985)
			(type default)
		)
		(layer "F.Cu")
	)
	(gr_line
		(start 77.554328 -31.471616)
		(end 77.850492 -31.768034)
		(stroke
			(width 0.06985)
			(type default)
		)
		(layer "F.Cu")
	)
	(gr_line
		(start 77.850492 -31.768034)
		(end 77.850492 -32.04845)
		(stroke
			(width 0.06985)
			(type default)
		)
		(layer "F.Cu")
	)
	(gr_line
		(start 77.976476 -29.90215)
		(end 78.245462 -30.171136)
		(stroke
			(width 0.0508)
			(type default)
		)
		(layer "F.Cu")
	)
	(gr_line
		(start 78.105 -47.752)
		(end 78.700376 -47.156624)
		(stroke
			(width 0.0508)
			(type default)
		)
		(layer "F.Cu")
	)
	(gr_line
		(start 78.105 -31.199074)
		(end 78.176882 -31.270956)
		(stroke
			(width 0.06985)
			(type default)
		)
		(layer "F.Cu")
	)
	(gr_line
		(start 78.105 -31.1658)
		(end 78.105 -31.199074)
		(stroke
			(width 0.06985)
			(type default)
		)
		(layer "F.Cu")
	)
	(gr_line
		(start 78.534768 -29.896308)
		(end 78.534768 -30.169358)
		(stroke
			(width 0.0508)
			(type default)
		)
		(layer "F.Cu")
	)
	(gr_line
		(start 78.534768 -29.896308)
		(end 78.535276 -29.8958)
		(stroke
			(width 0.0508)
			(type default)
		)
		(layer "F.Cu")
	)
	(gr_line
		(start 78.6638 -47.751238)
		(end 79.052674 -47.362364)
		(stroke
			(width 0.0508)
			(type default)
		)
		(layer "F.Cu")
	)
	(gr_line
		(start 78.6638 -31.190184)
		(end 78.6638 -31.269432)
		(stroke
			(width 0.06985)
			(type default)
		)
		(layer "F.Cu")
	)
	(gr_line
		(start 78.700376 -47.156624)
		(end 78.848204 -47.156624)
		(stroke
			(width 0.0508)
			(type default)
		)
		(layer "F.Cu")
	)
	(gr_line
		(start 79.342488 -47.361094)
		(end 79.389224 -47.40783)
		(stroke
			(width 0.0508)
			(type default)
		)
		(layer "F.Cu")
	)
	(gr_line
		(start 79.349854 -8.447278)
		(end 79.605378 -8.702802)
		(stroke
			(width 0.06985)
			(type default)
		)
		(layer "F.Cu")
	)
	(gr_line
		(start 79.349854 -6.195568)
		(end 79.349854 -8.447278)
		(stroke
			(width 0.06985)
			(type default)
		)
		(layer "F.Cu")
	)
	(gr_line
		(start 79.350616 -47.156624)
		(end 79.351886 -47.157894)
		(stroke
			(width 0.0508)
			(type default)
		)
		(layer "F.Cu")
	)
	(gr_line
		(start 79.370936 -10.33526)
		(end 79.605378 -10.100818)
		(stroke
			(width 0.06985)
			(type default)
		)
		(layer "F.Cu")
	)
	(gr_line
		(start 79.487268 -33.154874)
		(end 79.601568 -33.154874)
		(stroke
			(width 0.06985)
			(type default)
		)
		(layer "F.Cu")
	)
	(gr_line
		(start 79.699104 -32.793178)
		(end 79.770732 -32.864806)
		(stroke
			(width 0.06985)
			(type default)
		)
		(layer "F.Cu")
	)
	(gr_line
		(start 79.743808 -33.497774)
		(end 79.815436 -33.426146)
		(stroke
			(width 0.06985)
			(type default)
		)
		(layer "F.Cu")
	)
	(gr_line
		(start 79.830168 -33.411414)
		(end 79.944468 -33.411414)
		(stroke
			(width 0.06985)
			(type default)
		)
		(layer "F.Cu")
	)
	(gr_line
		(start 79.947008 -33.411414)
		(end 80.602328 -33.411414)
		(stroke
			(width 0.06985)
			(type default)
		)
		(layer "F.Cu")
	)
	(gr_line
		(start 79.997808 -30.713934)
		(end 80.096868 -30.812994)
		(stroke
			(width 0.0508)
			(type default)
		)
		(layer "F.Cu")
	)
	(gr_line
		(start 80.066388 -33.147254)
		(end 80.166718 -33.147254)
		(stroke
			(width 0.06985)
			(type default)
		)
		(layer "F.Cu")
	)
	(gr_line
		(start 80.094074 -10.100818)
		(end 80.328516 -10.33526)
		(stroke
			(width 0.06985)
			(type default)
		)
		(layer "F.Cu")
	)
	(gr_line
		(start 80.094074 -8.702802)
		(end 80.349852 -8.447024)
		(stroke
			(width 0.06985)
			(type default)
		)
		(layer "F.Cu")
	)
	(gr_line
		(start 80.124554 -31.297626)
		(end 80.28178 -31.1404)
		(stroke
			(width 0.06985)
			(type default)
		)
		(layer "F.Cu")
	)
	(gr_line
		(start 80.201008 -30.508194)
		(end 80.22336 -30.508194)
		(stroke
			(width 0.0508)
			(type default)
		)
		(layer "F.Cu")
	)
	(gr_line
		(start 80.22336 -30.508194)
		(end 81.054448 -30.759654)
		(stroke
			(width 0.0508)
			(type default)
		)
		(layer "F.Cu")
	)
	(gr_line
		(start 80.241648 -48.280066)
		(end 80.419956 -48.458374)
		(stroke
			(width 0.0508)
			(type default)
		)
		(layer "F.Cu")
	)
	(gr_line
		(start 80.241648 -48.260254)
		(end 80.241648 -48.280066)
		(stroke
			(width 0.0508)
			(type default)
		)
		(layer "F.Cu")
	)
	(gr_line
		(start 80.250538 -33.147254)
		(end 80.390746 -33.147254)
		(stroke
			(width 0.06985)
			(type default)
		)
		(layer "F.Cu")
	)
	(gr_line
		(start 80.264 -60.3758)
		(end 80.413352 -60.525152)
		(stroke
			(width 0.06985)
			(type default)
		)
		(layer "F.Cu")
	)
	(gr_line
		(start 80.28178 -31.1404)
		(end 80.449674 -31.1404)
		(stroke
			(width 0.06985)
			(type default)
		)
		(layer "F.Cu")
	)
	(gr_line
		(start 80.349852 -6.195568)
		(end 80.349852 -8.447024)
		(stroke
			(width 0.06985)
			(type default)
		)
		(layer "F.Cu")
	)
	(gr_line
		(start 80.390746 -33.147254)
		(end 80.738726 -32.799274)
		(stroke
			(width 0.06985)
			(type default)
		)
		(layer "F.Cu")
	)
	(gr_line
		(start 80.419956 -48.458374)
		(end 80.673194 -48.458374)
		(stroke
			(width 0.0508)
			(type default)
		)
		(layer "F.Cu")
	)
	(gr_line
		(start 80.422496 -48.153574)
		(end 80.444848 -48.153574)
		(stroke
			(width 0.0508)
			(type default)
		)
		(layer "F.Cu")
	)
	(gr_line
		(start 80.447388 -48.153574)
		(end 80.546448 -48.153574)
		(stroke
			(width 0.0508)
			(type default)
		)
		(layer "F.Cu")
	)
	(gr_line
		(start 80.449674 -31.1404)
		(end 80.607408 -31.298134)
		(stroke
			(width 0.06985)
			(type default)
		)
		(layer "F.Cu")
	)
	(gr_line
		(start 80.478376 -49.78654)
		(end 80.48244 -49.790604)
		(stroke
			(width 0.06985)
			(type default)
		)
		(layer "F.Cu")
	)
	(gr_line
		(start 80.48244 -49.88814)
		(end 81.280254 -50.685954)
		(stroke
			(width 0.06985)
			(type default)
		)
		(layer "F.Cu")
	)
	(gr_line
		(start 80.48244 -49.790604)
		(end 80.48244 -49.88814)
		(stroke
			(width 0.06985)
			(type default)
		)
		(layer "F.Cu")
	)
	(gr_line
		(start 80.551528 -49.285906)
		(end 80.551528 -49.309274)
		(stroke
			(width 0.0508)
			(type default)
		)
		(layer "F.Cu")
	)
	(gr_line
		(start 80.56118 -49.004474)
		(end 80.67802 -49.004474)
		(stroke
			(width 0.0508)
			(type default)
		)
		(layer "F.Cu")
	)
	(gr_line
		(start 80.5688 -54.6862)
		(end 80.684878 -54.570122)
		(stroke
			(width 0.0635)
			(type default)
		)
		(layer "F.Cu")
	)
	(gr_line
		(start 80.5688 -54.1274)
		(end 80.684878 -54.243478)
		(stroke
			(width 0.0635)
			(type default)
		)
		(layer "F.Cu")
	)
	(gr_line
		(start 80.673194 -48.458374)
		(end 81.028794 -48.102774)
		(stroke
			(width 0.0508)
			(type default)
		)
		(layer "F.Cu")
	)
	(gr_line
		(start 80.67802 -49.004474)
		(end 80.856328 -49.182782)
		(stroke
			(width 0.0508)
			(type default)
		)
		(layer "F.Cu")
	)
	(gr_line
		(start 80.686656 -54.568344)
		(end 80.7466 -54.5084)
		(stroke
			(width 0.0635)
			(type default)
		)
		(layer "F.Cu")
	)
	(gr_line
		(start 80.686656 -54.245256)
		(end 80.7212 -54.2798)
		(stroke
			(width 0.0635)
			(type default)
		)
		(layer "F.Cu")
	)
	(gr_line
		(start 80.738726 -32.799274)
		(end 80.950308 -32.799274)
		(stroke
			(width 0.06985)
			(type default)
		)
		(layer "F.Cu")
	)
	(gr_line
		(start 80.856328 -49.802034)
		(end 80.950308 -49.896014)
		(stroke
			(width 0.0508)
			(type default)
		)
		(layer "F.Cu")
	)
	(gr_line
		(start 80.856328 -49.182782)
		(end 80.856328 -49.802034)
		(stroke
			(width 0.0508)
			(type default)
		)
		(layer "F.Cu")
	)
	(gr_line
		(start 80.902048 -60.525152)
		(end 81.0514 -60.3758)
		(stroke
			(width 0.06985)
			(type default)
		)
		(layer "F.Cu")
	)
	(gr_line
		(start 81.028794 -48.102774)
		(end 81.308448 -48.102774)
		(stroke
			(width 0.0508)
			(type default)
		)
		(layer "F.Cu")
	)
	(gr_line
		(start 81.050384 -28.7782)
		(end 81.18856 -28.7782)
		(stroke
			(width 0.0508)
			(type default)
		)
		(layer "F.Cu")
	)
	(gr_line
		(start 81.097628 -29.410914)
		(end 81.3308 -29.410914)
		(stroke
			(width 0.0508)
			(type default)
		)
		(layer "F.Cu")
	)
	(gr_line
		(start 81.132172 -31.29915)
		(end 81.141316 -31.308294)
		(stroke
			(width 0.06985)
			(type default)
		)
		(layer "F.Cu")
	)
	(gr_line
		(start 81.141316 -31.308294)
		(end 81.768188 -31.308294)
		(stroke
			(width 0.06985)
			(type default)
		)
		(layer "F.Cu")
	)
	(gr_line
		(start 81.18856 -28.7782)
		(end 81.326228 -28.915868)
		(stroke
			(width 0.0508)
			(type default)
		)
		(layer "F.Cu")
	)
	(gr_line
		(start 81.229454 -49.59604)
		(end 81.646268 -50.012854)
		(stroke
			(width 0.06985)
			(type default)
		)
		(layer "F.Cu")
	)
	(gr_line
		(start 81.229454 -49.50206)
		(end 81.229454 -49.59604)
		(stroke
			(width 0.06985)
			(type default)
		)
		(layer "F.Cu")
	)
	(gr_line
		(start 81.280254 -50.685954)
		(end 81.364328 -50.685954)
		(stroke
			(width 0.06985)
			(type default)
		)
		(layer "F.Cu")
	)
	(gr_line
		(start 81.3308 -29.410914)
		(end 81.42859 -29.313124)
		(stroke
			(width 0.0508)
			(type default)
		)
		(layer "F.Cu")
	)
	(gr_line
		(start 81.42859 -29.209746)
		(end 81.42859 -29.313124)
		(stroke
			(width 0.0508)
			(type default)
		)
		(layer "F.Cu")
	)
	(gr_line
		(start 81.42859 -29.188156)
		(end 81.42859 -29.207206)
		(stroke
			(width 0.0508)
			(type default)
		)
		(layer "F.Cu")
	)
	(gr_line
		(start 81.531968 -28.984956)
		(end 81.531968 -29.004006)
		(stroke
			(width 0.0508)
			(type default)
		)
		(layer "F.Cu")
	)
	(gr_line
		(start 81.531968 -28.49372)
		(end 81.531968 -28.712668)
		(stroke
			(width 0.0508)
			(type default)
		)
		(layer "F.Cu")
	)
	(gr_line
		(start 81.6864 -53.594)
		(end 81.815178 -53.465222)
		(stroke
			(width 0.0635)
			(type default)
		)
		(layer "F.Cu")
	)
	(gr_line
		(start 81.6864 -53.0098)
		(end 81.815178 -53.138578)
		(stroke
			(width 0.0635)
			(type default)
		)
		(layer "F.Cu")
	)
	(gr_line
		(start 81.717896 -29.189934)
		(end 81.785968 -29.258006)
		(stroke
			(width 0.0508)
			(type default)
		)
		(layer "F.Cu")
	)
	(gr_line
		(start 81.785968 -29.258006)
		(end 81.785968 -29.578554)
		(stroke
			(width 0.0508)
			(type default)
		)
		(layer "F.Cu")
	)
	(gr_line
		(start 81.816956 -53.463444)
		(end 81.8388 -53.4416)
		(stroke
			(width 0.0635)
			(type default)
		)
		(layer "F.Cu")
	)
	(gr_line
		(start 81.816956 -53.140356)
		(end 81.8896 -53.213)
		(stroke
			(width 0.0635)
			(type default)
		)
		(layer "F.Cu")
	)
	(gr_line
		(start 81.853024 -50.448972)
		(end 82.046572 -50.448972)
		(stroke
			(width 0.06985)
			(type default)
		)
		(layer "F.Cu")
	)
	(gr_line
		(start 82.010504 -54.27726)
		(end 82.107024 -54.18074)
		(stroke
			(width 0.0635)
			(type default)
		)
		(layer "F.Cu")
	)
	(gr_line
		(start 82.046572 -50.448972)
		(end 82.238088 -50.640488)
		(stroke
			(width 0.06985)
			(type default)
		)
		(layer "F.Cu")
	)
	(gr_line
		(start 82.107024 -54.18074)
		(end 82.488024 -54.18074)
		(stroke
			(width 0.0635)
			(type default)
		)
		(layer "F.Cu")
	)
	(gr_line
		(start 82.126074 -49.960784)
		(end 82.445098 -49.960784)
		(stroke
			(width 0.06985)
			(type default)
		)
		(layer "F.Cu")
	)
	(gr_line
		(start 82.238088 -50.640488)
		(end 82.238088 -50.741834)
		(stroke
			(width 0.06985)
			(type default)
		)
		(layer "F.Cu")
	)
	(gr_line
		(start 82.239104 -54.5084)
		(end 82.355944 -54.5084)
		(stroke
			(width 0.0635)
			(type default)
		)
		(layer "F.Cu")
	)
	(gr_line
		(start 82.445098 -49.960784)
		(end 82.748628 -50.264314)
		(stroke
			(width 0.06985)
			(type default)
		)
		(layer "F.Cu")
	)
	(gr_line
		(start 82.488024 -54.18074)
		(end 82.584544 -54.27726)
		(stroke
			(width 0.0635)
			(type default)
		)
		(layer "F.Cu")
	)
	(gr_line
		(start 82.713068 -51.39055)
		(end 82.916268 -51.18735)
		(stroke
			(width 0.06985)
			(type default)
		)
		(layer "F.Cu")
	)
	(gr_line
		(start 82.916268 -50.952654)
		(end 82.916268 -51.18735)
		(stroke
			(width 0.06985)
			(type default)
		)
		(layer "F.Cu")
	)
	(gr_line
		(start 82.9437 -48.6664)
		(end 83.060794 -48.783494)
		(stroke
			(width 0.06985)
			(type default)
		)
		(layer "F.Cu")
	)
	(gr_line
		(start 83.0199 -49.2506)
		(end 83.167474 -49.2506)
		(stroke
			(width 0.06985)
			(type default)
		)
		(layer "F.Cu")
	)
	(gr_line
		(start 83.060794 -48.783494)
		(end 83.462368 -48.783494)
		(stroke
			(width 0.06985)
			(type default)
		)
		(layer "F.Cu")
	)
	(gr_line
		(start 83.064096 -55.886096)
		(end 83.0961 -55.886096)
		(stroke
			(width 0.06985)
			(type default)
		)
		(layer "F.Cu")
	)
	(gr_line
		(start 83.09864 -55.886096)
		(end 83.213956 -55.886096)
		(stroke
			(width 0.06985)
			(type default)
		)
		(layer "F.Cu")
	)
	(gr_line
		(start 83.112864 -51.664616)
		(end 83.112864 -51.791108)
		(stroke
			(width 0.06985)
			(type default)
		)
		(layer "F.Cu")
	)
	(gr_line
		(start 83.112864 -51.664616)
		(end 83.334606 -51.442874)
		(stroke
			(width 0.06985)
			(type default)
		)
		(layer "F.Cu")
	)
	(gr_line
		(start 83.167474 -49.2506)
		(end 83.462368 -49.545494)
		(stroke
			(width 0.06985)
			(type default)
		)
		(layer "F.Cu")
	)
	(gr_line
		(start 83.266788 -30.785054)
		(end 83.5914 -30.460442)
		(stroke
			(width 0.06985)
			(type default)
		)
		(layer "F.Cu")
	)
	(gr_line
		(start 83.334606 -51.442874)
		(end 83.447128 -51.442874)
		(stroke
			(width 0.06985)
			(type default)
		)
		(layer "F.Cu")
	)
	(gr_line
		(start 83.349846 -8.447278)
		(end 83.60537 -8.702802)
		(stroke
			(width 0.06985)
			(type default)
		)
		(layer "F.Cu")
	)
	(gr_line
		(start 83.349846 -6.195568)
		(end 83.349846 -8.447278)
		(stroke
			(width 0.06985)
			(type default)
		)
		(layer "F.Cu")
	)
	(gr_line
		(start 83.388962 -10.41273)
		(end 83.60537 -10.196322)
		(stroke
			(width 0.06985)
			(type default)
		)
		(layer "F.Cu")
	)
	(gr_line
		(start 83.44154 -55.543196)
		(end 83.44154 -55.62854)
		(stroke
			(width 0.06985)
			(type default)
		)
		(layer "F.Cu")
	)
	(gr_line
		(start 83.44154 -55.45328)
		(end 83.44154 -55.540656)
		(stroke
			(width 0.06985)
			(type default)
		)
		(layer "F.Cu")
	)
	(gr_line
		(start 83.55203 -59.904884)
		(end 83.764628 -59.904884)
		(stroke
			(width 0.06985)
			(type default)
		)
		(layer "F.Cu")
	)
	(gr_line
		(start 83.5914 -30.460442)
		(end 83.67141 -30.460442)
		(stroke
			(width 0.06985)
			(type default)
		)
		(layer "F.Cu")
	)
	(gr_line
		(start 83.644232 -31.086044)
		(end 83.727798 -31.086044)
		(stroke
			(width 0.06985)
			(type default)
		)
		(layer "F.Cu")
	)
	(gr_line
		(start 83.708748 -51.7398)
		(end 83.708748 -51.970686)
		(stroke
			(width 0.0635)
			(type default)
		)
		(layer "F.Cu")
	)
	(gr_line
		(start 83.708748 -51.7398)
		(end 84.056728 -51.099974)
		(stroke
			(width 0.0635)
			(type default)
		)
		(layer "F.Cu")
	)
	(gr_line
		(start 83.727798 -31.086044)
		(end 84.028788 -30.785054)
		(stroke
			(width 0.06985)
			(type default)
		)
		(layer "F.Cu")
	)
	(gr_line
		(start 83.767168 -59.904884)
		(end 83.829144 -59.904884)
		(stroke
			(width 0.06985)
			(type default)
		)
		(layer "F.Cu")
	)
	(gr_line
		(start 83.812888 -49.870614)
		(end 83.812888 -49.8856)
		(stroke
			(width 0.06985)
			(type default)
		)
		(layer "F.Cu")
	)
	(gr_line
		(start 83.812888 -49.870614)
		(end 84.138008 -49.545494)
		(stroke
			(width 0.06985)
			(type default)
		)
		(layer "F.Cu")
	)
	(gr_line
		(start 83.812888 -49.134014)
		(end 83.812888 -49.163986)
		(stroke
			(width 0.06985)
			(type default)
		)
		(layer "F.Cu")
	)
	(gr_line
		(start 83.812888 -49.134014)
		(end 84.163408 -48.783494)
		(stroke
			(width 0.06985)
			(type default)
		)
		(layer "F.Cu")
	)
	(gr_line
		(start 83.8454 -25.4508)
		(end 83.880452 -25.415748)
		(stroke
			(width 0.06985)
			(type default)
		)
		(layer "F.Cu")
	)
	(gr_line
		(start 83.8454 -24.892)
		(end 83.880452 -24.927052)
		(stroke
			(width 0.06985)
			(type default)
		)
		(layer "F.Cu")
	)
	(gr_line
		(start 83.879182 -56.751982)
		(end 84.1756 -57.0484)
		(stroke
			(width 0.06985)
			(type default)
		)
		(layer "F.Cu")
	)
	(gr_line
		(start 83.879182 -56.554624)
		(end 83.879182 -56.751982)
		(stroke
			(width 0.06985)
			(type default)
		)
		(layer "F.Cu")
	)
	(gr_line
		(start 84.026248 -51.839114)
		(end 84.026248 -51.961288)
		(stroke
			(width 0.0635)
			(type default)
		)
		(layer "F.Cu")
	)
	(gr_line
		(start 84.094066 -10.196322)
		(end 84.310474 -10.41273)
		(stroke
			(width 0.06985)
			(type default)
		)
		(layer "F.Cu")
	)
	(gr_line
		(start 84.094066 -8.702802)
		(end 84.349844 -8.447024)
		(stroke
			(width 0.06985)
			(type default)
		)
		(layer "F.Cu")
	)
	(gr_line
		(start 84.110068 -59.561984)
		(end 84.110068 -59.700668)
		(stroke
			(width 0.06985)
			(type default)
		)
		(layer "F.Cu")
	)
	(gr_line
		(start 84.110068 -59.349132)
		(end 84.110068 -59.559444)
		(stroke
			(width 0.06985)
			(type default)
		)
		(layer "F.Cu")
	)
	(gr_line
		(start 84.138008 -49.545494)
		(end 84.163408 -49.545494)
		(stroke
			(width 0.06985)
			(type default)
		)
		(layer "F.Cu")
	)
	(gr_line
		(start 84.1756 -57.0484)
		(end 84.372958 -57.0484)
		(stroke
			(width 0.06985)
			(type default)
		)
		(layer "F.Cu")
	)
	(gr_line
		(start 84.230464 -54.57444)
		(end 84.369656 -54.435248)
		(stroke
			(width 0.0508)
			(type default)
		)
		(layer "F.Cu")
	)
	(gr_line
		(start 84.231988 -26.558494)
		(end 84.44103 -26.558494)
		(stroke
			(width 0.06985)
			(type default)
		)
		(layer "F.Cu")
	)
	(gr_line
		(start 84.239608 -27.300174)
		(end 84.485734 -27.300174)
		(stroke
			(width 0.06985)
			(type default)
		)
		(layer "F.Cu")
	)
	(gr_line
		(start 84.241132 -54.01564)
		(end 84.369656 -54.144164)
		(stroke
			(width 0.0508)
			(type default)
		)
		(layer "F.Cu")
	)
	(gr_line
		(start 84.349844 -6.195568)
		(end 84.349844 -8.447024)
		(stroke
			(width 0.06985)
			(type default)
		)
		(layer "F.Cu")
	)
	(gr_line
		(start 84.3661 -56.5531)
		(end 84.374482 -56.561482)
		(stroke
			(width 0.06985)
			(type default)
		)
		(layer "F.Cu")
	)
	(gr_line
		(start 84.371434 -54.43347)
		(end 84.398104 -54.4068)
		(stroke
			(width 0.0508)
			(type default)
		)
		(layer "F.Cu")
	)
	(gr_line
		(start 84.371434 -54.145942)
		(end 84.429092 -54.2036)
		(stroke
			(width 0.0508)
			(type default)
		)
		(layer "F.Cu")
	)
	(gr_line
		(start 84.44103 -26.558494)
		(end 84.661502 -26.338022)
		(stroke
			(width 0.06985)
			(type default)
		)
		(layer "F.Cu")
	)
	(gr_line
		(start 84.485734 -27.300174)
		(end 84.692236 -27.093672)
		(stroke
			(width 0.06985)
			(type default)
		)
		(layer "F.Cu")
	)
	(gr_line
		(start 84.504784 -51.8414)
		(end 84.945728 -51.099974)
		(stroke
			(width 0.0635)
			(type default)
		)
		(layer "F.Cu")
	)
	(gr_line
		(start 84.717636 -29.98216)
		(end 84.73313 -29.997654)
		(stroke
			(width 0.06985)
			(type default)
		)
		(layer "F.Cu")
	)
	(gr_line
		(start 84.73313 -29.997654)
		(end 85.687408 -29.997654)
		(stroke
			(width 0.06985)
			(type default)
		)
		(layer "F.Cu")
	)
	(gr_line
		(start 84.734654 -30.607)
		(end 84.887308 -30.759654)
		(stroke
			(width 0.06985)
			(type default)
		)
		(layer "F.Cu")
	)
	(gr_line
		(start 84.735924 -52.059078)
		(end 84.953348 -51.841654)
		(stroke
			(width 0.0635)
			(type default)
		)
		(layer "F.Cu")
	)
	(gr_line
		(start 84.768944 -54.4068)
		(end 84.806028 -54.369716)
		(stroke
			(width 0.0508)
			(type default)
		)
		(layer "F.Cu")
	)
	(gr_line
		(start 84.834984 -48.784002)
		(end 85.06714 -48.784002)
		(stroke
			(width 0.06985)
			(type default)
		)
		(layer "F.Cu")
	)
	(gr_line
		(start 84.887308 -30.759654)
		(end 85.687408 -30.759654)
		(stroke
			(width 0.06985)
			(type default)
		)
		(layer "F.Cu")
	)
	(gr_line
		(start 85.015578 -48.103282)
		(end 85.448648 -47.670212)
		(stroke
			(width 0.06985)
			(type default)
		)
		(layer "F.Cu")
	)
	(gr_line
		(start 85.06714 -48.784002)
		(end 85.448648 -48.402494)
		(stroke
			(width 0.06985)
			(type default)
		)
		(layer "F.Cu")
	)
	(gr_line
		(start 85.1916 -49.877726)
		(end 85.527388 -50.213514)
		(stroke
			(width 0.06985)
			(type default)
		)
		(layer "F.Cu")
	)
	(gr_line
		(start 85.1916 -49.8602)
		(end 85.1916 -49.877726)
		(stroke
			(width 0.06985)
			(type default)
		)
		(layer "F.Cu")
	)
	(gr_line
		(start 85.277706 -50.626518)
		(end 85.557868 -50.90668)
		(stroke
			(width 0.06985)
			(type default)
		)
		(layer "F.Cu")
	)
	(gr_line
		(start 85.448648 -47.640494)
		(end 85.448648 -47.670212)
		(stroke
			(width 0.06985)
			(type default)
		)
		(layer "F.Cu")
	)
	(gr_line
		(start 85.510116 -53.664612)
		(end 85.5472 -53.627528)
		(stroke
			(width 0.0508)
			(type default)
		)
		(layer "F.Cu")
	)
	(gr_line
		(start 85.5345 -24.308816)
		(end 85.637116 -24.2062)
		(stroke
			(width 0.06985)
			(type default)
		)
		(layer "F.Cu")
	)
	(gr_line
		(start 85.5345 -23.749)
		(end 85.6234 -23.8379)
		(stroke
			(width 0.06985)
			(type default)
		)
		(layer "F.Cu")
	)
	(gr_line
		(start 85.553804 -52.706524)
		(end 85.580728 -52.6796)
		(stroke
			(width 0.0508)
			(type default)
		)
		(layer "F.Cu")
	)
	(gr_line
		(start 85.557868 -50.90668)
		(end 85.557868 -51.447954)
		(stroke
			(width 0.06985)
			(type default)
		)
		(layer "F.Cu")
	)
	(gr_line
		(start 85.6234 -23.8379)
		(end 86.0933 -23.8379)
		(stroke
			(width 0.06985)
			(type default)
		)
		(layer "F.Cu")
	)
	(gr_line
		(start 85.637116 -24.2062)
		(end 85.973158 -24.2062)
		(stroke
			(width 0.06985)
			(type default)
		)
		(layer "F.Cu")
	)
	(gr_line
		(start 85.65134 -25.3619)
		(end 85.7123 -25.3619)
		(stroke
			(width 0.06985)
			(type default)
		)
		(layer "F.Cu")
	)
	(gr_line
		(start 85.675978 -55.362094)
		(end 85.817964 -55.220108)
		(stroke
			(width 0.0508)
			(type default)
		)
		(layer "F.Cu")
	)
	(gr_line
		(start 85.684614 -54.795674)
		(end 85.817964 -54.929024)
		(stroke
			(width 0.0508)
			(type default)
		)
		(layer "F.Cu")
	)
	(gr_line
		(start 85.783928 -52.64912)
		(end 85.810852 -52.622196)
		(stroke
			(width 0.0508)
			(type default)
		)
		(layer "F.Cu")
	)
	(gr_line
		(start 85.8012 -48.8188)
		(end 85.805772 -48.8188)
		(stroke
			(width 0.06985)
			(type default)
		)
		(layer "F.Cu")
	)
	(gr_line
		(start 85.8012 -48.0568)
		(end 85.805772 -48.0568)
		(stroke
			(width 0.06985)
			(type default)
		)
		(layer "F.Cu")
	)
	(gr_line
		(start 85.805772 -48.8188)
		(end 86.149688 -49.162716)
		(stroke
			(width 0.06985)
			(type default)
		)
		(layer "F.Cu")
	)
	(gr_line
		(start 85.805772 -48.0568)
		(end 86.149688 -48.400716)
		(stroke
			(width 0.06985)
			(type default)
		)
		(layer "F.Cu")
	)
	(gr_line
		(start 85.819742 -55.21833)
		(end 85.874352 -55.16372)
		(stroke
			(width 0.0508)
			(type default)
		)
		(layer "F.Cu")
	)
	(gr_line
		(start 85.819742 -54.930802)
		(end 85.84946 -54.96052)
		(stroke
			(width 0.0508)
			(type default)
		)
		(layer "F.Cu")
	)
	(gr_line
		(start 85.982048 -52.006754)
		(end 85.982048 -52.159916)
		(stroke
			(width 0.0508)
			(type default)
		)
		(layer "F.Cu")
	)
	(gr_line
		(start 85.99424 -25.1587)
		(end 86.0552 -25.1587)
		(stroke
			(width 0.06985)
			(type default)
		)
		(layer "F.Cu")
	)
	(gr_line
		(start 86.060788 -50.952654)
		(end 86.286848 -51.880262)
		(stroke
			(width 0.0508)
			(type default)
		)
		(layer "F.Cu")
	)
	(gr_line
		(start 86.087204 -53.765196)
		(end 86.228682 -53.623718)
		(stroke
			(width 0.0508)
			(type default)
		)
		(layer "F.Cu")
	)
	(gr_line
		(start 86.097618 -53.20157)
		(end 86.228682 -53.332634)
		(stroke
			(width 0.0508)
			(type default)
		)
		(layer "F.Cu")
	)
	(gr_line
		(start 86.149688 -49.162716)
		(end 86.149688 -49.164494)
		(stroke
			(width 0.06985)
			(type default)
		)
		(layer "F.Cu")
	)
	(gr_line
		(start 86.149688 -48.400716)
		(end 86.149688 -48.402494)
		(stroke
			(width 0.06985)
			(type default)
		)
		(layer "F.Cu")
	)
	(gr_line
		(start 86.23046 -53.62194)
		(end 86.3092 -53.5432)
		(stroke
			(width 0.0508)
			(type default)
		)
		(layer "F.Cu")
	)
	(gr_line
		(start 86.23046 -53.334412)
		(end 86.236048 -53.34)
		(stroke
			(width 0.0508)
			(type default)
		)
		(layer "F.Cu")
	)
	(gr_line
		(start 86.271354 -52.161694)
		(end 86.286848 -52.1462)
		(stroke
			(width 0.0508)
			(type default)
		)
		(layer "F.Cu")
	)
	(gr_line
		(start 86.286848 -51.880262)
		(end 86.286848 -52.1462)
		(stroke
			(width 0.0508)
			(type default)
		)
		(layer "F.Cu")
	)
	(gr_line
		(start 86.487508 -51.75504)
		(end 86.503002 -51.770534)
		(stroke
			(width 0.0508)
			(type default)
		)
		(layer "F.Cu")
	)
	(gr_line
		(start 86.487508 -51.3842)
		(end 86.487508 -51.75504)
		(stroke
			(width 0.0508)
			(type default)
		)
		(layer "F.Cu")
	)
	(gr_line
		(start 86.487508 -51.3842)
		(end 86.741508 -50.741834)
		(stroke
			(width 0.0508)
			(type default)
		)
		(layer "F.Cu")
	)
	(gr_line
		(start 86.792308 -51.503834)
		(end 86.792308 -51.768756)
		(stroke
			(width 0.0508)
			(type default)
		)
		(layer "F.Cu")
	)
	(gr_line
		(start 86.927182 -47.152306)
		(end 87.303102 -46.776386)
		(stroke
			(width 0.06985)
			(type default)
		)
		(layer "F.Cu")
	)
	(gr_line
		(start 86.954106 -48.82515)
		(end 86.9569 -48.82515)
		(stroke
			(width 0.06985)
			(type default)
		)
		(layer "F.Cu")
	)
	(gr_line
		(start 86.954868 -48.266096)
		(end 87.190326 -48.266096)
		(stroke
			(width 0.06985)
			(type default)
		)
		(layer "F.Cu")
	)
	(gr_line
		(start 86.9569 -48.824896)
		(end 86.9569 -48.82515)
		(stroke
			(width 0.06985)
			(type default)
		)
		(layer "F.Cu")
	)
	(gr_line
		(start 86.9569 -48.824896)
		(end 86.998302 -48.783494)
		(stroke
			(width 0.06985)
			(type default)
		)
		(layer "F.Cu")
	)
	(gr_line
		(start 86.998302 -48.783494)
		(end 87.434928 -48.783494)
		(stroke
			(width 0.06985)
			(type default)
		)
		(layer "F.Cu")
	)
	(gr_line
		(start 87.172292 -54.84114)
		(end 87.314278 -54.699154)
		(stroke
			(width 0.0508)
			(type default)
		)
		(layer "F.Cu")
	)
	(gr_line
		(start 87.183468 -54.27726)
		(end 87.314278 -54.40807)
		(stroke
			(width 0.0508)
			(type default)
		)
		(layer "F.Cu")
	)
	(gr_line
		(start 87.190326 -48.266096)
		(end 87.434928 -48.021494)
		(stroke
			(width 0.06985)
			(type default)
		)
		(layer "F.Cu")
	)
	(gr_line
		(start 87.316056 -54.697376)
		(end 87.339932 -54.6735)
		(stroke
			(width 0.0508)
			(type default)
		)
		(layer "F.Cu")
	)
	(gr_line
		(start 87.316056 -54.409848)
		(end 87.376508 -54.4703)
		(stroke
			(width 0.0508)
			(type default)
		)
		(layer "F.Cu")
	)
	(gr_line
		(start 87.363808 -26.535634)
		(end 87.435436 -26.607262)
		(stroke
			(width 0.06985)
			(type default)
		)
		(layer "F.Cu")
	)
	(gr_line
		(start 87.409528 -50.995834)
		(end 87.767668 -51.826922)
		(stroke
			(width 0.0508)
			(type default)
		)
		(layer "F.Cu")
	)
	(gr_line
		(start 87.434928 -45.735494)
		(end 87.434928 -46.012354)
		(stroke
			(width 0.06985)
			(type default)
		)
		(layer "F.Cu")
	)
	(gr_line
		(start 87.462868 -51.953414)
		(end 87.561928 -52.052474)
		(stroke
			(width 0.0508)
			(type default)
		)
		(layer "F.Cu")
	)
	(gr_line
		(start 87.49284 -26.664666)
		(end 87.627968 -26.799794)
		(stroke
			(width 0.06985)
			(type default)
		)
		(layer "F.Cu")
	)
	(gr_line
		(start 87.627968 -26.799794)
		(end 87.627968 -27.447494)
		(stroke
			(width 0.06985)
			(type default)
		)
		(layer "F.Cu")
	)
	(gr_line
		(start 87.757 -48.388016)
		(end 88.135968 -48.766984)
		(stroke
			(width 0.06985)
			(type default)
		)
		(layer "F.Cu")
	)
	(gr_line
		(start 87.757 -48.387)
		(end 87.757 -48.388016)
		(stroke
			(width 0.06985)
			(type default)
		)
		(layer "F.Cu")
	)
	(gr_line
		(start 87.757 -46.863)
		(end 88.122506 -46.497494)
		(stroke
			(width 0.06985)
			(type default)
		)
		(layer "F.Cu")
	)
	(gr_line
		(start 87.757762 -49.142396)
		(end 87.781384 -49.166018)
		(stroke
			(width 0.06985)
			(type default)
		)
		(layer "F.Cu")
	)
	(gr_line
		(start 87.767668 -51.826922)
		(end 87.767668 -51.849274)
		(stroke
			(width 0.0508)
			(type default)
		)
		(layer "F.Cu")
	)
	(gr_line
		(start 87.781384 -49.19091)
		(end 88.135968 -49.545494)
		(stroke
			(width 0.06985)
			(type default)
		)
		(layer "F.Cu")
	)
	(gr_line
		(start 87.781384 -49.166018)
		(end 87.781384 -49.19091)
		(stroke
			(width 0.06985)
			(type default)
		)
		(layer "F.Cu")
	)
	(gr_line
		(start 87.790274 -47.60468)
		(end 88.13546 -47.259494)
		(stroke
			(width 0.06985)
			(type default)
		)
		(layer "F.Cu")
	)
	(gr_line
		(start 87.948008 -51.442874)
		(end 88.21801 -51.989736)
		(stroke
			(width 0.0508)
			(type default)
		)
		(layer "F.Cu")
	)
	(gr_line
		(start 88.035384 -30.013402)
		(end 88.374728 -30.352746)
		(stroke
			(width 0.06985)
			(type default)
		)
		(layer "F.Cu")
	)
	(gr_line
		(start 88.035384 -29.251402)
		(end 88.374728 -29.590746)
		(stroke
			(width 0.06985)
			(type default)
		)
		(layer "F.Cu")
	)
	(gr_line
		(start 88.122506 -46.497494)
		(end 88.135968 -46.497494)
		(stroke
			(width 0.06985)
			(type default)
		)
		(layer "F.Cu")
	)
	(gr_line
		(start 88.13546 -47.259494)
		(end 88.135968 -47.259494)
		(stroke
			(width 0.06985)
			(type default)
		)
		(layer "F.Cu")
	)
	(gr_line
		(start 88.135968 -48.766984)
		(end 88.135968 -48.783494)
		(stroke
			(width 0.06985)
			(type default)
		)
		(layer "F.Cu")
	)
	(gr_line
		(start 88.179148 -52.448714)
		(end 88.466168 -52.735734)
		(stroke
			(width 0.0508)
			(type default)
		)
		(layer "F.Cu")
	)
	(gr_line
		(start 88.21801 -51.989736)
		(end 88.671908 -52.443634)
		(stroke
			(width 0.0508)
			(type default)
		)
		(layer "F.Cu")
	)
	(gr_line
		(start 88.288622 -53.402738)
		(end 88.288622 -53.410358)
		(stroke
			(width 0.0508)
			(type default)
		)
		(layer "F.Cu")
	)
	(gr_line
		(start 88.288622 -53.402738)
		(end 88.466168 -53.225192)
		(stroke
			(width 0.0508)
			(type default)
		)
		(layer "F.Cu")
	)
	(gr_line
		(start 88.306656 -53.968904)
		(end 88.671908 -53.603652)
		(stroke
			(width 0.0508)
			(type default)
		)
		(layer "F.Cu")
	)
	(gr_line
		(start 88.374728 -30.352746)
		(end 88.374728 -30.378654)
		(stroke
			(width 0.06985)
			(type default)
		)
		(layer "F.Cu")
	)
	(gr_line
		(start 88.374728 -29.590746)
		(end 88.374728 -29.616654)
		(stroke
			(width 0.06985)
			(type default)
		)
		(layer "F.Cu")
	)
	(gr_line
		(start 88.529668 -52.013866)
		(end 88.605106 -52.089304)
		(stroke
			(width 0.0508)
			(type default)
		)
		(layer "F.Cu")
	)
	(gr_line
		(start 88.529668 -51.839114)
		(end 88.529668 -52.013866)
		(stroke
			(width 0.0508)
			(type default)
		)
		(layer "F.Cu")
	)
	(gr_line
		(start 88.560148 -51.099974)
		(end 88.894412 -51.772566)
		(stroke
			(width 0.0508)
			(type default)
		)
		(layer "F.Cu")
	)
	(gr_line
		(start 88.6714 -48.7426)
		(end 88.692482 -48.721518)
		(stroke
			(width 0.06985)
			(type default)
		)
		(layer "F.Cu")
	)
	(gr_line
		(start 88.6714 -48.1838)
		(end 88.877902 -48.1838)
		(stroke
			(width 0.06985)
			(type default)
		)
		(layer "F.Cu")
	)
	(gr_line
		(start 88.671908 -53.428392)
		(end 88.671908 -53.603652)
		(stroke
			(width 0.0508)
			(type default)
		)
		(layer "F.Cu")
	)
	(gr_line
		(start 88.671908 -52.443634)
		(end 88.671908 -52.532534)
		(stroke
			(width 0.0508)
			(type default)
		)
		(layer "F.Cu")
	)
	(gr_line
		(start 88.692482 -48.721518)
		(end 89.102184 -48.721518)
		(stroke
			(width 0.06985)
			(type default)
		)
		(layer "F.Cu")
	)
	(gr_line
		(start 88.743028 -27.036014)
		(end 88.743028 -27.300174)
		(stroke
			(width 0.06985)
			(type default)
		)
		(layer "F.Cu")
	)
	(gr_line
		(start 88.743028 -27.036014)
		(end 88.949276 -26.829766)
		(stroke
			(width 0.06985)
			(type default)
		)
		(layer "F.Cu")
	)
	(gr_line
		(start 88.877902 -48.1838)
		(end 89.421208 -47.640494)
		(stroke
			(width 0.06985)
			(type default)
		)
		(layer "F.Cu")
	)
	(gr_line
		(start 88.894412 -51.772566)
		(end 88.894412 -52.087526)
		(stroke
			(width 0.0508)
			(type default)
		)
		(layer "F.Cu")
	)
	(gr_line
		(start 89.00668 -26.772362)
		(end 89.078308 -26.700734)
		(stroke
			(width 0.06985)
			(type default)
		)
		(layer "F.Cu")
	)
	(gr_line
		(start 89.102184 -48.721518)
		(end 89.421208 -48.402494)
		(stroke
			(width 0.06985)
			(type default)
		)
		(layer "F.Cu")
	)
	(gr_line
		(start 89.149428 -52.05857)
		(end 89.164922 -52.074064)
		(stroke
			(width 0.0508)
			(type default)
		)
		(layer "F.Cu")
	)
	(gr_line
		(start 89.149428 -51.7398)
		(end 89.149428 -52.05857)
		(stroke
			(width 0.0508)
			(type default)
		)
		(layer "F.Cu")
	)
	(gr_line
		(start 89.149428 -51.7398)
		(end 89.449148 -51.099974)
		(stroke
			(width 0.0508)
			(type default)
		)
		(layer "F.Cu")
	)
	(gr_line
		(start 89.291668 -53.60797)
		(end 89.75979 -54.076092)
		(stroke
			(width 0.0508)
			(type default)
		)
		(layer "F.Cu")
	)
	(gr_line
		(start 89.291668 -52.20081)
		(end 89.291668 -52.279042)
		(stroke
			(width 0.0508)
			(type default)
		)
		(layer "F.Cu")
	)
	(gr_line
		(start 89.454228 -51.99761)
		(end 89.454228 -52.075842)
		(stroke
			(width 0.0508)
			(type default)
		)
		(layer "F.Cu")
	)
	(gr_line
		(start 89.454228 -51.841654)
		(end 89.454228 -51.99507)
		(stroke
			(width 0.0508)
			(type default)
		)
		(layer "F.Cu")
	)
	(gr_line
		(start 89.497408 -53.498242)
		(end 89.583006 -53.58384)
		(stroke
			(width 0.0508)
			(type default)
		)
		(layer "F.Cu")
	)
	(gr_line
		(start 89.583006 -53.58384)
		(end 89.748614 -53.58384)
		(stroke
			(width 0.0508)
			(type default)
		)
		(layer "F.Cu")
	)
	(gr_line
		(start 89.738708 -46.480222)
		(end 90.102436 -46.116494)
		(stroke
			(width 0.06985)
			(type default)
		)
		(layer "F.Cu")
	)
	(gr_line
		(start 89.748614 -53.58384)
		(end 89.812876 -53.519578)
		(stroke
			(width 0.0508)
			(type default)
		)
		(layer "F.Cu")
	)
	(gr_line
		(start 89.748868 -47.275496)
		(end 90.122248 -46.902116)
		(stroke
			(width 0.06985)
			(type default)
		)
		(layer "F.Cu")
	)
	(gr_line
		(start 89.82075 -49.465992)
		(end 89.82075 -49.54143)
		(stroke
			(width 0.06985)
			(type default)
		)
		(layer "F.Cu")
	)
	(gr_line
		(start 89.82075 -49.465992)
		(end 90.122248 -49.164494)
		(stroke
			(width 0.06985)
			(type default)
		)
		(layer "F.Cu")
	)
	(gr_line
		(start 89.82075 -48.703992)
		(end 89.82075 -48.77943)
		(stroke
			(width 0.06985)
			(type default)
		)
		(layer "F.Cu")
	)
	(gr_line
		(start 89.82075 -48.703992)
		(end 90.122248 -48.402494)
		(stroke
			(width 0.06985)
			(type default)
		)
		(layer "F.Cu")
	)
	(gr_line
		(start 90.102436 -46.116494)
		(end 90.122248 -46.116494)
		(stroke
			(width 0.06985)
			(type default)
		)
		(layer "F.Cu")
	)
	(gr_line
		(start 90.122248 -46.878494)
		(end 90.122248 -46.902116)
		(stroke
			(width 0.06985)
			(type default)
		)
		(layer "F.Cu")
	)
	(gr_line
		(start 90.485468 -52.006754)
		(end 90.485468 -52.146962)
		(stroke
			(width 0.0508)
			(type default)
		)
		(layer "F.Cu")
	)
	(gr_line
		(start 90.564208 -50.952654)
		(end 90.790268 -51.880262)
		(stroke
			(width 0.0508)
			(type default)
		)
		(layer "F.Cu")
	)
	(gr_line
		(start 90.5764 -49.7078)
		(end 90.738706 -49.545494)
		(stroke
			(width 0.06985)
			(type default)
		)
		(layer "F.Cu")
	)
	(gr_line
		(start 90.6018 -49.0982)
		(end 91.092782 -49.0982)
		(stroke
			(width 0.06985)
			(type default)
		)
		(layer "F.Cu")
	)
	(gr_line
		(start 90.6526 -53.58003)
		(end 91.029028 -53.956458)
		(stroke
			(width 0.0508)
			(type default)
		)
		(layer "F.Cu")
	)
	(gr_line
		(start 90.6526 -53.398928)
		(end 90.6526 -53.58003)
		(stroke
			(width 0.0508)
			(type default)
		)
		(layer "F.Cu")
	)
	(gr_line
		(start 90.738706 -49.545494)
		(end 91.407488 -49.545494)
		(stroke
			(width 0.06985)
			(type default)
		)
		(layer "F.Cu")
	)
	(gr_line
		(start 90.774774 -52.14874)
		(end 90.790268 -52.133246)
		(stroke
			(width 0.0508)
			(type default)
		)
		(layer "F.Cu")
	)
	(gr_line
		(start 90.790268 -51.880262)
		(end 90.790268 -52.133246)
		(stroke
			(width 0.0508)
			(type default)
		)
		(layer "F.Cu")
	)
	(gr_line
		(start 90.85834 -53.195728)
		(end 91.058492 -53.39588)
		(stroke
			(width 0.0508)
			(type default)
		)
		(layer "F.Cu")
	)
	(gr_line
		(start 90.923364 -55.019448)
		(end 90.923364 -55.249064)
		(stroke
			(width 0.0508)
			(type default)
		)
		(layer "F.Cu")
	)
	(gr_line
		(start 90.9574 -52.2732)
		(end 91.293188 -51.503834)
		(stroke
			(width 0.0508)
			(type default)
		)
		(layer "F.Cu")
	)
	(gr_line
		(start 91.07297 -52.448714)
		(end 91.242388 -52.448714)
		(stroke
			(width 0.0508)
			(type default)
		)
		(layer "F.Cu")
	)
	(gr_line
		(start 91.092782 -49.0982)
		(end 91.407488 -48.783494)
		(stroke
			(width 0.06985)
			(type default)
		)
		(layer "F.Cu")
	)
	(gr_line
		(start 91.145614 -54.950614)
		(end 91.396058 -54.950614)
		(stroke
			(width 0.0508)
			(type default)
		)
		(layer "F.Cu")
	)
	(gr_line
		(start 91.658948 -51.826922)
		(end 91.658948 -51.849274)
		(stroke
			(width 0.0508)
			(type default)
		)
		(layer "F.Cu")
	)
	(gr_line
		(start 91.658948 -51.826922)
		(end 91.912948 -50.995834)
		(stroke
			(width 0.0508)
			(type default)
		)
		(layer "F.Cu")
	)
	(gr_line
		(start 91.7448 -52.611528)
		(end 91.7448 -52.644548)
		(stroke
			(width 0.0508)
			(type default)
		)
		(layer "F.Cu")
	)
	(gr_line
		(start 91.7448 -24.765)
		(end 91.964002 -24.984202)
		(stroke
			(width 0.0508)
			(type default)
		)
		(layer "F.Cu")
	)
	(gr_line
		(start 91.7448 -22.9108)
		(end 92.185236 -23.351236)
		(stroke
			(width 0.0508)
			(type default)
		)
		(layer "F.Cu")
	)
	(gr_line
		(start 91.759278 -49.155096)
		(end 92.108528 -48.805846)
		(stroke
			(width 0.06985)
			(type default)
		)
		(layer "F.Cu")
	)
	(gr_line
		(start 91.759278 -48.4378)
		(end 92.108528 -48.08855)
		(stroke
			(width 0.06985)
			(type default)
		)
		(layer "F.Cu")
	)
	(gr_line
		(start 91.862148 -52.408328)
		(end 91.862148 -52.441348)
		(stroke
			(width 0.0508)
			(type default)
		)
		(layer "F.Cu")
	)
	(gr_line
		(start 91.864688 -52.052474)
		(end 91.963748 -51.953414)
		(stroke
			(width 0.0508)
			(type default)
		)
		(layer "F.Cu")
	)
	(gr_line
		(start 91.96578 -24.98598)
		(end 91.982036 -25.002236)
		(stroke
			(width 0.0508)
			(type default)
		)
		(layer "F.Cu")
	)
	(gr_line
		(start 92.108528 -48.783494)
		(end 92.108528 -48.805846)
		(stroke
			(width 0.06985)
			(type default)
		)
		(layer "F.Cu")
	)
	(gr_line
		(start 92.108528 -48.021494)
		(end 92.108528 -48.08855)
		(stroke
			(width 0.06985)
			(type default)
		)
		(layer "F.Cu")
	)
	(gr_line
		(start 92.185236 -25.054052)
		(end 92.201492 -25.070308)
		(stroke
			(width 0.0508)
			(type default)
		)
		(layer "F.Cu")
	)
	(gr_line
		(start 92.185236 -23.351236)
		(end 92.185236 -24.796496)
		(stroke
			(width 0.0508)
			(type default)
		)
		(layer "F.Cu")
	)
	(gr_line
		(start 92.451428 -51.442874)
		(end 92.5068 -51.498246)
		(stroke
			(width 0.0508)
			(type default)
		)
		(layer "F.Cu")
	)
	(gr_line
		(start 92.461588 -50.274474)
		(end 92.756228 -51.29403)
		(stroke
			(width 0.0508)
			(type default)
		)
		(layer "F.Cu")
	)
	(gr_line
		(start 92.5322 -58.23966)
		(end 92.5322 -58.26506)
		(stroke
			(width 0.0508)
			(type default)
		)
		(layer "F.Cu")
	)
	(gr_line
		(start 92.5322 -58.23966)
		(end 92.558108 -58.213752)
		(stroke
			(width 0.0508)
			(type default)
		)
		(layer "F.Cu")
	)
	(gr_line
		(start 92.559886 -58.211974)
		(end 92.60205 -58.16981)
		(stroke
			(width 0.0508)
			(type default)
		)
		(layer "F.Cu")
	)
	(gr_line
		(start 92.68333 -48.499014)
		(end 92.77985 -48.402494)
		(stroke
			(width 0.06985)
			(type default)
		)
		(layer "F.Cu")
	)
	(gr_line
		(start 92.696538 -49.057814)
		(end 92.813378 -49.174654)
		(stroke
			(width 0.06985)
			(type default)
		)
		(layer "F.Cu")
	)
	(gr_line
		(start 92.71254 -51.613054)
		(end 92.756228 -51.569366)
		(stroke
			(width 0.0508)
			(type default)
		)
		(layer "F.Cu")
	)
	(gr_line
		(start 92.756228 -51.29403)
		(end 92.756228 -51.569366)
		(stroke
			(width 0.0508)
			(type default)
		)
		(layer "F.Cu")
	)
	(gr_line
		(start 92.77985 -48.402494)
		(end 93.393768 -48.402494)
		(stroke
			(width 0.06985)
			(type default)
		)
		(layer "F.Cu")
	)
	(gr_line
		(start 92.80525 -58.16981)
		(end 92.847414 -58.211974)
		(stroke
			(width 0.0508)
			(type default)
		)
		(layer "F.Cu")
	)
	(gr_line
		(start 92.813378 -49.174654)
		(end 93.383608 -49.174654)
		(stroke
			(width 0.06985)
			(type default)
		)
		(layer "F.Cu")
	)
	(gr_line
		(start 92.849192 -58.213752)
		(end 92.8751 -58.23966)
		(stroke
			(width 0.0508)
			(type default)
		)
		(layer "F.Cu")
	)
	(gr_line
		(start 92.8751 -58.23966)
		(end 92.8751 -58.26506)
		(stroke
			(width 0.0508)
			(type default)
		)
		(layer "F.Cu")
	)
	(gr_line
		(start 93.030548 -51.839114)
		(end 93.20276 -52.011326)
		(stroke
			(width 0.0508)
			(type default)
		)
		(layer "F.Cu")
	)
	(gr_line
		(start 93.063568 -51.099974)
		(end 93.4085 -51.7906)
		(stroke
			(width 0.0508)
			(type default)
		)
		(layer "F.Cu")
	)
	(gr_line
		(start 93.383608 -49.174654)
		(end 93.393768 -49.164494)
		(stroke
			(width 0.06985)
			(type default)
		)
		(layer "F.Cu")
	)
	(gr_line
		(start 93.4085 -51.7906)
		(end 93.4085 -51.808126)
		(stroke
			(width 0.0508)
			(type default)
		)
		(layer "F.Cu")
	)
	(gr_line
		(start 93.752924 -48.743362)
		(end 93.75394 -48.743362)
		(stroke
			(width 0.06985)
			(type default)
		)
		(layer "F.Cu")
	)
	(gr_line
		(start 93.75394 -48.743362)
		(end 94.094808 -48.402494)
		(stroke
			(width 0.06985)
			(type default)
		)
		(layer "F.Cu")
	)
	(gr_line
		(start 93.7768 -47.958248)
		(end 93.7768 -48.0314)
		(stroke
			(width 0.06985)
			(type default)
		)
		(layer "F.Cu")
	)
	(gr_line
		(start 93.7768 -47.958248)
		(end 94.094808 -47.640494)
		(stroke
			(width 0.06985)
			(type default)
		)
		(layer "F.Cu")
	)
	(gr_line
		(start 93.850206 -26.933906)
		(end 94.132908 -27.216608)
		(stroke
			(width 0.0508)
			(type default)
		)
		(layer "F.Cu")
	)
	(gr_line
		(start 93.851984 -26.6446)
		(end 94.082362 -26.6446)
		(stroke
			(width 0.0508)
			(type default)
		)
		(layer "F.Cu")
	)
	(gr_line
		(start 94.0054 -30.431486)
		(end 94.333568 -30.759654)
		(stroke
			(width 0.06985)
			(type default)
		)
		(layer "F.Cu")
	)
	(gr_line
		(start 94.0054 -30.369002)
		(end 94.0054 -30.431486)
		(stroke
			(width 0.06985)
			(type default)
		)
		(layer "F.Cu")
	)
	(gr_line
		(start 94.082362 -26.6446)
		(end 94.165928 -26.561034)
		(stroke
			(width 0.0508)
			(type default)
		)
		(layer "F.Cu")
	)
	(gr_line
		(start 94.132908 -27.216608)
		(end 94.132908 -27.300174)
		(stroke
			(width 0.0508)
			(type default)
		)
		(layer "F.Cu")
	)
	(gr_line
		(start 94.333568 -29.997654)
		(end 94.6658 -30.329886)
		(stroke
			(width 0.06985)
			(type default)
		)
		(layer "F.Cu")
	)
	(gr_line
		(start 94.6658 -30.329886)
		(end 94.6658 -30.394402)
		(stroke
			(width 0.06985)
			(type default)
		)
		(layer "F.Cu")
	)
	(gr_line
		(start 94.976188 -49.048162)
		(end 95.11538 -49.048162)
		(stroke
			(width 0.06985)
			(type default)
		)
		(layer "F.Cu")
	)
	(gr_line
		(start 94.996 -48.3489)
		(end 95.052642 -48.3489)
		(stroke
			(width 0.06985)
			(type default)
		)
		(layer "F.Cu")
	)
	(gr_line
		(start 95.052642 -48.3489)
		(end 95.380048 -48.021494)
		(stroke
			(width 0.06985)
			(type default)
		)
		(layer "F.Cu")
	)
	(gr_line
		(start 95.11538 -49.048162)
		(end 95.380048 -48.783494)
		(stroke
			(width 0.06985)
			(type default)
		)
		(layer "F.Cu")
	)
	(gr_line
		(start 95.167704 -57.550304)
		(end 95.311214 -57.693814)
		(stroke
			(width 0.0508)
			(type default)
		)
		(layer "F.Cu")
	)
	(gr_line
		(start 95.311214 -57.7469)
		(end 95.311214 -57.792874)
		(stroke
			(width 0.0508)
			(type default)
		)
		(layer "F.Cu")
	)
	(gr_line
		(start 95.311214 -57.693814)
		(end 95.311214 -57.74436)
		(stroke
			(width 0.0508)
			(type default)
		)
		(layer "F.Cu")
	)
	(gr_line
		(start 95.446088 -57.54116)
		(end 95.514414 -57.54116)
		(stroke
			(width 0.0508)
			(type default)
		)
		(layer "F.Cu")
	)
	(gr_line
		(start 95.516954 -57.54116)
		(end 95.54464 -57.54116)
		(stroke
			(width 0.0508)
			(type default)
		)
		(layer "F.Cu")
	)
	(gr_line
		(start 95.54464 -57.54116)
		(end 95.553784 -57.550304)
		(stroke
			(width 0.0508)
			(type default)
		)
		(layer "F.Cu")
	)
	(gr_line
		(start 95.553784 -57.550304)
		(end 95.697294 -57.693814)
		(stroke
			(width 0.06985)
			(type default)
		)
		(layer "F.Cu")
	)
	(gr_line
		(start 95.5802 -54.9148)
		(end 95.9866 -54.5084)
		(stroke
			(width 0.0508)
			(type default)
		)
		(layer "F.Cu")
	)
	(gr_line
		(start 95.5802 -53.594)
		(end 95.697294 -53.476906)
		(stroke
			(width 0.0508)
			(type default)
		)
		(layer "F.Cu")
	)
	(gr_line
		(start 95.63735 -59.42965)
		(end 95.63735 -59.45505)
		(stroke
			(width 0.0508)
			(type default)
		)
		(layer "F.Cu")
	)
	(gr_line
		(start 95.63735 -59.42965)
		(end 95.656908 -59.410092)
		(stroke
			(width 0.0508)
			(type default)
		)
		(layer "F.Cu")
	)
	(gr_line
		(start 95.658686 -59.408314)
		(end 95.7072 -59.3598)
		(stroke
			(width 0.0508)
			(type default)
		)
		(layer "F.Cu")
	)
	(gr_line
		(start 95.745808 -52.448714)
		(end 95.840296 -52.543202)
		(stroke
			(width 0.0508)
			(type default)
		)
		(layer "F.Cu")
	)
	(gr_line
		(start 95.796608 -52.046124)
		(end 96.046036 -52.295552)
		(stroke
			(width 0.0508)
			(type default)
		)
		(layer "F.Cu")
	)
	(gr_line
		(start 95.796608 -51.503834)
		(end 95.796608 -52.046124)
		(stroke
			(width 0.0508)
			(type default)
		)
		(layer "F.Cu")
	)
	(gr_line
		(start 95.842836 -53.271928)
		(end 95.842836 -53.331364)
		(stroke
			(width 0.0508)
			(type default)
		)
		(layer "F.Cu")
	)
	(gr_line
		(start 95.9104 -59.3725)
		(end 95.946214 -59.408314)
		(stroke
			(width 0.0508)
			(type default)
		)
		(layer "F.Cu")
	)
	(gr_line
		(start 95.947992 -59.410092)
		(end 95.98025 -59.44235)
		(stroke
			(width 0.0508)
			(type default)
		)
		(layer "F.Cu")
	)
	(gr_line
		(start 95.98025 -59.44235)
		(end 95.98025 -59.45505)
		(stroke
			(width 0.0508)
			(type default)
		)
		(layer "F.Cu")
	)
	(gr_line
		(start 95.9866 -53.537104)
		(end 95.9866 -54.5084)
		(stroke
			(width 0.0508)
			(type default)
		)
		(layer "F.Cu")
	)
	(gr_line
		(start 95.9866 -53.475128)
		(end 95.9866 -53.534564)
		(stroke
			(width 0.0508)
			(type default)
		)
		(layer "F.Cu")
	)
	(gr_line
		(start 96.046036 -52.295552)
		(end 96.046036 -52.340002)
		(stroke
			(width 0.0508)
			(type default)
		)
		(layer "F.Cu")
	)
	(gr_line
		(start 96.393 -23.0251)
		(end 96.63176 -23.26386)
		(stroke
			(width 0.0508)
			(type default)
		)
		(layer "F.Cu")
	)
	(gr_line
		(start 96.393 -23.0124)
		(end 96.393 -23.0251)
		(stroke
			(width 0.0508)
			(type default)
		)
		(layer "F.Cu")
	)
	(gr_line
		(start 96.393 -21.158708)
		(end 96.8375 -21.603208)
		(stroke
			(width 0.0508)
			(type default)
		)
		(layer "F.Cu")
	)
	(gr_line
		(start 96.8375 -21.603208)
		(end 96.8375 -23.06066)
		(stroke
			(width 0.0508)
			(type default)
		)
		(layer "F.Cu")
	)
	(gr_line
		(start 97.6884 -47.249842)
		(end 97.6884 -47.2694)
		(stroke
			(width 0.0508)
			(type default)
		)
		(layer "F.Cu")
	)
	(gr_line
		(start 97.6884 -47.249842)
		(end 98.059748 -46.878494)
		(stroke
			(width 0.0508)
			(type default)
		)
		(layer "F.Cu")
	)
	(gr_line
		(start 97.715832 -47.800768)
		(end 97.715832 -47.98314)
		(stroke
			(width 0.0508)
			(type default)
		)
		(layer "F.Cu")
	)
	(gr_line
		(start 97.715832 -47.800768)
		(end 97.876106 -47.640494)
		(stroke
			(width 0.0508)
			(type default)
		)
		(layer "F.Cu")
	)
	(gr_line
		(start 97.742248 -26.52014)
		(end 97.742248 -26.558494)
		(stroke
			(width 0.0508)
			(type default)
		)
		(layer "F.Cu")
	)
	(gr_line
		(start 97.747328 -26.984706)
		(end 97.747328 -27.300174)
		(stroke
			(width 0.0508)
			(type default)
		)
		(layer "F.Cu")
	)
	(gr_line
		(start 97.747328 -26.984706)
		(end 98.047048 -26.684986)
		(stroke
			(width 0.0508)
			(type default)
		)
		(layer "F.Cu")
	)
	(gr_line
		(start 97.876106 -47.640494)
		(end 98.067368 -47.640494)
		(stroke
			(width 0.0508)
			(type default)
		)
		(layer "F.Cu")
	)
	(gr_line
		(start 97.922842 -31.138368)
		(end 98.306128 -31.521654)
		(stroke
			(width 0.0508)
			(type default)
		)
		(layer "F.Cu")
	)
	(gr_line
		(start 97.922842 -31.123128)
		(end 97.922842 -31.138368)
		(stroke
			(width 0.0508)
			(type default)
		)
		(layer "F.Cu")
	)
	(gr_line
		(start 97.947988 -26.31694)
		(end 98.047048 -26.416)
		(stroke
			(width 0.0508)
			(type default)
		)
		(layer "F.Cu")
	)
	(gr_line
		(start 97.973134 -30.360112)
		(end 98.306128 -30.693106)
		(stroke
			(width 0.0508)
			(type default)
		)
		(layer "F.Cu")
	)
	(gr_line
		(start 98.047048 -26.416)
		(end 98.047048 -26.684986)
		(stroke
			(width 0.0508)
			(type default)
		)
		(layer "F.Cu")
	)
	(gr_line
		(start 98.059748 -46.878494)
		(end 98.067368 -46.878494)
		(stroke
			(width 0.0508)
			(type default)
		)
		(layer "F.Cu")
	)
	(gr_line
		(start 98.306128 -30.693106)
		(end 98.306128 -30.759654)
		(stroke
			(width 0.0508)
			(type default)
		)
		(layer "F.Cu")
	)
	(gr_line
		(start 99.0854 -55.6133)
		(end 99.5553 -56.0832)
		(stroke
			(width 0.0508)
			(type default)
		)
		(layer "F.Cu")
	)
	(gr_line
		(start 99.0854 -54.18074)
		(end 99.0854 -55.6133)
		(stroke
			(width 0.0508)
			(type default)
		)
		(layer "F.Cu")
	)
	(gr_line
		(start 99.184968 -52.840128)
		(end 99.184968 -52.859432)
		(stroke
			(width 0.0508)
			(type default)
		)
		(layer "F.Cu")
	)
	(gr_line
		(start 99.184968 -51.858418)
		(end 99.184968 -51.902614)
		(stroke
			(width 0.0508)
			(type default)
		)
		(layer "F.Cu")
	)
	(gr_line
		(start 99.184968 -51.858418)
		(end 99.568508 -51.474878)
		(stroke
			(width 0.0508)
			(type default)
		)
		(layer "F.Cu")
	)
	(gr_line
		(start 99.2886 -53.043328)
		(end 99.2886 -53.062632)
		(stroke
			(width 0.0508)
			(type default)
		)
		(layer "F.Cu")
	)
	(gr_line
		(start 99.29114 -53.97754)
		(end 99.5934 -54.2798)
		(stroke
			(width 0.0508)
			(type default)
		)
		(layer "F.Cu")
	)
	(gr_line
		(start 99.390708 -52.105814)
		(end 99.489768 -52.006754)
		(stroke
			(width 0.0508)
			(type default)
		)
		(layer "F.Cu")
	)
	(gr_line
		(start 99.514152 -60.64504)
		(end 99.788726 -60.64504)
		(stroke
			(width 0.06985)
			(type default)
		)
		(layer "F.Cu")
	)
	(gr_line
		(start 99.568508 -50.952654)
		(end 99.568508 -51.474878)
		(stroke
			(width 0.0508)
			(type default)
		)
		(layer "F.Cu")
	)
	(gr_line
		(start 99.791266 -60.64504)
		(end 99.89312 -60.64504)
		(stroke
			(width 0.06985)
			(type default)
		)
		(layer "F.Cu")
	)
	(gr_line
		(start 100.134166 -60.99048)
		(end 100.134166 -61.246512)
		(stroke
			(width 0.06985)
			(type default)
		)
		(layer "F.Cu")
	)
	(gr_line
		(start 100.134166 -60.889134)
		(end 100.134166 -60.98794)
		(stroke
			(width 0.06985)
			(type default)
		)
		(layer "F.Cu")
	)
	(gr_line
		(start 100.8634 -24.5364)
		(end 101.08946 -24.76246)
		(stroke
			(width 0.0508)
			(type default)
		)
		(layer "F.Cu")
	)
	(gr_line
		(start 100.9142 -22.648672)
		(end 101.2952 -23.029672)
		(stroke
			(width 0.0508)
			(type default)
		)
		(layer "F.Cu")
	)
	(gr_line
		(start 100.929694 -59.324748)
		(end 100.929694 -59.605164)
		(stroke
			(width 0.06985)
			(type default)
		)
		(layer "F.Cu")
	)
	(gr_line
		(start 100.929694 -59.324748)
		(end 101.226112 -59.02833)
		(stroke
			(width 0.06985)
			(type default)
		)
		(layer "F.Cu")
	)
	(gr_line
		(start 101.226112 -59.02833)
		(end 101.506528 -59.02833)
		(stroke
			(width 0.06985)
			(type default)
		)
		(layer "F.Cu")
	)
	(gr_line
		(start 101.2952 -23.029672)
		(end 101.2952 -24.55926)
		(stroke
			(width 0.0508)
			(type default)
		)
		(layer "F.Cu")
	)
	(gr_line
		(start 101.416612 -59.606688)
		(end 101.508052 -59.515248)
		(stroke
			(width 0.06985)
			(type default)
		)
		(layer "F.Cu")
	)
	(gr_line
		(start 101.457252 -61.935106)
		(end 101.810312 -61.935106)
		(stroke
			(width 0.0635)
			(type default)
		)
		(layer "F.Cu")
	)
	(gr_line
		(start 101.548692 -25.738836)
		(end 101.556312 -25.746456)
		(stroke
			(width 0.0508)
			(type default)
		)
		(layer "F.Cu")
	)
	(gr_line
		(start 101.556312 -26.869898)
		(end 101.638608 -26.952194)
		(stroke
			(width 0.0508)
			(type default)
		)
		(layer "F.Cu")
	)
	(gr_line
		(start 101.556312 -26.02103)
		(end 101.556312 -26.869898)
		(stroke
			(width 0.0508)
			(type default)
		)
		(layer "F.Cu")
	)
	(gr_line
		(start 101.759512 -25.81529)
		(end 101.767132 -25.82291)
		(stroke
			(width 0.0508)
			(type default)
		)
		(layer "F.Cu")
	)
	(gr_line
		(start 101.76891 -25.824688)
		(end 101.895148 -25.950926)
		(stroke
			(width 0.0508)
			(type default)
		)
		(layer "F.Cu")
	)
	(gr_line
		(start 101.812852 -61.935106)
		(end 101.818694 -61.935106)
		(stroke
			(width 0.0635)
			(type default)
		)
		(layer "F.Cu")
	)
	(gr_line
		(start 101.895148 -25.950926)
		(end 101.895148 -25.951434)
		(stroke
			(width 0.0508)
			(type default)
		)
		(layer "F.Cu")
	)
	(gr_line
		(start 102.039928 -49.164494)
		(end 102.353618 -49.478184)
		(stroke
			(width 0.0508)
			(type default)
		)
		(layer "F.Cu")
	)
	(gr_line
		(start 102.039928 -48.402494)
		(end 102.367588 -48.730154)
		(stroke
			(width 0.0508)
			(type default)
		)
		(layer "F.Cu")
	)
	(gr_line
		(start 102.039928 -46.878494)
		(end 102.5144 -46.404022)
		(stroke
			(width 0.0508)
			(type default)
		)
		(layer "F.Cu")
	)
	(gr_line
		(start 102.039928 -46.116494)
		(end 102.168706 -46.116494)
		(stroke
			(width 0.0508)
			(type default)
		)
		(layer "F.Cu")
	)
	(gr_line
		(start 102.066852 -62.191646)
		(end 102.066852 -62.546992)
		(stroke
			(width 0.0635)
			(type default)
		)
		(layer "F.Cu")
	)
	(gr_line
		(start 102.066852 -62.046358)
		(end 102.066852 -62.189106)
		(stroke
			(width 0.0635)
			(type default)
		)
		(layer "F.Cu")
	)
	(gr_line
		(start 102.168706 -46.116494)
		(end 102.5144 -45.7708)
		(stroke
			(width 0.0508)
			(type default)
		)
		(layer "F.Cu")
	)
	(gr_line
		(start 102.353618 -49.478184)
		(end 102.353618 -49.53127)
		(stroke
			(width 0.0508)
			(type default)
		)
		(layer "F.Cu")
	)
	(gr_line
		(start 102.367588 -48.730154)
		(end 102.367588 -48.791876)
		(stroke
			(width 0.0508)
			(type default)
		)
		(layer "F.Cu")
	)
	(gr_line
		(start 102.5144 -46.3296)
		(end 102.5144 -46.404022)
		(stroke
			(width 0.0508)
			(type default)
		)
		(layer "F.Cu")
	)
	(gr_line
		(start 102.928674 -46.983904)
		(end 103.049578 -46.983904)
		(stroke
			(width 0.0508)
			(type default)
		)
		(layer "F.Cu")
	)
	(gr_line
		(start 103.049578 -46.983904)
		(end 103.325168 -47.259494)
		(stroke
			(width 0.0508)
			(type default)
		)
		(layer "F.Cu")
	)
	(gr_line
		(start 103.325168 -49.303432)
		(end 103.325168 -49.545494)
		(stroke
			(width 0.0508)
			(type default)
		)
		(layer "F.Cu")
	)
	(gr_line
		(start 103.325168 -49.303432)
		(end 103.4542 -49.1744)
		(stroke
			(width 0.0508)
			(type default)
		)
		(layer "F.Cu")
	)
	(gr_line
		(start 103.325168 -48.744632)
		(end 103.325168 -48.783494)
		(stroke
			(width 0.0508)
			(type default)
		)
		(layer "F.Cu")
	)
	(gr_line
		(start 103.325168 -48.744632)
		(end 103.6828 -48.387)
		(stroke
			(width 0.0508)
			(type default)
		)
		(layer "F.Cu")
	)
	(gr_line
		(start 103.325168 -46.784768)
		(end 103.434896 -46.894496)
		(stroke
			(width 0.0508)
			(type default)
		)
		(layer "F.Cu")
	)
	(gr_line
		(start 103.325168 -46.497494)
		(end 103.325168 -46.784768)
		(stroke
			(width 0.0508)
			(type default)
		)
		(layer "F.Cu")
	)
	(gr_line
		(start 103.434896 -46.894496)
		(end 103.693468 -46.894496)
		(stroke
			(width 0.0508)
			(type default)
		)
		(layer "F.Cu")
	)
	(gr_line
		(start 103.4542 -49.1744)
		(end 103.6574 -49.1744)
		(stroke
			(width 0.0508)
			(type default)
		)
		(layer "F.Cu")
	)
	(gr_line
		(start 103.569008 -51.447954)
		(end 103.656384 -51.53533)
		(stroke
			(width 0.0508)
			(type default)
		)
		(layer "F.Cu")
	)
	(gr_line
		(start 103.656384 -51.53533)
		(end 103.656384 -51.934618)
		(stroke
			(width 0.0508)
			(type default)
		)
		(layer "F.Cu")
	)
	(gr_line
		(start 103.7209 -59.1439)
		(end 103.7463 -59.1439)
		(stroke
			(width 0.0508)
			(type default)
		)
		(layer "F.Cu")
	)
	(gr_line
		(start 103.7209 -58.801)
		(end 103.7463 -58.801)
		(stroke
			(width 0.0508)
			(type default)
		)
		(layer "F.Cu")
	)
	(gr_line
		(start 103.7463 -59.1439)
		(end 103.772208 -59.117992)
		(stroke
			(width 0.0508)
			(type default)
		)
		(layer "F.Cu")
	)
	(gr_line
		(start 103.7463 -58.801)
		(end 103.772208 -58.826908)
		(stroke
			(width 0.0508)
			(type default)
		)
		(layer "F.Cu")
	)
	(gr_line
		(start 103.773986 -59.116214)
		(end 103.81615 -59.07405)
		(stroke
			(width 0.0508)
			(type default)
		)
		(layer "F.Cu")
	)
	(gr_line
		(start 103.773986 -58.828686)
		(end 103.81615 -58.87085)
		(stroke
			(width 0.0508)
			(type default)
		)
		(layer "F.Cu")
	)
	(gr_line
		(start 103.862124 -52.137818)
		(end 103.993188 -52.006754)
		(stroke
			(width 0.0508)
			(type default)
		)
		(layer "F.Cu")
	)
	(gr_line
		(start 104.267 -56.7817)
		(end 104.6607 -57.1754)
		(stroke
			(width 0.0508)
			(type default)
		)
		(layer "F.Cu")
	)
	(gr_line
		(start 104.267 -55.47614)
		(end 104.267 -56.7817)
		(stroke
			(width 0.0508)
			(type default)
		)
		(layer "F.Cu")
	)
	(gr_line
		(start 104.47274 -55.27294)
		(end 104.6734 -55.4736)
		(stroke
			(width 0.0508)
			(type default)
		)
		(layer "F.Cu")
	)
	(gr_line
		(start 105.237788 -26.3652)
		(end 105.639108 -27.447494)
		(stroke
			(width 0.0508)
			(type default)
		)
		(layer "F.Cu")
	)
	(gr_line
		(start 105.313988 -24.892)
		(end 105.3465 -24.924512)
		(stroke
			(width 0.0508)
			(type default)
		)
		(layer "F.Cu")
	)
	(gr_line
		(start 105.339388 -22.9235)
		(end 105.7402 -23.324312)
		(stroke
			(width 0.0508)
			(type default)
		)
		(layer "F.Cu")
	)
	(gr_line
		(start 105.3465 -25.908)
		(end 105.3465 -25.91816)
		(stroke
			(width 0.0508)
			(type default)
		)
		(layer "F.Cu")
	)
	(gr_line
		(start 105.3465 -24.924512)
		(end 105.3465 -25.058624)
		(stroke
			(width 0.0508)
			(type default)
		)
		(layer "F.Cu")
	)
	(gr_line
		(start 105.440988 -26.1112)
		(end 105.440988 -26.12136)
		(stroke
			(width 0.0508)
			(type default)
		)
		(layer "F.Cu")
	)
	(gr_line
		(start 105.443528 -26.322528)
		(end 105.514394 -26.393394)
		(stroke
			(width 0.0508)
			(type default)
		)
		(layer "F.Cu")
	)
	(gr_line
		(start 105.514394 -26.393394)
		(end 105.717848 -26.393394)
		(stroke
			(width 0.0508)
			(type default)
		)
		(layer "F.Cu")
	)
	(gr_line
		(start 105.550208 -30.759654)
		(end 105.880154 -31.0896)
		(stroke
			(width 0.06985)
			(type default)
		)
		(layer "F.Cu")
	)
	(gr_line
		(start 105.550208 -30.032706)
		(end 105.893616 -30.376114)
		(stroke
			(width 0.06985)
			(type default)
		)
		(layer "F.Cu")
	)
	(gr_line
		(start 105.550208 -29.997654)
		(end 105.550208 -30.032706)
		(stroke
			(width 0.06985)
			(type default)
		)
		(layer "F.Cu")
	)
	(gr_line
		(start 105.55224 -25.261824)
		(end 105.7402 -25.073864)
		(stroke
			(width 0.0508)
			(type default)
		)
		(layer "F.Cu")
	)
	(gr_line
		(start 105.7402 -23.324312)
		(end 105.7402 -25.073864)
		(stroke
			(width 0.0508)
			(type default)
		)
		(layer "F.Cu")
	)
	(gr_line
		(start 105.880154 -31.0896)
		(end 105.880154 -31.1404)
		(stroke
			(width 0.06985)
			(type default)
		)
		(layer "F.Cu")
	)
	(gr_line
		(start 105.961688 -51.78044)
		(end 106.251502 -52.070254)
		(stroke
			(width 0.0508)
			(type default)
		)
		(layer "F.Cu")
	)
	(gr_line
		(start 105.961688 -51.442874)
		(end 105.961688 -51.78044)
		(stroke
			(width 0.0508)
			(type default)
		)
		(layer "F.Cu")
	)
	(gr_line
		(start 106.251248 -30.7594)
		(end 106.251248 -30.759654)
		(stroke
			(width 0.0508)
			(type default)
		)
		(layer "F.Cu")
	)
	(gr_line
		(start 106.251248 -30.7594)
		(end 106.378248 -30.6324)
		(stroke
			(width 0.0508)
			(type default)
		)
		(layer "F.Cu")
	)
	(gr_line
		(start 106.251248 -30.076648)
		(end 106.4514 -30.2768)
		(stroke
			(width 0.0508)
			(type default)
		)
		(layer "F.Cu")
	)
	(gr_line
		(start 106.251248 -29.997654)
		(end 106.251248 -30.076648)
		(stroke
			(width 0.0508)
			(type default)
		)
		(layer "F.Cu")
	)
	(gr_line
		(start 106.378248 -30.6324)
		(end 106.850688 -30.6324)
		(stroke
			(width 0.0508)
			(type default)
		)
		(layer "F.Cu")
	)
	(gr_line
		(start 106.4514 -30.2768)
		(end 106.7054 -30.2768)
		(stroke
			(width 0.0508)
			(type default)
		)
		(layer "F.Cu")
	)
	(gr_line
		(start 106.528108 -45.034708)
		(end 106.735118 -45.241718)
		(stroke
			(width 0.0508)
			(type default)
		)
		(layer "F.Cu")
	)
	(gr_line
		(start 106.528108 -44.927774)
		(end 106.528108 -45.034708)
		(stroke
			(width 0.0508)
			(type default)
		)
		(layer "F.Cu")
	)
	(gr_line
		(start 106.528108 -40.955214)
		(end 106.771186 -40.955214)
		(stroke
			(width 0.0508)
			(type default)
		)
		(layer "F.Cu")
	)
	(gr_line
		(start 106.528108 -37.683694)
		(end 106.864912 -38.020498)
		(stroke
			(width 0.0508)
			(type default)
		)
		(layer "F.Cu")
	)
	(gr_line
		(start 106.528108 -33.711134)
		(end 106.56443 -33.711134)
		(stroke
			(width 0.0508)
			(type default)
		)
		(layer "F.Cu")
	)
	(gr_line
		(start 106.540808 -51.839114)
		(end 106.540808 -52.068476)
		(stroke
			(width 0.0508)
			(type default)
		)
		(layer "F.Cu")
	)
	(gr_line
		(start 106.56443 -33.711134)
		(end 106.919268 -33.356296)
		(stroke
			(width 0.0508)
			(type default)
		)
		(layer "F.Cu")
	)
	(gr_line
		(start 106.7054 -30.2768)
		(end 106.8324 -30.1498)
		(stroke
			(width 0.0508)
			(type default)
		)
		(layer "F.Cu")
	)
	(gr_line
		(start 106.735118 -45.241718)
		(end 106.914188 -45.241718)
		(stroke
			(width 0.0508)
			(type default)
		)
		(layer "F.Cu")
	)
	(gr_line
		(start 106.771186 -40.955214)
		(end 106.9086 -40.8178)
		(stroke
			(width 0.0508)
			(type default)
		)
		(layer "F.Cu")
	)
	(gr_line
		(start 106.8324 -30.0482)
		(end 106.8324 -30.1498)
		(stroke
			(width 0.0508)
			(type default)
		)
		(layer "F.Cu")
	)
	(gr_line
		(start 106.864912 -38.020498)
		(end 106.898694 -38.020498)
		(stroke
			(width 0.0508)
			(type default)
		)
		(layer "F.Cu")
	)
	(gr_line
		(start 106.884216 -41.315386)
		(end 106.929936 -41.315386)
		(stroke
			(width 0.0508)
			(type default)
		)
		(layer "F.Cu")
	)
	(gr_line
		(start 106.898694 -37.318442)
		(end 107.263946 -37.683694)
		(stroke
			(width 0.0508)
			(type default)
		)
		(layer "F.Cu")
	)
	(gr_line
		(start 106.9086 -40.649398)
		(end 106.9086 -40.8178)
		(stroke
			(width 0.0508)
			(type default)
		)
		(layer "F.Cu")
	)
	(gr_line
		(start 106.929936 -41.315386)
		(end 107.290108 -40.955214)
		(stroke
			(width 0.0508)
			(type default)
		)
		(layer "F.Cu")
	)
	(gr_line
		(start 107.198668 -29.266896)
		(end 107.536488 -29.604716)
		(stroke
			(width 0.0508)
			(type default)
		)
		(layer "F.Cu")
	)
	(gr_line
		(start 107.263946 -37.683694)
		(end 107.290108 -37.683694)
		(stroke
			(width 0.0508)
			(type default)
		)
		(layer "F.Cu")
	)
	(gr_line
		(start 107.290108 -44.927774)
		(end 107.64393 -45.281596)
		(stroke
			(width 0.0508)
			(type default)
		)
		(layer "F.Cu")
	)
	(gr_line
		(start 107.290108 -33.711134)
		(end 107.32643 -33.711134)
		(stroke
			(width 0.0508)
			(type default)
		)
		(layer "F.Cu")
	)
	(gr_line
		(start 107.32643 -33.711134)
		(end 107.611164 -33.4264)
		(stroke
			(width 0.0508)
			(type default)
		)
		(layer "F.Cu")
	)
	(gr_line
		(start 107.536488 -29.604716)
		(end 107.536488 -29.616654)
		(stroke
			(width 0.0508)
			(type default)
		)
		(layer "F.Cu")
	)
	(gr_line
		(start 107.536488 -28.868116)
		(end 107.8738 -29.205428)
		(stroke
			(width 0.0508)
			(type default)
		)
		(layer "F.Cu")
	)
	(gr_line
		(start 107.536488 -28.854654)
		(end 107.536488 -28.868116)
		(stroke
			(width 0.0508)
			(type default)
		)
		(layer "F.Cu")
	)
	(gr_line
		(start 107.611164 -33.4264)
		(end 107.6452 -33.4264)
		(stroke
			(width 0.0508)
			(type default)
		)
		(layer "F.Cu")
	)
	(gr_line
		(start 107.64393 -45.281596)
		(end 107.655868 -45.281596)
		(stroke
			(width 0.0508)
			(type default)
		)
		(layer "F.Cu")
	)
	(gr_line
		(start 107.6452 -33.4264)
		(end 107.6706 -33.401)
		(stroke
			(width 0.0508)
			(type default)
		)
		(layer "F.Cu")
	)
	(gr_line
		(start 107.8738 -29.205428)
		(end 107.8738 -29.21)
		(stroke
			(width 0.0508)
			(type default)
		)
		(layer "F.Cu")
	)
	(gr_line
		(start 108.237528 -29.616654)
		(end 108.263182 -29.591)
		(stroke
			(width 0.0508)
			(type default)
		)
		(layer "F.Cu")
	)
	(gr_line
		(start 108.237528 -28.854654)
		(end 108.415074 -29.0322)
		(stroke
			(width 0.0508)
			(type default)
		)
		(layer "F.Cu")
	)
	(gr_line
		(start 108.252768 -26.957274)
		(end 108.475526 -26.957274)
		(stroke
			(width 0.0508)
			(type default)
		)
		(layer "F.Cu")
	)
	(gr_line
		(start 108.263182 -29.591)
		(end 108.7374 -29.591)
		(stroke
			(width 0.0508)
			(type default)
		)
		(layer "F.Cu")
	)
	(gr_line
		(start 108.415074 -29.0322)
		(end 108.6866 -29.0322)
		(stroke
			(width 0.0508)
			(type default)
		)
		(layer "F.Cu")
	)
	(gr_line
		(start 108.475526 -26.957274)
		(end 108.60024 -26.83256)
		(stroke
			(width 0.0508)
			(type default)
		)
		(layer "F.Cu")
	)
	(gr_line
		(start 108.60024 -26.61158)
		(end 108.60024 -26.83256)
		(stroke
			(width 0.0508)
			(type default)
		)
		(layer "F.Cu")
	)
	(gr_line
		(start 108.772452 -42.598086)
		(end 109.11586 -42.941494)
		(stroke
			(width 0.0508)
			(type default)
		)
		(layer "F.Cu")
	)
	(gr_line
		(start 108.783628 -27.215592)
		(end 108.783628 -27.447494)
		(stroke
			(width 0.0508)
			(type default)
		)
		(layer "F.Cu")
	)
	(gr_line
		(start 108.783628 -27.215592)
		(end 108.786676 -27.215592)
		(stroke
			(width 0.0508)
			(type default)
		)
		(layer "F.Cu")
	)
	(gr_line
		(start 108.786676 -27.215592)
		(end 108.99267 -27.009598)
		(stroke
			(width 0.0508)
			(type default)
		)
		(layer "F.Cu")
	)
	(gr_line
		(start 108.81106 -35.320986)
		(end 109.135672 -34.996374)
		(stroke
			(width 0.0508)
			(type default)
		)
		(layer "F.Cu")
	)
	(gr_line
		(start 108.821474 -43.247056)
		(end 108.82884 -43.254422)
		(stroke
			(width 0.0508)
			(type default)
		)
		(layer "F.Cu")
	)
	(gr_line
		(start 108.82884 -43.276266)
		(end 109.195108 -43.642534)
		(stroke
			(width 0.0508)
			(type default)
		)
		(layer "F.Cu")
	)
	(gr_line
		(start 108.82884 -43.254422)
		(end 108.82884 -43.276266)
		(stroke
			(width 0.0508)
			(type default)
		)
		(layer "F.Cu")
	)
	(gr_line
		(start 109.11586 -42.941494)
		(end 109.195108 -42.941494)
		(stroke
			(width 0.0508)
			(type default)
		)
		(layer "F.Cu")
	)
	(gr_line
		(start 109.135672 -34.996374)
		(end 109.195108 -34.996374)
		(stroke
			(width 0.0508)
			(type default)
		)
		(layer "F.Cu")
	)
	(gr_line
		(start 109.195108 -35.697414)
		(end 109.396276 -35.898582)
		(stroke
			(width 0.0508)
			(type default)
		)
		(layer "F.Cu")
	)
	(gr_line
		(start 109.396276 -35.898582)
		(end 109.396276 -36.13785)
		(stroke
			(width 0.0508)
			(type default)
		)
		(layer "F.Cu")
	)
	(gr_line
		(start 110.749588 -46.489874)
		(end 111.060738 -46.178724)
		(stroke
			(width 0.0508)
			(type default)
		)
		(layer "F.Cu")
	)
	(gr_line
		(start 111.060738 -46.178724)
		(end 111.421418 -46.178724)
		(stroke
			(width 0.0508)
			(type default)
		)
		(layer "F.Cu")
	)
	(gr_line
		(start 111.092488 -42.598594)
		(end 111.171482 -42.5196)
		(stroke
			(width 0.0508)
			(type default)
		)
		(layer "F.Cu")
	)
	(gr_line
		(start 111.092488 -38.095174)
		(end 111.262668 -38.265354)
		(stroke
			(width 0.0635)
			(type default)
		)
		(layer "F.Cu")
	)
	(gr_line
		(start 111.153448 -34.749994)
		(end 111.686848 -34.749994)
		(stroke
			(width 0.0508)
			(type default)
		)
		(layer "F.Cu")
	)
	(gr_line
		(start 111.171482 -42.5196)
		(end 111.345726 -42.5196)
		(stroke
			(width 0.0508)
			(type default)
		)
		(layer "F.Cu")
	)
	(gr_line
		(start 111.262668 -38.265354)
		(end 111.887 -38.265354)
		(stroke
			(width 0.0635)
			(type default)
		)
		(layer "F.Cu")
	)
	(gr_line
		(start 111.345726 -42.5196)
		(end 111.6076 -42.781474)
		(stroke
			(width 0.0508)
			(type default)
		)
		(layer "F.Cu")
	)
	(gr_line
		(start 111.488728 -46.520354)
		(end 111.624618 -46.384464)
		(stroke
			(width 0.0508)
			(type default)
		)
		(layer "F.Cu")
	)
	(gr_line
		(start 111.603028 -38.582854)
		(end 111.628174 -38.608)
		(stroke
			(width 0.0635)
			(type default)
		)
		(layer "F.Cu")
	)
	(gr_line
		(start 111.6076 -42.781474)
		(end 112.221264 -42.781474)
		(stroke
			(width 0.0508)
			(type default)
		)
		(layer "F.Cu")
	)
	(gr_line
		(start 111.628174 -38.608)
		(end 111.719106 -38.608)
		(stroke
			(width 0.0635)
			(type default)
		)
		(layer "F.Cu")
	)
	(gr_line
		(start 111.686848 -34.749994)
		(end 111.809022 -34.62782)
		(stroke
			(width 0.0508)
			(type default)
		)
		(layer "F.Cu")
	)
	(gr_line
		(start 111.887 -38.265354)
		(end 111.973106 -38.35146)
		(stroke
			(width 0.0635)
			(type default)
		)
		(layer "F.Cu")
	)
	(gr_line
		(start 112.098328 -42.367454)
		(end 112.223042 -42.492168)
		(stroke
			(width 0.0508)
			(type default)
		)
		(layer "F.Cu")
	)
	(gr_line
		(start 112.098328 -34.629598)
		(end 112.098328 -34.800794)
		(stroke
			(width 0.0508)
			(type default)
		)
		(layer "F.Cu")
	)
	(gr_line
		(start 114.78895 -49.387506)
		(end 114.956844 -49.5554)
		(stroke
			(width 0.0508)
			(type default)
		)
		(layer "F.Cu")
	)
	(gr_line
		(start 114.790728 -49.0982)
		(end 115.1636 -49.0982)
		(stroke
			(width 0.0508)
			(type default)
		)
		(layer "F.Cu")
	)
	(gr_line
		(start 114.86134 -44.62526)
		(end 115.062 -44.4246)
		(stroke
			(width 0.0508)
			(type default)
		)
		(layer "F.Cu")
	)
	(gr_line
		(start 114.956844 -49.5554)
		(end 116.4844 -49.5554)
		(stroke
			(width 0.0508)
			(type default)
		)
		(layer "F.Cu")
	)
	(gr_line
		(start 115.06454 -44.831)
		(end 116.4336 -44.831)
		(stroke
			(width 0.0508)
			(type default)
		)
		(layer "F.Cu")
	)
	(gr_line
		(start 115.72494 -32.25546)
		(end 115.951 -32.0294)
		(stroke
			(width 0.0508)
			(type default)
		)
		(layer "F.Cu")
	)
	(gr_line
		(start 115.92814 -32.4612)
		(end 117.2464 -32.4612)
		(stroke
			(width 0.0508)
			(type default)
		)
		(layer "F.Cu")
	)
	(gr_line
		(start 116.140738 -36.95954)
		(end 116.5352 -37.354002)
		(stroke
			(width 0.0635)
			(type default)
		)
		(layer "F.Cu")
	)
	(gr_line
		(start 116.297202 -36.703)
		(end 116.5352 -36.465002)
		(stroke
			(width 0.0635)
			(type default)
		)
		(layer "F.Cu")
	)
	(gr_line
		(start 116.4336 -44.831)
		(end 116.84 -44.4246)
		(stroke
			(width 0.0508)
			(type default)
		)
		(layer "F.Cu")
	)
	(gr_line
		(start 116.4844 -49.5554)
		(end 116.9416 -49.0982)
		(stroke
			(width 0.0508)
			(type default)
		)
		(layer "F.Cu")
	)
	(gr_line
		(start 117.2464 -32.4612)
		(end 117.6528 -32.0548)
		(stroke
			(width 0.0508)
			(type default)
		)
		(layer "F.Cu")
	)
	(gr_line
		(start 117.3988 -37.354002)
		(end 118.1608 -37.354002)
		(stroke
			(width 0.0635)
			(type default)
		)
		(layer "F.Cu")
	)
	(gr_line
		(start 117.3988 -36.465002)
		(end 118.1862 -36.465002)
		(stroke
			(width 0.0635)
			(type default)
		)
		(layer "F.Cu")
	)
	(gr_line
		(start 118.1608 -37.354002)
		(end 118.237 -37.277802)
		(stroke
			(width 0.0635)
			(type default)
		)
		(layer "F.Cu")
	)
	(gr_line
		(start 118.1862 -36.465002)
		(end 118.237 -36.515802)
		(stroke
			(width 0.0635)
			(type default)
		)
		(layer "F.Cu")
	)
	(gr_line
		(start 118.237 -37.277802)
		(end 118.436644 -37.078158)
		(stroke
			(width 0.0635)
			(type default)
		)
		(layer "F.Cu")
	)
	(gr_line
		(start 118.237 -36.515802)
		(end 118.436644 -36.715446)
		(stroke
			(width 0.0635)
			(type default)
		)
		(layer "F.Cu")
	)
	(gr_line
		(start 135.4328 -5.818378)
		(end 135.632698 -5.61848)
		(stroke
			(width 0.0889)
			(type default)
		)
		(layer "F.Cu")
	)
	(gr_line
		(start 135.549894 -2.402332)
		(end 135.649716 -2.502154)
		(stroke
			(width 0.0889)
			(type default)
		)
		(layer "F.Cu")
	)
	(gr_line
		(start 135.549894 -1.68402)
		(end 135.549894 -2.402332)
		(stroke
			(width 0.0889)
			(type default)
		)
		(layer "F.Cu")
	)
	(gr_line
		(start 136.032748 -66.672206)
		(end 136.232646 -66.872104)
		(stroke
			(width 0.0889)
			(type default)
		)
		(layer "F.Cu")
	)
	(gr_line
		(start 136.067292 -5.61848)
		(end 136.26719 -5.818378)
		(stroke
			(width 0.0889)
			(type default)
		)
		(layer "F.Cu")
	)
	(gr_line
		(start 136.084564 -2.502154)
		(end 136.149842 -2.436876)
		(stroke
			(width 0.0889)
			(type default)
		)
		(layer "F.Cu")
	)
	(gr_line
		(start 136.149842 -1.68402)
		(end 136.149842 -2.436876)
		(stroke
			(width 0.0889)
			(type default)
		)
		(layer "F.Cu")
	)
	(gr_line
		(start 136.150096 -70.053708)
		(end 136.150096 -70.806564)
		(stroke
			(width 0.0889)
			(type default)
		)
		(layer "F.Cu")
	)
	(gr_line
		(start 136.150096 -70.053708)
		(end 136.215374 -69.98843)
		(stroke
			(width 0.0889)
			(type default)
		)
		(layer "F.Cu")
	)
	(gr_line
		(start 136.650222 -69.98843)
		(end 136.750044 -70.088252)
		(stroke
			(width 0.0889)
			(type default)
		)
		(layer "F.Cu")
	)
	(gr_line
		(start 136.66724 -66.872104)
		(end 136.867138 -66.672206)
		(stroke
			(width 0.0889)
			(type default)
		)
		(layer "F.Cu")
	)
	(gr_line
		(start 136.750044 -70.088252)
		(end 136.750044 -70.806564)
		(stroke
			(width 0.0889)
			(type default)
		)
		(layer "F.Cu")
	)
	(gr_line
		(start 140.83284 -5.818378)
		(end 141.032738 -5.61848)
		(stroke
			(width 0.0889)
			(type default)
		)
		(layer "F.Cu")
	)
	(gr_line
		(start 140.949934 -2.402332)
		(end 141.049756 -2.502154)
		(stroke
			(width 0.0889)
			(type default)
		)
		(layer "F.Cu")
	)
	(gr_line
		(start 140.949934 -1.68402)
		(end 140.949934 -2.402332)
		(stroke
			(width 0.0889)
			(type default)
		)
		(layer "F.Cu")
	)
	(gr_line
		(start 141.467332 -5.61848)
		(end 141.66723 -5.818378)
		(stroke
			(width 0.0889)
			(type default)
		)
		(layer "F.Cu")
	)
	(gr_line
		(start 141.484604 -2.502154)
		(end 141.549882 -2.436876)
		(stroke
			(width 0.0889)
			(type default)
		)
		(layer "F.Cu")
	)
	(gr_line
		(start 141.549882 -1.68402)
		(end 141.549882 -2.436876)
		(stroke
			(width 0.0889)
			(type default)
		)
		(layer "F.Cu")
	)
	(gr_line
		(start 145.632678 -66.672206)
		(end 145.832576 -66.872104)
		(stroke
			(width 0.0889)
			(type default)
		)
		(layer "F.Cu")
	)
	(gr_line
		(start 145.750026 -70.053708)
		(end 145.750026 -70.806564)
		(stroke
			(width 0.0889)
			(type default)
		)
		(layer "F.Cu")
	)
	(gr_line
		(start 145.750026 -70.053708)
		(end 145.815304 -69.98843)
		(stroke
			(width 0.0889)
			(type default)
		)
		(layer "F.Cu")
	)
	(gr_line
		(start 146.250152 -69.98843)
		(end 146.349974 -70.088252)
		(stroke
			(width 0.0889)
			(type default)
		)
		(layer "F.Cu")
	)
	(gr_line
		(start 146.26717 -66.872104)
		(end 146.467068 -66.672206)
		(stroke
			(width 0.0889)
			(type default)
		)
		(layer "F.Cu")
	)
	(gr_line
		(start 146.349974 -70.088252)
		(end 146.349974 -70.806564)
		(stroke
			(width 0.0889)
			(type default)
		)
		(layer "F.Cu")
	)
	(gr_line
		(start 152.832816 -5.818378)
		(end 153.032714 -5.61848)
		(stroke
			(width 0.0889)
			(type default)
		)
		(layer "F.Cu")
	)
	(gr_line
		(start 152.94991 -2.402332)
		(end 153.049732 -2.502154)
		(stroke
			(width 0.0889)
			(type default)
		)
		(layer "F.Cu")
	)
	(gr_line
		(start 152.94991 -1.68402)
		(end 152.94991 -2.402332)
		(stroke
			(width 0.0889)
			(type default)
		)
		(layer "F.Cu")
	)
	(gr_line
		(start 153.434796 -64.616076)
		(end 153.74366 -64.307212)
		(stroke
			(width 0.10795)
			(type default)
		)
		(layer "F.Cu")
	)
	(gr_line
		(start 153.467308 -5.61848)
		(end 153.667206 -5.818378)
		(stroke
			(width 0.0889)
			(type default)
		)
		(layer "F.Cu")
	)
	(gr_line
		(start 153.48458 -2.502154)
		(end 153.549858 -2.436876)
		(stroke
			(width 0.0889)
			(type default)
		)
		(layer "F.Cu")
	)
	(gr_line
		(start 153.549858 -1.68402)
		(end 153.549858 -2.436876)
		(stroke
			(width 0.0889)
			(type default)
		)
		(layer "F.Cu")
	)
	(gr_line
		(start 153.850086 -63.724536)
		(end 153.850086 -63.836296)
		(stroke
			(width 0.10795)
			(type default)
		)
		(layer "F.Cu")
	)
	(gr_line
		(start 153.850086 -62.59322)
		(end 153.850086 -63.721996)
		(stroke
			(width 0.10795)
			(type default)
		)
		(layer "F.Cu")
	)
	(gr_line
		(start 154.1018 -64.9224)
		(end 154.1145 -64.9097)
		(stroke
			(width 0.10795)
			(type default)
		)
		(layer "F.Cu")
	)
	(gr_line
		(start 154.1145 -64.675512)
		(end 154.1145 -64.9097)
		(stroke
			(width 0.10795)
			(type default)
		)
		(layer "F.Cu")
	)
	(gr_line
		(start 154.1145 -64.092836)
		(end 154.1145 -64.204596)
		(stroke
			(width 0.10795)
			(type default)
		)
		(layer "F.Cu")
	)
	(gr_line
		(start 154.15006 -69.9262)
		(end 154.15006 -70.806564)
		(stroke
			(width 0.10795)
			(type default)
		)
		(layer "F.Cu")
	)
	(gr_line
		(start 154.22626 -69.091048)
		(end 154.684984 -68.632324)
		(stroke
			(width 0.10795)
			(type default)
		)
		(layer "F.Cu")
	)
	(gr_line
		(start 154.372818 -63.834518)
		(end 154.450034 -63.757302)
		(stroke
			(width 0.10795)
			(type default)
		)
		(layer "F.Cu")
	)
	(gr_line
		(start 154.450034 -62.59322)
		(end 154.450034 -63.757302)
		(stroke
			(width 0.10795)
			(type default)
		)
		(layer "F.Cu")
	)
	(gr_line
		(start 154.5971 -69.45757)
		(end 154.740864 -69.313806)
		(stroke
			(width 0.10795)
			(type default)
		)
		(layer "F.Cu")
	)
	(gr_line
		(start 154.661616 -69.9389)
		(end 154.750008 -70.027292)
		(stroke
			(width 0.10795)
			(type default)
		)
		(layer "F.Cu")
	)
	(gr_line
		(start 154.740864 -69.313806)
		(end 154.913584 -69.313806)
		(stroke
			(width 0.10795)
			(type default)
		)
		(layer "F.Cu")
	)
	(gr_line
		(start 154.750008 -70.027292)
		(end 154.750008 -70.806564)
		(stroke
			(width 0.10795)
			(type default)
		)
		(layer "F.Cu")
	)
	(gr_line
		(start 163.625022 -3.278378)
		(end 163.74745 -3.15595)
		(stroke
			(width 0.10795)
			(type default)
		)
		(layer "F.Cu")
	)
	(gr_line
		(start 163.74999 -1.68402)
		(end 163.74999 -2.357628)
		(stroke
			(width 0.10795)
			(type default)
		)
		(layer "F.Cu")
	)
	(gr_line
		(start 163.9062 -3.938778)
		(end 164.11829 -3.726688)
		(stroke
			(width 0.10795)
			(type default)
		)
		(layer "F.Cu")
	)
	(gr_line
		(start 164.049964 -9.183878)
		(end 164.049964 -9.897364)
		(stroke
			(width 0.10795)
			(type default)
		)
		(layer "F.Cu")
	)
	(gr_line
		(start 164.049964 -9.183878)
		(end 164.279072 -8.95477)
		(stroke
			(width 0.10795)
			(type default)
		)
		(layer "F.Cu")
	)
	(gr_line
		(start 164.11829 -3.52425)
		(end 164.11829 -3.726688)
		(stroke
			(width 0.10795)
			(type default)
		)
		(layer "F.Cu")
	)
	(gr_line
		(start 164.12083 -2.725928)
		(end 164.349938 -2.49682)
		(stroke
			(width 0.10795)
			(type default)
		)
		(layer "F.Cu")
	)
	(gr_line
		(start 164.281612 -7.576566)
		(end 164.281612 -7.821676)
		(stroke
			(width 0.10795)
			(type default)
		)
		(layer "F.Cu")
	)
	(gr_line
		(start 164.281612 -7.576566)
		(end 164.338 -7.520178)
		(stroke
			(width 0.10795)
			(type default)
		)
		(layer "F.Cu")
	)
	(gr_line
		(start 164.349938 -1.68402)
		(end 164.349938 -2.49682)
		(stroke
			(width 0.10795)
			(type default)
		)
		(layer "F.Cu")
	)
	(gr_line
		(start 164.649912 -9.32307)
		(end 164.649912 -9.897364)
		(stroke
			(width 0.10795)
			(type default)
		)
		(layer "F.Cu")
	)
	(gr_line
		(start 164.652452 -8.189976)
		(end 164.9857 -7.856728)
		(stroke
			(width 0.10795)
			(type default)
		)
		(layer "F.Cu")
	)
	(gr_line
		(start 164.832792 -66.672206)
		(end 165.03269 -66.872104)
		(stroke
			(width 0.0889)
			(type default)
		)
		(layer "F.Cu")
	)
	(gr_line
		(start 164.95014 -70.053708)
		(end 164.95014 -70.806564)
		(stroke
			(width 0.0889)
			(type default)
		)
		(layer "F.Cu")
	)
	(gr_line
		(start 164.95014 -70.053708)
		(end 165.015418 -69.98843)
		(stroke
			(width 0.0889)
			(type default)
		)
		(layer "F.Cu")
	)
	(gr_line
		(start 164.9857 -7.824978)
		(end 164.9857 -7.856728)
		(stroke
			(width 0.10795)
			(type default)
		)
		(layer "F.Cu")
	)
	(gr_line
		(start 165.450266 -69.98843)
		(end 165.550088 -70.088252)
		(stroke
			(width 0.0889)
			(type default)
		)
		(layer "F.Cu")
	)
	(gr_line
		(start 165.467284 -66.872104)
		(end 165.667182 -66.672206)
		(stroke
			(width 0.0889)
			(type default)
		)
		(layer "F.Cu")
	)
	(gr_line
		(start 165.550088 -70.088252)
		(end 165.550088 -70.806564)
		(stroke
			(width 0.0889)
			(type default)
		)
		(layer "F.Cu")
	)
	(gr_line
		(start 172.03293 -5.792978)
		(end 172.232828 -5.59308)
		(stroke
			(width 0.0889)
			(type default)
		)
		(layer "F.Cu")
	)
	(gr_line
		(start 172.150024 -2.402332)
		(end 172.249846 -2.502154)
		(stroke
			(width 0.0889)
			(type default)
		)
		(layer "F.Cu")
	)
	(gr_line
		(start 172.150024 -1.68402)
		(end 172.150024 -2.402332)
		(stroke
			(width 0.0889)
			(type default)
		)
		(layer "F.Cu")
	)
	(gr_line
		(start 172.667422 -5.59308)
		(end 172.86732 -5.792978)
		(stroke
			(width 0.0889)
			(type default)
		)
		(layer "F.Cu")
	)
	(gr_line
		(start 172.684694 -2.502154)
		(end 172.749972 -2.436876)
		(stroke
			(width 0.0889)
			(type default)
		)
		(layer "F.Cu")
	)
	(gr_line
		(start 172.749972 -1.68402)
		(end 172.749972 -2.436876)
		(stroke
			(width 0.0889)
			(type default)
		)
		(layer "F.Cu")
	)
	(gr_line
		(start 181.63286 -5.818378)
		(end 181.832758 -5.61848)
		(stroke
			(width 0.0889)
			(type default)
		)
		(layer "F.Cu")
	)
	(gr_line
		(start 181.749954 -2.402332)
		(end 181.849776 -2.502154)
		(stroke
			(width 0.0889)
			(type default)
		)
		(layer "F.Cu")
	)
	(gr_line
		(start 181.749954 -1.68402)
		(end 181.749954 -2.402332)
		(stroke
			(width 0.0889)
			(type default)
		)
		(layer "F.Cu")
	)
	(gr_line
		(start 181.897528 -4.954778)
		(end 181.897528 -4.972558)
		(stroke
			(width 0.0889)
			(type default)
		)
		(layer "F.Cu")
	)
	(gr_line
		(start 181.897528 -3.86207)
		(end 181.897528 -3.87985)
		(stroke
			(width 0.0889)
			(type default)
		)
		(layer "F.Cu")
	)
	(gr_line
		(start 182.0418 -4.649978)
		(end 182.0418 -4.667758)
		(stroke
			(width 0.0889)
			(type default)
		)
		(layer "F.Cu")
	)
	(gr_line
		(start 182.0418 -4.16687)
		(end 182.0418 -4.18465)
		(stroke
			(width 0.0889)
			(type default)
		)
		(layer "F.Cu")
	)
	(gr_line
		(start 182.232808 -66.672206)
		(end 182.432706 -66.872104)
		(stroke
			(width 0.0889)
			(type default)
		)
		(layer "F.Cu")
	)
	(gr_line
		(start 182.267352 -5.61848)
		(end 182.46725 -5.818378)
		(stroke
			(width 0.0889)
			(type default)
		)
		(layer "F.Cu")
	)
	(gr_line
		(start 182.284624 -2.502154)
		(end 182.349902 -2.436876)
		(stroke
			(width 0.0889)
			(type default)
		)
		(layer "F.Cu")
	)
	(gr_line
		(start 182.349902 -1.68402)
		(end 182.349902 -2.436876)
		(stroke
			(width 0.0889)
			(type default)
		)
		(layer "F.Cu")
	)
	(gr_line
		(start 182.350156 -70.053708)
		(end 182.350156 -70.806564)
		(stroke
			(width 0.0889)
			(type default)
		)
		(layer "F.Cu")
	)
	(gr_line
		(start 182.350156 -70.053708)
		(end 182.415434 -69.98843)
		(stroke
			(width 0.0889)
			(type default)
		)
		(layer "F.Cu")
	)
	(gr_line
		(start 182.850282 -69.98843)
		(end 182.950104 -70.088252)
		(stroke
			(width 0.0889)
			(type default)
		)
		(layer "F.Cu")
	)
	(gr_line
		(start 182.8673 -66.872104)
		(end 183.067198 -66.672206)
		(stroke
			(width 0.0889)
			(type default)
		)
		(layer "F.Cu")
	)
	(gr_line
		(start 182.950104 -70.088252)
		(end 182.950104 -70.806564)
		(stroke
			(width 0.0889)
			(type default)
		)
		(layer "F.Cu")
	)
	(gr_line
		(start 186.132724 -5.996178)
		(end 186.270138 -6.133592)
		(stroke
			(width 0.0889)
			(type default)
		)
		(layer "F.Cu")
	)
	(gr_line
		(start 186.249818 -9.155938)
		(end 186.249818 -9.897364)
		(stroke
			(width 0.0889)
			(type default)
		)
		(layer "F.Cu")
	)
	(gr_line
		(start 186.249818 -9.155938)
		(end 186.731656 -8.6741)
		(stroke
			(width 0.0889)
			(type default)
		)
		(layer "F.Cu")
	)
	(gr_line
		(start 186.704986 -6.133592)
		(end 186.8424 -5.996178)
		(stroke
			(width 0.0889)
			(type default)
		)
		(layer "F.Cu")
	)
	(gr_line
		(start 186.732672 -66.672206)
		(end 186.8932 -66.511678)
		(stroke
			(width 0.0889)
			(type default)
		)
		(layer "F.Cu")
	)
	(gr_line
		(start 186.8424 -5.996178)
		(end 186.967114 -5.996178)
		(stroke
			(width 0.0889)
			(type default)
		)
		(layer "F.Cu")
	)
	(gr_line
		(start 186.85002 -63.33617)
		(end 187.103258 -63.589408)
		(stroke
			(width 0.0889)
			(type default)
		)
		(layer "F.Cu")
	)
	(gr_line
		(start 186.85002 -62.59322)
		(end 186.85002 -63.33617)
		(stroke
			(width 0.0889)
			(type default)
		)
		(layer "F.Cu")
	)
	(gr_line
		(start 186.85002 -8.990584)
		(end 186.85002 -9.897364)
		(stroke
			(width 0.0889)
			(type default)
		)
		(layer "F.Cu")
	)
	(gr_line
		(start 186.85002 -8.990584)
		(end 187.038996 -8.801608)
		(stroke
			(width 0.0889)
			(type default)
		)
		(layer "F.Cu")
	)
	(gr_line
		(start 186.8932 -7.958582)
		(end 186.8932 -7.977886)
		(stroke
			(width 0.0889)
			(type default)
		)
		(layer "F.Cu")
	)
	(gr_line
		(start 187.038996 -8.263382)
		(end 187.038996 -8.282686)
		(stroke
			(width 0.0889)
			(type default)
		)
		(layer "F.Cu")
	)
	(gr_line
		(start 187.20054 -66.305684)
		(end 187.567062 -66.672206)
		(stroke
			(width 0.0889)
			(type default)
		)
		(layer "F.Cu")
	)
	(gr_line
		(start 187.410598 -63.377064)
		(end 187.449968 -63.337694)
		(stroke
			(width 0.0889)
			(type default)
		)
		(layer "F.Cu")
	)
	(gr_line
		(start 187.449968 -62.59322)
		(end 187.449968 -63.337694)
		(stroke
			(width 0.0889)
			(type default)
		)
		(layer "F.Cu")
	)
	(gr_line
		(start 1.9304 -67.178682)
		(end 2.164842 -66.94424)
		(stroke
			(width 0.06985)
			(type default)
		)
		(layer "B.Cu")
	)
	(gr_line
		(start 1.9304 -66.221102)
		(end 2.164842 -66.455544)
		(stroke
			(width 0.06985)
			(type default)
		)
		(layer "B.Cu")
	)
	(gr_line
		(start 1.9304 -64.178688)
		(end 2.164842 -63.944246)
		(stroke
			(width 0.06985)
			(type default)
		)
		(layer "B.Cu")
	)
	(gr_line
		(start 1.9304 -63.221108)
		(end 2.164842 -63.45555)
		(stroke
			(width 0.06985)
			(type default)
		)
		(layer "B.Cu")
	)
	(gr_line
		(start 1.9304 -61.178694)
		(end 2.164842 -60.944252)
		(stroke
			(width 0.06985)
			(type default)
		)
		(layer "B.Cu")
	)
	(gr_line
		(start 1.9304 -60.221114)
		(end 2.164842 -60.455556)
		(stroke
			(width 0.06985)
			(type default)
		)
		(layer "B.Cu")
	)
	(gr_line
		(start 2.4003 -52.42052)
		(end 2.4003 -52.55006)
		(stroke
			(width 0.06985)
			(type default)
		)
		(layer "B.Cu")
	)
	(gr_line
		(start 2.4003 -51.181)
		(end 2.4003 -51.31054)
		(stroke
			(width 0.06985)
			(type default)
		)
		(layer "B.Cu")
	)
	(gr_line
		(start 2.74574 -52.89296)
		(end 2.94386 -52.69484)
		(stroke
			(width 0.06985)
			(type default)
		)
		(layer "B.Cu")
	)
	(gr_line
		(start 2.74574 -52.07762)
		(end 2.94386 -52.27574)
		(stroke
			(width 0.06985)
			(type default)
		)
		(layer "B.Cu")
	)
	(gr_line
		(start 2.74574 -51.65344)
		(end 2.94386 -51.45532)
		(stroke
			(width 0.06985)
			(type default)
		)
		(layer "B.Cu")
	)
	(gr_line
		(start 2.74574 -50.8381)
		(end 2.94386 -51.03622)
		(stroke
			(width 0.06985)
			(type default)
		)
		(layer "B.Cu")
	)
	(gr_line
		(start 2.94386 -52.27574)
		(end 2.94386 -52.69484)
		(stroke
			(width 0.06985)
			(type default)
		)
		(layer "B.Cu")
	)
	(gr_line
		(start 2.94386 -51.03622)
		(end 2.94386 -51.45532)
		(stroke
			(width 0.06985)
			(type default)
		)
		(layer "B.Cu")
	)
	(gr_line
		(start 3.08229 -54.13883)
		(end 3.17373 -54.23027)
		(stroke
			(width 0.06985)
			(type default)
		)
		(layer "B.Cu")
	)
	(gr_line
		(start 3.083814 -53.651912)
		(end 3.364484 -53.651912)
		(stroke
			(width 0.06985)
			(type default)
		)
		(layer "B.Cu")
	)
	(gr_line
		(start 3.32486 -59.664346)
		(end 3.559302 -59.429904)
		(stroke
			(width 0.06985)
			(type default)
		)
		(layer "B.Cu")
	)
	(gr_line
		(start 3.32486 -58.706766)
		(end 3.559302 -58.941208)
		(stroke
			(width 0.06985)
			(type default)
		)
		(layer "B.Cu")
	)
	(gr_line
		(start 3.364484 -53.651912)
		(end 3.660648 -53.94833)
		(stroke
			(width 0.06985)
			(type default)
		)
		(layer "B.Cu")
	)
	(gr_line
		(start 3.45186 -65.664334)
		(end 3.686302 -65.429892)
		(stroke
			(width 0.06985)
			(type default)
		)
		(layer "B.Cu")
	)
	(gr_line
		(start 3.45186 -64.706754)
		(end 3.686302 -64.941196)
		(stroke
			(width 0.06985)
			(type default)
		)
		(layer "B.Cu")
	)
	(gr_line
		(start 3.45186 -62.66434)
		(end 3.686302 -62.429898)
		(stroke
			(width 0.06985)
			(type default)
		)
		(layer "B.Cu")
	)
	(gr_line
		(start 3.45186 -61.70676)
		(end 3.686302 -61.941202)
		(stroke
			(width 0.06985)
			(type default)
		)
		(layer "B.Cu")
	)
	(gr_line
		(start 3.660648 -53.94833)
		(end 3.660648 -54.228746)
		(stroke
			(width 0.06985)
			(type default)
		)
		(layer "B.Cu")
	)
	(gr_line
		(start 4.577588 -66.94424)
		(end 4.583176 -66.949828)
		(stroke
			(width 0.06985)
			(type default)
		)
		(layer "B.Cu")
	)
	(gr_line
		(start 4.577588 -66.455544)
		(end 4.583176 -66.449956)
		(stroke
			(width 0.06985)
			(type default)
		)
		(layer "B.Cu")
	)
	(gr_line
		(start 4.577588 -63.944246)
		(end 4.583176 -63.949834)
		(stroke
			(width 0.06985)
			(type default)
		)
		(layer "B.Cu")
	)
	(gr_line
		(start 4.577588 -63.45555)
		(end 4.583176 -63.449962)
		(stroke
			(width 0.06985)
			(type default)
		)
		(layer "B.Cu")
	)
	(gr_line
		(start 4.577588 -62.444122)
		(end 4.58343 -62.449964)
		(stroke
			(width 0.06985)
			(type default)
		)
		(layer "B.Cu")
	)
	(gr_line
		(start 4.577588 -61.955426)
		(end 4.583176 -61.949838)
		(stroke
			(width 0.06985)
			(type default)
		)
		(layer "B.Cu")
	)
	(gr_line
		(start 4.577588 -60.944252)
		(end 4.583176 -60.94984)
		(stroke
			(width 0.06985)
			(type default)
		)
		(layer "B.Cu")
	)
	(gr_line
		(start 4.577588 -60.455556)
		(end 4.583176 -60.449968)
		(stroke
			(width 0.06985)
			(type default)
		)
		(layer "B.Cu")
	)
	(gr_line
		(start 4.583176 -66.949828)
		(end 5.575046 -66.949828)
		(stroke
			(width 0.06985)
			(type default)
		)
		(layer "B.Cu")
	)
	(gr_line
		(start 4.583176 -66.449956)
		(end 5.575046 -66.449956)
		(stroke
			(width 0.06985)
			(type default)
		)
		(layer "B.Cu")
	)
	(gr_line
		(start 4.583176 -63.949834)
		(end 5.575046 -63.949834)
		(stroke
			(width 0.06985)
			(type default)
		)
		(layer "B.Cu")
	)
	(gr_line
		(start 4.583176 -63.449962)
		(end 5.575046 -63.449962)
		(stroke
			(width 0.06985)
			(type default)
		)
		(layer "B.Cu")
	)
	(gr_line
		(start 4.583176 -61.949838)
		(end 5.575046 -61.949838)
		(stroke
			(width 0.06985)
			(type default)
		)
		(layer "B.Cu")
	)
	(gr_line
		(start 4.583176 -60.94984)
		(end 5.575046 -60.94984)
		(stroke
			(width 0.06985)
			(type default)
		)
		(layer "B.Cu")
	)
	(gr_line
		(start 4.583176 -60.449968)
		(end 5.575046 -60.449968)
		(stroke
			(width 0.06985)
			(type default)
		)
		(layer "B.Cu")
	)
	(gr_line
		(start 4.58343 -62.449964)
		(end 5.575046 -62.449964)
		(stroke
			(width 0.06985)
			(type default)
		)
		(layer "B.Cu")
	)
	(gr_line
		(start 4.828286 -54.949852)
		(end 5.575046 -54.949852)
		(stroke
			(width 0.06985)
			(type default)
		)
		(layer "B.Cu")
	)
	(gr_line
		(start 4.837938 -54.471062)
		(end 4.85902 -54.44998)
		(stroke
			(width 0.06985)
			(type default)
		)
		(layer "B.Cu")
	)
	(gr_line
		(start 4.85902 -54.44998)
		(end 5.575046 -54.44998)
		(stroke
			(width 0.06985)
			(type default)
		)
		(layer "B.Cu")
	)
	(gr_line
		(start 4.868164 -65.449958)
		(end 5.575046 -65.449958)
		(stroke
			(width 0.06985)
			(type default)
		)
		(layer "B.Cu")
	)
	(gr_line
		(start 4.873498 -64.966596)
		(end 4.890262 -64.949832)
		(stroke
			(width 0.06985)
			(type default)
		)
		(layer "B.Cu")
	)
	(gr_line
		(start 4.890262 -64.949832)
		(end 5.575046 -64.949832)
		(stroke
			(width 0.06985)
			(type default)
		)
		(layer "B.Cu")
	)
	(gr_line
		(start 4.890262 -58.949844)
		(end 5.575046 -58.949844)
		(stroke
			(width 0.06985)
			(type default)
		)
		(layer "B.Cu")
	)
	(gr_line
		(start 4.898898 -59.429904)
		(end 4.918964 -59.44997)
		(stroke
			(width 0.06985)
			(type default)
		)
		(layer "B.Cu")
	)
	(gr_line
		(start 4.918964 -59.44997)
		(end 5.575046 -59.44997)
		(stroke
			(width 0.06985)
			(type default)
		)
		(layer "B.Cu")
	)
	(gr_line
		(start 5.575046 -57.949846)
		(end 6.235954 -57.949846)
		(stroke
			(width 0.06985)
			(type default)
		)
		(layer "B.Cu")
	)
	(gr_line
		(start 5.575046 -57.449974)
		(end 6.294374 -57.449974)
		(stroke
			(width 0.06985)
			(type default)
		)
		(layer "B.Cu")
	)
	(gr_line
		(start 5.575046 -56.449976)
		(end 6.288024 -56.449976)
		(stroke
			(width 0.06985)
			(type default)
		)
		(layer "B.Cu")
	)
	(gr_line
		(start 5.575046 -55.94985)
		(end 6.29285 -55.94985)
		(stroke
			(width 0.06985)
			(type default)
		)
		(layer "B.Cu")
	)
	(gr_line
		(start 6.235954 -57.949846)
		(end 6.270752 -57.915048)
		(stroke
			(width 0.06985)
			(type default)
		)
		(layer "B.Cu")
	)
	(gr_line
		(start 6.288024 -56.449976)
		(end 6.296152 -56.441848)
		(stroke
			(width 0.06985)
			(type default)
		)
		(layer "B.Cu")
	)
	(gr_line
		(start 6.29285 -55.94985)
		(end 6.296152 -55.953152)
		(stroke
			(width 0.06985)
			(type default)
		)
		(layer "B.Cu")
	)
	(gr_line
		(start 7.877048 -51.361848)
		(end 8.128 -51.6128)
		(stroke
			(width 0.06985)
			(type default)
		)
		(layer "B.Cu")
	)
	(gr_line
		(start 7.877048 -50.873152)
		(end 8.128 -50.6222)
		(stroke
			(width 0.06985)
			(type default)
		)
		(layer "B.Cu")
	)
	(gr_line
		(start 8.505698 -53.241702)
		(end 8.8392 -52.9082)
		(stroke
			(width 0.06985)
			(type default)
		)
		(layer "B.Cu")
	)
	(gr_line
		(start 8.588248 -53.647848)
		(end 8.8392 -53.8988)
		(stroke
			(width 0.06985)
			(type default)
		)
		(layer "B.Cu")
	)
	(gr_line
		(start 17.349978 -8.447278)
		(end 17.605502 -8.702802)
		(stroke
			(width 0.06985)
			(type default)
		)
		(layer "B.Cu")
	)
	(gr_line
		(start 17.349978 -5.814568)
		(end 17.349978 -8.447278)
		(stroke
			(width 0.06985)
			(type default)
		)
		(layer "B.Cu")
	)
	(gr_line
		(start 18.094198 -8.702802)
		(end 18.349976 -8.447024)
		(stroke
			(width 0.06985)
			(type default)
		)
		(layer "B.Cu")
	)
	(gr_line
		(start 18.349976 -5.814568)
		(end 18.349976 -8.447024)
		(stroke
			(width 0.06985)
			(type default)
		)
		(layer "B.Cu")
	)
	(gr_line
		(start 19.271742 -43.19524)
		(end 19.469862 -43.39336)
		(stroke
			(width 0.06985)
			(type default)
		)
		(layer "B.Cu")
	)
	(gr_line
		(start 19.469862 -43.39336)
		(end 19.888962 -43.39336)
		(stroke
			(width 0.06985)
			(type default)
		)
		(layer "B.Cu")
	)
	(gr_line
		(start 19.614642 -42.8498)
		(end 19.744182 -42.8498)
		(stroke
			(width 0.06985)
			(type default)
		)
		(layer "B.Cu")
	)
	(gr_line
		(start 19.888962 -43.39336)
		(end 20.087082 -43.19524)
		(stroke
			(width 0.06985)
			(type default)
		)
		(layer "B.Cu")
	)
	(gr_line
		(start 20.09521 -15.488666)
		(end 20.329652 -15.254224)
		(stroke
			(width 0.06985)
			(type default)
		)
		(layer "B.Cu")
	)
	(gr_line
		(start 20.193 -13.1572)
		(end 20.329652 -13.293852)
		(stroke
			(width 0.06985)
			(type default)
		)
		(layer "B.Cu")
	)
	(gr_line
		(start 20.193 -12.2428)
		(end 20.329652 -12.106148)
		(stroke
			(width 0.06985)
			(type default)
		)
		(layer "B.Cu")
	)
	(gr_line
		(start 20.818348 -15.254224)
		(end 21.05279 -15.488666)
		(stroke
			(width 0.06985)
			(type default)
		)
		(layer "B.Cu")
	)
	(gr_line
		(start 20.818348 -13.293852)
		(end 20.955 -13.1572)
		(stroke
			(width 0.06985)
			(type default)
		)
		(layer "B.Cu")
	)
	(gr_line
		(start 20.818348 -12.106148)
		(end 20.955 -12.2428)
		(stroke
			(width 0.06985)
			(type default)
		)
		(layer "B.Cu")
	)
	(gr_line
		(start 21.34997 -8.447278)
		(end 21.605494 -8.702802)
		(stroke
			(width 0.06985)
			(type default)
		)
		(layer "B.Cu")
	)
	(gr_line
		(start 21.34997 -5.814568)
		(end 21.34997 -8.447278)
		(stroke
			(width 0.06985)
			(type default)
		)
		(layer "B.Cu")
	)
	(gr_line
		(start 21.6662 -13.8176)
		(end 21.717 -13.7668)
		(stroke
			(width 0.06985)
			(type default)
		)
		(layer "B.Cu")
	)
	(gr_line
		(start 21.717 -13.1572)
		(end 21.717 -13.7668)
		(stroke
			(width 0.06985)
			(type default)
		)
		(layer "B.Cu")
	)
	(gr_line
		(start 21.717 -12.2428)
		(end 21.853652 -12.106148)
		(stroke
			(width 0.06985)
			(type default)
		)
		(layer "B.Cu")
	)
	(gr_line
		(start 22.09419 -8.702802)
		(end 22.349968 -8.447024)
		(stroke
			(width 0.06985)
			(type default)
		)
		(layer "B.Cu")
	)
	(gr_line
		(start 22.342348 -12.106148)
		(end 22.479 -12.2428)
		(stroke
			(width 0.06985)
			(type default)
		)
		(layer "B.Cu")
	)
	(gr_line
		(start 22.349968 -5.814568)
		(end 22.349968 -8.447024)
		(stroke
			(width 0.06985)
			(type default)
		)
		(layer "B.Cu")
	)
	(gr_line
		(start 22.479 -13.7668)
		(end 22.5298 -13.8176)
		(stroke
			(width 0.06985)
			(type default)
		)
		(layer "B.Cu")
	)
	(gr_line
		(start 22.479 -13.1572)
		(end 22.479 -13.7668)
		(stroke
			(width 0.06985)
			(type default)
		)
		(layer "B.Cu")
	)
	(gr_line
		(start 25.349962 -8.447278)
		(end 25.605486 -8.702802)
		(stroke
			(width 0.06985)
			(type default)
		)
		(layer "B.Cu")
	)
	(gr_line
		(start 25.349962 -5.814568)
		(end 25.349962 -8.447278)
		(stroke
			(width 0.06985)
			(type default)
		)
		(layer "B.Cu")
	)
	(gr_line
		(start 25.4127 -13.8176)
		(end 25.4635 -13.7668)
		(stroke
			(width 0.06985)
			(type default)
		)
		(layer "B.Cu")
	)
	(gr_line
		(start 25.4635 -13.1572)
		(end 25.4635 -13.7668)
		(stroke
			(width 0.06985)
			(type default)
		)
		(layer "B.Cu")
	)
	(gr_line
		(start 25.4635 -12.2428)
		(end 25.600152 -12.106148)
		(stroke
			(width 0.06985)
			(type default)
		)
		(layer "B.Cu")
	)
	(gr_line
		(start 26.088848 -12.106148)
		(end 26.2255 -12.2428)
		(stroke
			(width 0.06985)
			(type default)
		)
		(layer "B.Cu")
	)
	(gr_line
		(start 26.094182 -8.702802)
		(end 26.34996 -8.447024)
		(stroke
			(width 0.06985)
			(type default)
		)
		(layer "B.Cu")
	)
	(gr_line
		(start 26.2255 -13.7668)
		(end 26.2763 -13.8176)
		(stroke
			(width 0.06985)
			(type default)
		)
		(layer "B.Cu")
	)
	(gr_line
		(start 26.2255 -13.1572)
		(end 26.2255 -13.7668)
		(stroke
			(width 0.06985)
			(type default)
		)
		(layer "B.Cu")
	)
	(gr_line
		(start 26.34996 -5.814568)
		(end 26.34996 -8.447024)
		(stroke
			(width 0.06985)
			(type default)
		)
		(layer "B.Cu")
	)
	(gr_line
		(start 29.349954 -8.447278)
		(end 29.605478 -8.702802)
		(stroke
			(width 0.06985)
			(type default)
		)
		(layer "B.Cu")
	)
	(gr_line
		(start 29.349954 -5.814568)
		(end 29.349954 -8.447278)
		(stroke
			(width 0.06985)
			(type default)
		)
		(layer "B.Cu")
	)
	(gr_line
		(start 29.4132 -14.5796)
		(end 29.600652 -14.392148)
		(stroke
			(width 0.06985)
			(type default)
		)
		(layer "B.Cu")
	)
	(gr_line
		(start 29.464 -13.1572)
		(end 29.600652 -13.293852)
		(stroke
			(width 0.06985)
			(type default)
		)
		(layer "B.Cu")
	)
	(gr_line
		(start 29.464 -12.2428)
		(end 29.600652 -12.106148)
		(stroke
			(width 0.06985)
			(type default)
		)
		(layer "B.Cu")
	)
	(gr_line
		(start 30.089348 -14.392148)
		(end 30.2768 -14.5796)
		(stroke
			(width 0.06985)
			(type default)
		)
		(layer "B.Cu")
	)
	(gr_line
		(start 30.089348 -13.293852)
		(end 30.226 -13.1572)
		(stroke
			(width 0.06985)
			(type default)
		)
		(layer "B.Cu")
	)
	(gr_line
		(start 30.089348 -12.106148)
		(end 30.226 -12.2428)
		(stroke
			(width 0.06985)
			(type default)
		)
		(layer "B.Cu")
	)
	(gr_line
		(start 30.094174 -8.702802)
		(end 30.349952 -8.447024)
		(stroke
			(width 0.06985)
			(type default)
		)
		(layer "B.Cu")
	)
	(gr_line
		(start 30.349952 -5.814568)
		(end 30.349952 -8.447024)
		(stroke
			(width 0.06985)
			(type default)
		)
		(layer "B.Cu")
	)
	(gr_line
		(start 33.349946 -8.447278)
		(end 33.60547 -8.702802)
		(stroke
			(width 0.06985)
			(type default)
		)
		(layer "B.Cu")
	)
	(gr_line
		(start 33.349946 -5.814568)
		(end 33.349946 -8.447278)
		(stroke
			(width 0.06985)
			(type default)
		)
		(layer "B.Cu")
	)
	(gr_line
		(start 33.4264 -14.5796)
		(end 33.613852 -14.392148)
		(stroke
			(width 0.06985)
			(type default)
		)
		(layer "B.Cu")
	)
	(gr_line
		(start 33.4772 -13.1572)
		(end 33.613852 -13.293852)
		(stroke
			(width 0.06985)
			(type default)
		)
		(layer "B.Cu")
	)
	(gr_line
		(start 33.4772 -12.2428)
		(end 33.613852 -12.106148)
		(stroke
			(width 0.06985)
			(type default)
		)
		(layer "B.Cu")
	)
	(gr_line
		(start 34.094166 -8.702802)
		(end 34.349944 -8.447024)
		(stroke
			(width 0.06985)
			(type default)
		)
		(layer "B.Cu")
	)
	(gr_line
		(start 34.102548 -14.392148)
		(end 34.29 -14.5796)
		(stroke
			(width 0.06985)
			(type default)
		)
		(layer "B.Cu")
	)
	(gr_line
		(start 34.102548 -13.293852)
		(end 34.2392 -13.1572)
		(stroke
			(width 0.06985)
			(type default)
		)
		(layer "B.Cu")
	)
	(gr_line
		(start 34.102548 -12.106148)
		(end 34.2392 -12.2428)
		(stroke
			(width 0.06985)
			(type default)
		)
		(layer "B.Cu")
	)
	(gr_line
		(start 34.349944 -5.814568)
		(end 34.349944 -8.447024)
		(stroke
			(width 0.06985)
			(type default)
		)
		(layer "B.Cu")
	)
	(gr_line
		(start 36.236148 -23.358348)
		(end 36.449 -23.5712)
		(stroke
			(width 0.06985)
			(type default)
		)
		(layer "B.Cu")
	)
	(gr_line
		(start 36.236148 -22.869652)
		(end 36.449 -22.6568)
		(stroke
			(width 0.06985)
			(type default)
		)
		(layer "B.Cu")
	)
	(gr_line
		(start 36.449 -23.5712)
		(end 36.5252 -23.495)
		(stroke
			(width 0.06985)
			(type default)
		)
		(layer "B.Cu")
	)
	(gr_line
		(start 36.449 -22.6568)
		(end 36.5252 -22.733)
		(stroke
			(width 0.06985)
			(type default)
		)
		(layer "B.Cu")
	)
	(gr_line
		(start 36.5252 -23.495)
		(end 37.2872 -23.495)
		(stroke
			(width 0.06985)
			(type default)
		)
		(layer "B.Cu")
	)
	(gr_line
		(start 36.5252 -22.733)
		(end 37.2872 -22.733)
		(stroke
			(width 0.06985)
			(type default)
		)
		(layer "B.Cu")
	)
	(gr_line
		(start 37.349938 -8.447278)
		(end 37.605462 -8.702802)
		(stroke
			(width 0.06985)
			(type default)
		)
		(layer "B.Cu")
	)
	(gr_line
		(start 37.349938 -5.814568)
		(end 37.349938 -8.447278)
		(stroke
			(width 0.06985)
			(type default)
		)
		(layer "B.Cu")
	)
	(gr_line
		(start 37.41801 -13.8176)
		(end 37.46881 -13.7668)
		(stroke
			(width 0.06985)
			(type default)
		)
		(layer "B.Cu")
	)
	(gr_line
		(start 37.46881 -13.1572)
		(end 37.46881 -13.7668)
		(stroke
			(width 0.06985)
			(type default)
		)
		(layer "B.Cu")
	)
	(gr_line
		(start 37.46881 -12.2428)
		(end 37.605462 -12.106148)
		(stroke
			(width 0.06985)
			(type default)
		)
		(layer "B.Cu")
	)
	(gr_line
		(start 38.082728 -30.013148)
		(end 38.27018 -30.2006)
		(stroke
			(width 0.06985)
			(type default)
		)
		(layer "B.Cu")
	)
	(gr_line
		(start 38.082728 -29.524452)
		(end 38.27018 -29.337)
		(stroke
			(width 0.06985)
			(type default)
		)
		(layer "B.Cu")
	)
	(gr_line
		(start 38.094158 -12.106148)
		(end 38.23081 -12.2428)
		(stroke
			(width 0.06985)
			(type default)
		)
		(layer "B.Cu")
	)
	(gr_line
		(start 38.094158 -8.702802)
		(end 38.349936 -8.447024)
		(stroke
			(width 0.06985)
			(type default)
		)
		(layer "B.Cu")
	)
	(gr_line
		(start 38.1508 -23.495)
		(end 38.287452 -23.358348)
		(stroke
			(width 0.06985)
			(type default)
		)
		(layer "B.Cu")
	)
	(gr_line
		(start 38.1508 -22.733)
		(end 38.287452 -22.869652)
		(stroke
			(width 0.06985)
			(type default)
		)
		(layer "B.Cu")
	)
	(gr_line
		(start 38.23081 -13.7668)
		(end 38.28161 -13.8176)
		(stroke
			(width 0.06985)
			(type default)
		)
		(layer "B.Cu")
	)
	(gr_line
		(start 38.23081 -13.1572)
		(end 38.23081 -13.7668)
		(stroke
			(width 0.06985)
			(type default)
		)
		(layer "B.Cu")
	)
	(gr_line
		(start 38.349936 -5.814568)
		(end 38.349936 -8.447024)
		(stroke
			(width 0.06985)
			(type default)
		)
		(layer "B.Cu")
	)
	(gr_line
		(start 38.60927 -33.43021)
		(end 38.70071 -33.52165)
		(stroke
			(width 0.06985)
			(type default)
		)
		(layer "B.Cu")
	)
	(gr_line
		(start 38.610794 -32.943292)
		(end 38.89121 -32.943292)
		(stroke
			(width 0.06985)
			(type default)
		)
		(layer "B.Cu")
	)
	(gr_line
		(start 38.89121 -32.943292)
		(end 39.187628 -33.23971)
		(stroke
			(width 0.06985)
			(type default)
		)
		(layer "B.Cu")
	)
	(gr_line
		(start 39.187628 -33.23971)
		(end 39.187628 -33.520126)
		(stroke
			(width 0.06985)
			(type default)
		)
		(layer "B.Cu")
	)
	(gr_line
		(start 39.44366 -12.34694)
		(end 39.678102 -12.581382)
		(stroke
			(width 0.06985)
			(type default)
		)
		(layer "B.Cu")
	)
	(gr_line
		(start 39.485824 -34.306764)
		(end 39.577264 -34.398204)
		(stroke
			(width 0.06985)
			(type default)
		)
		(layer "B.Cu")
	)
	(gr_line
		(start 39.487348 -33.819846)
		(end 39.767764 -33.819846)
		(stroke
			(width 0.06985)
			(type default)
		)
		(layer "B.Cu")
	)
	(gr_line
		(start 39.767764 -33.819846)
		(end 40.064182 -34.11601)
		(stroke
			(width 0.06985)
			(type default)
		)
		(layer "B.Cu")
	)
	(gr_line
		(start 39.8018 -14.605)
		(end 39.878 -14.6812)
		(stroke
			(width 0.06985)
			(type default)
		)
		(layer "B.Cu")
	)
	(gr_line
		(start 39.8018 -14.605)
		(end 40.014652 -14.392148)
		(stroke
			(width 0.06985)
			(type default)
		)
		(layer "B.Cu")
	)
	(gr_line
		(start 39.878 -16.3322)
		(end 40.014652 -16.468852)
		(stroke
			(width 0.06985)
			(type default)
		)
		(layer "B.Cu")
	)
	(gr_line
		(start 39.878 -14.6812)
		(end 39.878 -15.4686)
		(stroke
			(width 0.06985)
			(type default)
		)
		(layer "B.Cu")
	)
	(gr_line
		(start 40.064182 -34.11601)
		(end 40.064182 -34.39668)
		(stroke
			(width 0.06985)
			(type default)
		)
		(layer "B.Cu")
	)
	(gr_line
		(start 40.166798 -12.581382)
		(end 40.40124 -12.34694)
		(stroke
			(width 0.06985)
			(type default)
		)
		(layer "B.Cu")
	)
	(gr_line
		(start 40.362124 -35.183064)
		(end 40.453564 -35.274504)
		(stroke
			(width 0.06985)
			(type default)
		)
		(layer "B.Cu")
	)
	(gr_line
		(start 40.363648 -34.696146)
		(end 40.644318 -34.696146)
		(stroke
			(width 0.06985)
			(type default)
		)
		(layer "B.Cu")
	)
	(gr_line
		(start 40.503348 -16.468852)
		(end 40.64 -16.3322)
		(stroke
			(width 0.06985)
			(type default)
		)
		(layer "B.Cu")
	)
	(gr_line
		(start 40.503348 -14.392148)
		(end 40.7162 -14.605)
		(stroke
			(width 0.06985)
			(type default)
		)
		(layer "B.Cu")
	)
	(gr_line
		(start 40.64 -14.6812)
		(end 40.64 -15.4686)
		(stroke
			(width 0.06985)
			(type default)
		)
		(layer "B.Cu")
	)
	(gr_line
		(start 40.64 -14.6812)
		(end 40.7162 -14.605)
		(stroke
			(width 0.06985)
			(type default)
		)
		(layer "B.Cu")
	)
	(gr_line
		(start 40.644318 -34.696146)
		(end 40.940482 -34.992564)
		(stroke
			(width 0.06985)
			(type default)
		)
		(layer "B.Cu")
	)
	(gr_line
		(start 40.940482 -34.992564)
		(end 40.940482 -35.27298)
		(stroke
			(width 0.06985)
			(type default)
		)
		(layer "B.Cu")
	)
	(gr_line
		(start 41.34993 -8.447278)
		(end 41.605454 -8.702802)
		(stroke
			(width 0.06985)
			(type default)
		)
		(layer "B.Cu")
	)
	(gr_line
		(start 41.34993 -5.814568)
		(end 41.34993 -8.447278)
		(stroke
			(width 0.06985)
			(type default)
		)
		(layer "B.Cu")
	)
	(gr_line
		(start 41.418002 -13.8176)
		(end 41.468802 -13.7668)
		(stroke
			(width 0.06985)
			(type default)
		)
		(layer "B.Cu")
	)
	(gr_line
		(start 41.468802 -13.1572)
		(end 41.468802 -13.7668)
		(stroke
			(width 0.06985)
			(type default)
		)
		(layer "B.Cu")
	)
	(gr_line
		(start 41.468802 -12.2428)
		(end 41.605454 -12.106148)
		(stroke
			(width 0.06985)
			(type default)
		)
		(layer "B.Cu")
	)
	(gr_line
		(start 41.51757 -18.02003)
		(end 41.51757 -18.6563)
		(stroke
			(width 0.06985)
			(type default)
		)
		(layer "B.Cu")
	)
	(gr_line
		(start 41.51757 -18.02003)
		(end 41.525952 -18.011648)
		(stroke
			(width 0.06985)
			(type default)
		)
		(layer "B.Cu")
	)
	(gr_line
		(start 41.8592 -28.7528)
		(end 41.8846 -28.7274)
		(stroke
			(width 0.06985)
			(type default)
		)
		(layer "B.Cu")
	)
	(gr_line
		(start 41.8592 -28.7528)
		(end 42.021252 -28.914852)
		(stroke
			(width 0.06985)
			(type default)
		)
		(layer "B.Cu")
	)
	(gr_line
		(start 41.8846 -27.9654)
		(end 41.8846 -28.7274)
		(stroke
			(width 0.06985)
			(type default)
		)
		(layer "B.Cu")
	)
	(gr_line
		(start 41.8846 -27.1018)
		(end 42.01795 -26.96845)
		(stroke
			(width 0.06985)
			(type default)
		)
		(layer "B.Cu")
	)
	(gr_line
		(start 42.014648 -18.011648)
		(end 42.01795 -18.01495)
		(stroke
			(width 0.06985)
			(type default)
		)
		(layer "B.Cu")
	)
	(gr_line
		(start 42.01795 -25.8445)
		(end 42.01795 -26.96845)
		(stroke
			(width 0.06985)
			(type default)
		)
		(layer "B.Cu")
	)
	(gr_line
		(start 42.01795 -18.01495)
		(end 42.01795 -18.6563)
		(stroke
			(width 0.06985)
			(type default)
		)
		(layer "B.Cu")
	)
	(gr_line
		(start 42.09415 -31.32963)
		(end 42.09415 -31.45917)
		(stroke
			(width 0.06985)
			(type default)
		)
		(layer "B.Cu")
	)
	(gr_line
		(start 42.09415 -30.09011)
		(end 42.09415 -30.21965)
		(stroke
			(width 0.06985)
			(type default)
		)
		(layer "B.Cu")
	)
	(gr_line
		(start 42.09415 -12.106148)
		(end 42.230802 -12.2428)
		(stroke
			(width 0.06985)
			(type default)
		)
		(layer "B.Cu")
	)
	(gr_line
		(start 42.09415 -8.702802)
		(end 42.349928 -8.447024)
		(stroke
			(width 0.06985)
			(type default)
		)
		(layer "B.Cu")
	)
	(gr_line
		(start 42.230802 -13.7668)
		(end 42.281602 -13.8176)
		(stroke
			(width 0.06985)
			(type default)
		)
		(layer "B.Cu")
	)
	(gr_line
		(start 42.230802 -13.1572)
		(end 42.230802 -13.7668)
		(stroke
			(width 0.06985)
			(type default)
		)
		(layer "B.Cu")
	)
	(gr_line
		(start 42.349928 -5.814568)
		(end 42.349928 -8.447024)
		(stroke
			(width 0.06985)
			(type default)
		)
		(layer "B.Cu")
	)
	(gr_line
		(start 42.43959 -31.80207)
		(end 42.63771 -31.60395)
		(stroke
			(width 0.06985)
			(type default)
		)
		(layer "B.Cu")
	)
	(gr_line
		(start 42.43959 -30.98673)
		(end 42.63771 -31.18485)
		(stroke
			(width 0.06985)
			(type default)
		)
		(layer "B.Cu")
	)
	(gr_line
		(start 42.43959 -30.56255)
		(end 42.63771 -30.36443)
		(stroke
			(width 0.06985)
			(type default)
		)
		(layer "B.Cu")
	)
	(gr_line
		(start 42.43959 -29.74721)
		(end 42.63771 -29.94533)
		(stroke
			(width 0.06985)
			(type default)
		)
		(layer "B.Cu")
	)
	(gr_line
		(start 42.45356 -44.15536)
		(end 42.688002 -44.389802)
		(stroke
			(width 0.06985)
			(type default)
		)
		(layer "B.Cu")
	)
	(gr_line
		(start 42.509948 -28.914852)
		(end 42.672 -28.7528)
		(stroke
			(width 0.06985)
			(type default)
		)
		(layer "B.Cu")
	)
	(gr_line
		(start 42.51833 -26.97353)
		(end 42.6466 -27.1018)
		(stroke
			(width 0.06985)
			(type default)
		)
		(layer "B.Cu")
	)
	(gr_line
		(start 42.51833 -25.8445)
		(end 42.51833 -26.97353)
		(stroke
			(width 0.06985)
			(type default)
		)
		(layer "B.Cu")
	)
	(gr_line
		(start 42.63771 -31.18485)
		(end 42.63771 -31.60395)
		(stroke
			(width 0.06985)
			(type default)
		)
		(layer "B.Cu")
	)
	(gr_line
		(start 42.63771 -29.94533)
		(end 42.63771 -30.36443)
		(stroke
			(width 0.06985)
			(type default)
		)
		(layer "B.Cu")
	)
	(gr_line
		(start 42.6466 -28.7274)
		(end 42.672 -28.7528)
		(stroke
			(width 0.06985)
			(type default)
		)
		(layer "B.Cu")
	)
	(gr_line
		(start 42.6466 -27.9654)
		(end 42.6466 -28.7274)
		(stroke
			(width 0.06985)
			(type default)
		)
		(layer "B.Cu")
	)
	(gr_line
		(start 42.657268 -35.77336)
		(end 42.855388 -35.57524)
		(stroke
			(width 0.06985)
			(type default)
		)
		(layer "B.Cu")
	)
	(gr_line
		(start 42.855388 -35.57524)
		(end 43.274488 -35.57524)
		(stroke
			(width 0.06985)
			(type default)
		)
		(layer "B.Cu")
	)
	(gr_line
		(start 43.000168 -36.1188)
		(end 43.129708 -36.1188)
		(stroke
			(width 0.06985)
			(type default)
		)
		(layer "B.Cu")
	)
	(gr_line
		(start 43.176698 -44.389802)
		(end 43.41114 -44.15536)
		(stroke
			(width 0.06985)
			(type default)
		)
		(layer "B.Cu")
	)
	(gr_line
		(start 43.25366 -12.5984)
		(end 43.488102 -12.832842)
		(stroke
			(width 0.06985)
			(type default)
		)
		(layer "B.Cu")
	)
	(gr_line
		(start 43.274488 -35.57524)
		(end 43.472608 -35.77336)
		(stroke
			(width 0.06985)
			(type default)
		)
		(layer "B.Cu")
	)
	(gr_line
		(start 43.3578 -15.5702)
		(end 43.3832 -15.5956)
		(stroke
			(width 0.06985)
			(type default)
		)
		(layer "B.Cu")
	)
	(gr_line
		(start 43.3578 -15.5702)
		(end 43.519852 -15.408148)
		(stroke
			(width 0.06985)
			(type default)
		)
		(layer "B.Cu")
	)
	(gr_line
		(start 43.3832 -17.2212)
		(end 43.519852 -17.357852)
		(stroke
			(width 0.06985)
			(type default)
		)
		(layer "B.Cu")
	)
	(gr_line
		(start 43.3832 -15.5956)
		(end 43.3832 -16.3576)
		(stroke
			(width 0.06985)
			(type default)
		)
		(layer "B.Cu")
	)
	(gr_line
		(start 43.51909 -18.03654)
		(end 43.51909 -18.6563)
		(stroke
			(width 0.06985)
			(type default)
		)
		(layer "B.Cu")
	)
	(gr_line
		(start 43.51909 -18.03654)
		(end 43.524932 -18.030698)
		(stroke
			(width 0.06985)
			(type default)
		)
		(layer "B.Cu")
	)
	(gr_line
		(start 43.976798 -12.832842)
		(end 44.21124 -12.5984)
		(stroke
			(width 0.06985)
			(type default)
		)
		(layer "B.Cu")
	)
	(gr_line
		(start 44.008548 -17.357852)
		(end 44.1452 -17.2212)
		(stroke
			(width 0.06985)
			(type default)
		)
		(layer "B.Cu")
	)
	(gr_line
		(start 44.008548 -15.408148)
		(end 44.1706 -15.5702)
		(stroke
			(width 0.06985)
			(type default)
		)
		(layer "B.Cu")
	)
	(gr_line
		(start 44.013628 -18.030698)
		(end 44.01947 -18.03654)
		(stroke
			(width 0.06985)
			(type default)
		)
		(layer "B.Cu")
	)
	(gr_line
		(start 44.01947 -18.03654)
		(end 44.01947 -18.6563)
		(stroke
			(width 0.06985)
			(type default)
		)
		(layer "B.Cu")
	)
	(gr_line
		(start 44.1452 -15.5956)
		(end 44.1452 -16.3576)
		(stroke
			(width 0.06985)
			(type default)
		)
		(layer "B.Cu")
	)
	(gr_line
		(start 44.1452 -15.5956)
		(end 44.1706 -15.5702)
		(stroke
			(width 0.06985)
			(type default)
		)
		(layer "B.Cu")
	)
	(gr_line
		(start 44.458636 -45.711364)
		(end 44.458636 -46.087792)
		(stroke
			(width 0.06985)
			(type default)
		)
		(layer "B.Cu")
	)
	(gr_line
		(start 44.858686 -45.748448)
		(end 44.858686 -46.087792)
		(stroke
			(width 0.06985)
			(type default)
		)
		(layer "B.Cu")
	)
	(gr_line
		(start 44.998386 -43.9166)
		(end 45.244004 -44.162218)
		(stroke
			(width 0.06985)
			(type default)
		)
		(layer "B.Cu")
	)
	(gr_line
		(start 45.349922 -8.447278)
		(end 45.605446 -8.702802)
		(stroke
			(width 0.06985)
			(type default)
		)
		(layer "B.Cu")
	)
	(gr_line
		(start 45.349922 -5.814568)
		(end 45.349922 -8.447278)
		(stroke
			(width 0.06985)
			(type default)
		)
		(layer "B.Cu")
	)
	(gr_line
		(start 45.466 -13.1572)
		(end 45.466 -13.8176)
		(stroke
			(width 0.06985)
			(type default)
		)
		(layer "B.Cu")
	)
	(gr_line
		(start 45.466 -12.2428)
		(end 45.602652 -12.106148)
		(stroke
			(width 0.06985)
			(type default)
		)
		(layer "B.Cu")
	)
	(gr_line
		(start 45.52061 -18.05559)
		(end 45.52061 -18.6563)
		(stroke
			(width 0.06985)
			(type default)
		)
		(layer "B.Cu")
	)
	(gr_line
		(start 45.658786 -45.664628)
		(end 45.658786 -46.087792)
		(stroke
			(width 0.06985)
			(type default)
		)
		(layer "B.Cu")
	)
	(gr_line
		(start 45.732446 -44.162218)
		(end 45.956474 -43.93819)
		(stroke
			(width 0.06985)
			(type default)
		)
		(layer "B.Cu")
	)
	(gr_line
		(start 45.999146 -18.065496)
		(end 46.02099 -18.08734)
		(stroke
			(width 0.06985)
			(type default)
		)
		(layer "B.Cu")
	)
	(gr_line
		(start 46.02099 -18.08734)
		(end 46.02099 -18.6563)
		(stroke
			(width 0.06985)
			(type default)
		)
		(layer "B.Cu")
	)
	(gr_line
		(start 46.053756 -45.371258)
		(end 46.058582 -45.376084)
		(stroke
			(width 0.06985)
			(type default)
		)
		(layer "B.Cu")
	)
	(gr_line
		(start 46.058582 -51.70678)
		(end 46.058582 -52.400962)
		(stroke
			(width 0.06985)
			(type default)
		)
		(layer "B.Cu")
	)
	(gr_line
		(start 46.058582 -45.376084)
		(end 46.058582 -46.087792)
		(stroke
			(width 0.06985)
			(type default)
		)
		(layer "B.Cu")
	)
	(gr_line
		(start 46.091348 -12.106148)
		(end 46.228 -12.2428)
		(stroke
			(width 0.06985)
			(type default)
		)
		(layer "B.Cu")
	)
	(gr_line
		(start 46.094142 -8.702802)
		(end 46.34992 -8.447024)
		(stroke
			(width 0.06985)
			(type default)
		)
		(layer "B.Cu")
	)
	(gr_line
		(start 46.1772 -13.8176)
		(end 46.228 -13.7668)
		(stroke
			(width 0.06985)
			(type default)
		)
		(layer "B.Cu")
	)
	(gr_line
		(start 46.228 -13.1572)
		(end 46.228 -13.7668)
		(stroke
			(width 0.06985)
			(type default)
		)
		(layer "B.Cu")
	)
	(gr_line
		(start 46.34992 -5.814568)
		(end 46.34992 -8.447024)
		(stroke
			(width 0.06985)
			(type default)
		)
		(layer "B.Cu")
	)
	(gr_line
		(start 46.458632 -51.70678)
		(end 46.458632 -52.31257)
		(stroke
			(width 0.06985)
			(type default)
		)
		(layer "B.Cu")
	)
	(gr_line
		(start 46.717204 -32.972756)
		(end 46.915324 -32.774636)
		(stroke
			(width 0.06985)
			(type default)
		)
		(layer "B.Cu")
	)
	(gr_line
		(start 46.915324 -32.774636)
		(end 47.334424 -32.774636)
		(stroke
			(width 0.06985)
			(type default)
		)
		(layer "B.Cu")
	)
	(gr_line
		(start 47.060104 -33.318196)
		(end 47.189644 -33.318196)
		(stroke
			(width 0.06985)
			(type default)
		)
		(layer "B.Cu")
	)
	(gr_line
		(start 47.258732 -51.70678)
		(end 47.258732 -52.262532)
		(stroke
			(width 0.06985)
			(type default)
		)
		(layer "B.Cu")
	)
	(gr_line
		(start 47.258732 -45.57776)
		(end 47.258732 -46.087792)
		(stroke
			(width 0.06985)
			(type default)
		)
		(layer "B.Cu")
	)
	(gr_line
		(start 47.2948 -14.605)
		(end 47.371 -14.6812)
		(stroke
			(width 0.06985)
			(type default)
		)
		(layer "B.Cu")
	)
	(gr_line
		(start 47.2948 -14.605)
		(end 47.507652 -14.392148)
		(stroke
			(width 0.06985)
			(type default)
		)
		(layer "B.Cu")
	)
	(gr_line
		(start 47.334424 -32.774636)
		(end 47.532544 -32.972756)
		(stroke
			(width 0.06985)
			(type default)
		)
		(layer "B.Cu")
	)
	(gr_line
		(start 47.371 -16.3322)
		(end 47.507652 -16.468852)
		(stroke
			(width 0.06985)
			(type default)
		)
		(layer "B.Cu")
	)
	(gr_line
		(start 47.371 -14.6812)
		(end 47.371 -15.4686)
		(stroke
			(width 0.06985)
			(type default)
		)
		(layer "B.Cu")
	)
	(gr_line
		(start 47.46371 -13.7922)
		(end 47.579534 -13.908024)
		(stroke
			(width 0.06985)
			(type default)
		)
		(layer "B.Cu")
	)
	(gr_line
		(start 47.52213 -19.27733)
		(end 47.533052 -19.288252)
		(stroke
			(width 0.06985)
			(type default)
		)
		(layer "B.Cu")
	)
	(gr_line
		(start 47.52213 -18.6563)
		(end 47.52213 -19.27733)
		(stroke
			(width 0.06985)
			(type default)
		)
		(layer "B.Cu")
	)
	(gr_line
		(start 47.658782 -51.70678)
		(end 47.658782 -52.17414)
		(stroke
			(width 0.06985)
			(type default)
		)
		(layer "B.Cu")
	)
	(gr_line
		(start 47.658782 -45.666152)
		(end 47.658782 -46.087792)
		(stroke
			(width 0.06985)
			(type default)
		)
		(layer "B.Cu")
	)
	(gr_line
		(start 47.956724 -32.972756)
		(end 48.154844 -32.774636)
		(stroke
			(width 0.06985)
			(type default)
		)
		(layer "B.Cu")
	)
	(gr_line
		(start 47.996348 -16.468852)
		(end 48.133 -16.3322)
		(stroke
			(width 0.06985)
			(type default)
		)
		(layer "B.Cu")
	)
	(gr_line
		(start 47.996348 -14.392148)
		(end 48.2092 -14.605)
		(stroke
			(width 0.06985)
			(type default)
		)
		(layer "B.Cu")
	)
	(gr_line
		(start 48.021748 -19.288252)
		(end 48.02251 -19.28749)
		(stroke
			(width 0.06985)
			(type default)
		)
		(layer "B.Cu")
	)
	(gr_line
		(start 48.02251 -18.6563)
		(end 48.02251 -19.28749)
		(stroke
			(width 0.06985)
			(type default)
		)
		(layer "B.Cu")
	)
	(gr_line
		(start 48.0568 -44.1452)
		(end 48.0568 -44.19346)
		(stroke
			(width 0.06985)
			(type default)
		)
		(layer "B.Cu")
	)
	(gr_line
		(start 48.067976 -13.908024)
		(end 48.1838 -13.7922)
		(stroke
			(width 0.06985)
			(type default)
		)
		(layer "B.Cu")
	)
	(gr_line
		(start 48.133 -14.6812)
		(end 48.133 -15.4686)
		(stroke
			(width 0.06985)
			(type default)
		)
		(layer "B.Cu")
	)
	(gr_line
		(start 48.133 -14.6812)
		(end 48.2092 -14.605)
		(stroke
			(width 0.06985)
			(type default)
		)
		(layer "B.Cu")
	)
	(gr_line
		(start 48.154844 -32.774636)
		(end 48.573944 -32.774636)
		(stroke
			(width 0.06985)
			(type default)
		)
		(layer "B.Cu")
	)
	(gr_line
		(start 48.2473 -43.8023)
		(end 48.2473 -43.85056)
		(stroke
			(width 0.06985)
			(type default)
		)
		(layer "B.Cu")
	)
	(gr_line
		(start 48.299624 -33.318196)
		(end 48.429164 -33.318196)
		(stroke
			(width 0.06985)
			(type default)
		)
		(layer "B.Cu")
	)
	(gr_line
		(start 48.573944 -32.774636)
		(end 48.772064 -32.972756)
		(stroke
			(width 0.06985)
			(type default)
		)
		(layer "B.Cu")
	)
	(gr_line
		(start 48.668178 -50.697384)
		(end 49.136046 -50.697384)
		(stroke
			(width 0.06985)
			(type default)
		)
		(layer "B.Cu")
	)
	(gr_line
		(start 48.668178 -50.297334)
		(end 49.224438 -50.297334)
		(stroke
			(width 0.06985)
			(type default)
		)
		(layer "B.Cu")
	)
	(gr_line
		(start 48.668178 -49.897284)
		(end 49.379632 -49.897284)
		(stroke
			(width 0.06985)
			(type default)
		)
		(layer "B.Cu")
	)
	(gr_line
		(start 48.668178 -49.497234)
		(end 49.379886 -49.497234)
		(stroke
			(width 0.06985)
			(type default)
		)
		(layer "B.Cu")
	)
	(gr_line
		(start 48.668178 -47.097188)
		(end 49.295812 -47.097188)
		(stroke
			(width 0.06985)
			(type default)
		)
		(layer "B.Cu")
	)
	(gr_line
		(start 48.668178 -46.697392)
		(end 49.207166 -46.697392)
		(stroke
			(width 0.06985)
			(type default)
		)
		(layer "B.Cu")
	)
	(gr_line
		(start 49.29505 -20.41144)
		(end 49.529492 -20.176998)
		(stroke
			(width 0.06985)
			(type default)
		)
		(layer "B.Cu")
	)
	(gr_line
		(start 49.349914 -8.447278)
		(end 49.605438 -8.702802)
		(stroke
			(width 0.06985)
			(type default)
		)
		(layer "B.Cu")
	)
	(gr_line
		(start 49.349914 -5.814568)
		(end 49.349914 -8.447278)
		(stroke
			(width 0.06985)
			(type default)
		)
		(layer "B.Cu")
	)
	(gr_line
		(start 49.38903 -10.26033)
		(end 49.605438 -10.043922)
		(stroke
			(width 0.06985)
			(type default)
		)
		(layer "B.Cu")
	)
	(gr_line
		(start 49.434242 -38.26764)
		(end 49.434242 -38.421818)
		(stroke
			(width 0.06985)
			(type default)
		)
		(layer "B.Cu")
	)
	(gr_line
		(start 49.434242 -38.029642)
		(end 49.434242 -38.2651)
		(stroke
			(width 0.06985)
			(type default)
		)
		(layer "B.Cu")
	)
	(gr_line
		(start 49.52365 -19.29765)
		(end 49.539652 -19.313652)
		(stroke
			(width 0.06985)
			(type default)
		)
		(layer "B.Cu")
	)
	(gr_line
		(start 49.52365 -18.6563)
		(end 49.52365 -19.29765)
		(stroke
			(width 0.06985)
			(type default)
		)
		(layer "B.Cu")
	)
	(gr_line
		(start 49.73066 -38.61054)
		(end 49.777142 -38.61054)
		(stroke
			(width 0.06985)
			(type default)
		)
		(layer "B.Cu")
	)
	(gr_line
		(start 49.779682 -38.61054)
		(end 50.07356 -38.61054)
		(stroke
			(width 0.06985)
			(type default)
		)
		(layer "B.Cu")
	)
	(gr_line
		(start 50.018188 -20.176998)
		(end 50.25263 -20.41144)
		(stroke
			(width 0.06985)
			(type default)
		)
		(layer "B.Cu")
	)
	(gr_line
		(start 50.02403 -18.6563)
		(end 50.02403 -19.31797)
		(stroke
			(width 0.06985)
			(type default)
		)
		(layer "B.Cu")
	)
	(gr_line
		(start 50.094134 -10.043922)
		(end 50.310542 -10.26033)
		(stroke
			(width 0.06985)
			(type default)
		)
		(layer "B.Cu")
	)
	(gr_line
		(start 50.094134 -8.702802)
		(end 50.349912 -8.447024)
		(stroke
			(width 0.06985)
			(type default)
		)
		(layer "B.Cu")
	)
	(gr_line
		(start 50.349912 -5.814568)
		(end 50.349912 -8.447024)
		(stroke
			(width 0.06985)
			(type default)
		)
		(layer "B.Cu")
	)
	(gr_line
		(start 50.464212 -48.319182)
		(end 50.645568 -48.500538)
		(stroke
			(width 0.06985)
			(type default)
		)
		(layer "B.Cu")
	)
	(gr_line
		(start 50.464212 -47.83074)
		(end 50.658014 -47.636938)
		(stroke
			(width 0.06985)
			(type default)
		)
		(layer "B.Cu")
	)
	(gr_line
		(start 51.282346 -34.0868)
		(end 51.480212 -34.284666)
		(stroke
			(width 0.06985)
			(type default)
		)
		(layer "B.Cu")
	)
	(gr_line
		(start 51.968654 -34.284666)
		(end 52.16652 -34.0868)
		(stroke
			(width 0.06985)
			(type default)
		)
		(layer "B.Cu")
	)
	(gr_line
		(start 52.52466 -35.31616)
		(end 52.756054 -35.547554)
		(stroke
			(width 0.06985)
			(type default)
		)
		(layer "B.Cu")
	)
	(gr_line
		(start 52.931314 -29.606748)
		(end 53.151786 -29.82722)
		(stroke
			(width 0.06985)
			(type default)
		)
		(layer "B.Cu")
	)
	(gr_line
		(start 52.931314 -29.118306)
		(end 53.151786 -28.897834)
		(stroke
			(width 0.06985)
			(type default)
		)
		(layer "B.Cu")
	)
	(gr_line
		(start 53.244496 -35.547554)
		(end 53.478938 -35.313112)
		(stroke
			(width 0.06985)
			(type default)
		)
		(layer "B.Cu")
	)
	(gr_line
		(start 58.185558 -37.31514)
		(end 58.185558 -37.32784)
		(stroke
			(width 0.06985)
			(type default)
		)
		(layer "B.Cu")
	)
	(gr_line
		(start 58.340498 -36.97224)
		(end 58.340498 -36.98494)
		(stroke
			(width 0.06985)
			(type default)
		)
		(layer "B.Cu")
	)
	(gr_line
		(start 59.423808 -36.102798)
		(end 59.65825 -36.33724)
		(stroke
			(width 0.06985)
			(type default)
		)
		(layer "B.Cu")
	)
	(gr_line
		(start 59.423808 -35.614102)
		(end 59.65825 -35.37966)
		(stroke
			(width 0.06985)
			(type default)
		)
		(layer "B.Cu")
	)
	(gr_line
		(start 60.77585 -46.519846)
		(end 60.990226 -46.734222)
		(stroke
			(width 0.06985)
			(type default)
		)
		(layer "B.Cu")
	)
	(gr_line
		(start 60.77585 -46.03115)
		(end 60.9346 -45.8724)
		(stroke
			(width 0.06985)
			(type default)
		)
		(layer "B.Cu")
	)
	(gr_line
		(start 61.34989 -8.447024)
		(end 61.605668 -8.702802)
		(stroke
			(width 0.06985)
			(type default)
		)
		(layer "B.Cu")
	)
	(gr_line
		(start 61.34989 -5.814568)
		(end 61.34989 -8.447024)
		(stroke
			(width 0.06985)
			(type default)
		)
		(layer "B.Cu")
	)
	(gr_line
		(start 61.40831 -10.250678)
		(end 61.623702 -10.035286)
		(stroke
			(width 0.06985)
			(type default)
		)
		(layer "B.Cu")
	)
	(gr_line
		(start 62.094364 -8.702802)
		(end 62.349888 -8.447278)
		(stroke
			(width 0.06985)
			(type default)
		)
		(layer "B.Cu")
	)
	(gr_line
		(start 62.112398 -10.035286)
		(end 62.32779 -10.250678)
		(stroke
			(width 0.06985)
			(type default)
		)
		(layer "B.Cu")
	)
	(gr_line
		(start 62.349888 -5.814568)
		(end 62.349888 -8.447278)
		(stroke
			(width 0.06985)
			(type default)
		)
		(layer "B.Cu")
	)
	(gr_line
		(start 63.946532 -31.500064)
		(end 64.7446 -31.500064)
		(stroke
			(width 0.06985)
			(type default)
		)
		(layer "B.Cu")
	)
	(gr_line
		(start 63.946532 -30.699964)
		(end 64.7446 -30.699964)
		(stroke
			(width 0.06985)
			(type default)
		)
		(layer "B.Cu")
	)
	(gr_line
		(start 63.946532 -28.299918)
		(end 64.6684 -28.299918)
		(stroke
			(width 0.06985)
			(type default)
		)
		(layer "B.Cu")
	)
	(gr_line
		(start 63.946532 -27.500072)
		(end 64.668654 -27.500072)
		(stroke
			(width 0.06985)
			(type default)
		)
		(layer "B.Cu")
	)
	(gr_line
		(start 64.6684 -28.299918)
		(end 64.824102 -28.144216)
		(stroke
			(width 0.06985)
			(type default)
		)
		(layer "B.Cu")
	)
	(gr_line
		(start 64.668654 -27.500072)
		(end 64.824102 -27.65552)
		(stroke
			(width 0.06985)
			(type default)
		)
		(layer "B.Cu")
	)
	(gr_line
		(start 64.7446 -31.500064)
		(end 64.900302 -31.344362)
		(stroke
			(width 0.06985)
			(type default)
		)
		(layer "B.Cu")
	)
	(gr_line
		(start 64.7446 -30.699964)
		(end 64.900302 -30.855666)
		(stroke
			(width 0.06985)
			(type default)
		)
		(layer "B.Cu")
	)
	(gr_line
		(start 65.349882 -8.447024)
		(end 65.60566 -8.702802)
		(stroke
			(width 0.06985)
			(type default)
		)
		(layer "B.Cu")
	)
	(gr_line
		(start 65.349882 -5.814568)
		(end 65.349882 -8.447024)
		(stroke
			(width 0.06985)
			(type default)
		)
		(layer "B.Cu")
	)
	(gr_line
		(start 65.786 -14.0462)
		(end 65.786 -14.6812)
		(stroke
			(width 0.06985)
			(type default)
		)
		(layer "B.Cu")
	)
	(gr_line
		(start 65.786 -13.1318)
		(end 65.922652 -12.995148)
		(stroke
			(width 0.06985)
			(type default)
		)
		(layer "B.Cu")
	)
	(gr_line
		(start 66.094356 -8.702802)
		(end 66.34988 -8.447278)
		(stroke
			(width 0.06985)
			(type default)
		)
		(layer "B.Cu")
	)
	(gr_line
		(start 66.34988 -5.814568)
		(end 66.34988 -8.447278)
		(stroke
			(width 0.06985)
			(type default)
		)
		(layer "B.Cu")
	)
	(gr_line
		(start 66.411348 -12.995148)
		(end 66.548 -13.1318)
		(stroke
			(width 0.06985)
			(type default)
		)
		(layer "B.Cu")
	)
	(gr_line
		(start 66.548 -14.0462)
		(end 66.548 -14.6812)
		(stroke
			(width 0.06985)
			(type default)
		)
		(layer "B.Cu")
	)
	(gr_line
		(start 66.589148 -30.394148)
		(end 66.7258 -30.5308)
		(stroke
			(width 0.06985)
			(type default)
		)
		(layer "B.Cu")
	)
	(gr_line
		(start 66.589148 -29.905452)
		(end 66.7258 -29.7688)
		(stroke
			(width 0.06985)
			(type default)
		)
		(layer "B.Cu")
	)
	(gr_line
		(start 66.589148 -28.184348)
		(end 66.7258 -28.321)
		(stroke
			(width 0.06985)
			(type default)
		)
		(layer "B.Cu")
	)
	(gr_line
		(start 66.589148 -27.695652)
		(end 66.7258 -27.559)
		(stroke
			(width 0.06985)
			(type default)
		)
		(layer "B.Cu")
	)
	(gr_line
		(start 67.6402 -30.5308)
		(end 67.776852 -30.394148)
		(stroke
			(width 0.06985)
			(type default)
		)
		(layer "B.Cu")
	)
	(gr_line
		(start 67.6402 -29.7688)
		(end 67.776852 -29.905452)
		(stroke
			(width 0.06985)
			(type default)
		)
		(layer "B.Cu")
	)
	(gr_line
		(start 67.6402 -28.321)
		(end 67.776852 -28.184348)
		(stroke
			(width 0.06985)
			(type default)
		)
		(layer "B.Cu")
	)
	(gr_line
		(start 67.6402 -27.559)
		(end 67.776852 -27.695652)
		(stroke
			(width 0.06985)
			(type default)
		)
		(layer "B.Cu")
	)
	(gr_line
		(start 68.072 -14.0462)
		(end 68.072 -14.605)
		(stroke
			(width 0.06985)
			(type default)
		)
		(layer "B.Cu")
	)
	(gr_line
		(start 68.072 -13.1318)
		(end 68.208652 -12.995148)
		(stroke
			(width 0.06985)
			(type default)
		)
		(layer "B.Cu")
	)
	(gr_line
		(start 68.697348 -12.995148)
		(end 68.834 -13.1318)
		(stroke
			(width 0.06985)
			(type default)
		)
		(layer "B.Cu")
	)
	(gr_line
		(start 68.834 -14.0462)
		(end 68.834 -14.605)
		(stroke
			(width 0.06985)
			(type default)
		)
		(layer "B.Cu")
	)
	(gr_line
		(start 68.93941 -28.209494)
		(end 69.13499 -28.405074)
		(stroke
			(width 0.06985)
			(type default)
		)
		(layer "B.Cu")
	)
	(gr_line
		(start 68.93941 -27.720798)
		(end 69.1388 -27.521408)
		(stroke
			(width 0.06985)
			(type default)
		)
		(layer "B.Cu")
	)
	(gr_line
		(start 69.349874 -8.447024)
		(end 69.605652 -8.702802)
		(stroke
			(width 0.06985)
			(type default)
		)
		(layer "B.Cu")
	)
	(gr_line
		(start 69.349874 -5.814568)
		(end 69.349874 -8.447024)
		(stroke
			(width 0.06985)
			(type default)
		)
		(layer "B.Cu")
	)
	(gr_line
		(start 70.094348 -8.702802)
		(end 70.349872 -8.447278)
		(stroke
			(width 0.06985)
			(type default)
		)
		(layer "B.Cu")
	)
	(gr_line
		(start 70.349872 -5.814568)
		(end 70.349872 -8.447278)
		(stroke
			(width 0.06985)
			(type default)
		)
		(layer "B.Cu")
	)
	(gr_line
		(start 72.8472 -14.7066)
		(end 72.898 -14.6558)
		(stroke
			(width 0.06985)
			(type default)
		)
		(layer "B.Cu")
	)
	(gr_line
		(start 72.898 -14.0462)
		(end 72.898 -14.6558)
		(stroke
			(width 0.06985)
			(type default)
		)
		(layer "B.Cu")
	)
	(gr_line
		(start 72.898 -13.1318)
		(end 73.034652 -12.995148)
		(stroke
			(width 0.06985)
			(type default)
		)
		(layer "B.Cu")
	)
	(gr_line
		(start 73.349866 -8.447278)
		(end 73.60539 -8.702802)
		(stroke
			(width 0.06985)
			(type default)
		)
		(layer "B.Cu")
	)
	(gr_line
		(start 73.349866 -5.814568)
		(end 73.349866 -8.447278)
		(stroke
			(width 0.06985)
			(type default)
		)
		(layer "B.Cu")
	)
	(gr_line
		(start 73.523348 -12.995148)
		(end 73.66 -13.1318)
		(stroke
			(width 0.06985)
			(type default)
		)
		(layer "B.Cu")
	)
	(gr_line
		(start 73.66 -14.6558)
		(end 73.7108 -14.7066)
		(stroke
			(width 0.06985)
			(type default)
		)
		(layer "B.Cu")
	)
	(gr_line
		(start 73.66 -14.0462)
		(end 73.66 -14.6558)
		(stroke
			(width 0.06985)
			(type default)
		)
		(layer "B.Cu")
	)
	(gr_line
		(start 74.094086 -8.702802)
		(end 74.349864 -8.447024)
		(stroke
			(width 0.06985)
			(type default)
		)
		(layer "B.Cu")
	)
	(gr_line
		(start 74.349864 -5.814568)
		(end 74.349864 -8.447024)
		(stroke
			(width 0.06985)
			(type default)
		)
		(layer "B.Cu")
	)
	(gr_line
		(start 76.89215 -29.464)
		(end 76.918058 -29.489908)
		(stroke
			(width 0.0508)
			(type default)
		)
		(layer "B.Cu")
	)
	(gr_line
		(start 76.89215 -29.4386)
		(end 76.89215 -29.464)
		(stroke
			(width 0.0508)
			(type default)
		)
		(layer "B.Cu")
	)
	(gr_line
		(start 76.919836 -29.491686)
		(end 76.962 -29.53385)
		(stroke
			(width 0.0508)
			(type default)
		)
		(layer "B.Cu")
	)
	(gr_line
		(start 76.962 -30.28442)
		(end 76.962 -30.37586)
		(stroke
			(width 0.0508)
			(type default)
		)
		(layer "B.Cu")
	)
	(gr_line
		(start 77.1652 -29.53385)
		(end 77.207364 -29.491686)
		(stroke
			(width 0.0508)
			(type default)
		)
		(layer "B.Cu")
	)
	(gr_line
		(start 77.16774 -30.57906)
		(end 77.26426 -30.48254)
		(stroke
			(width 0.0508)
			(type default)
		)
		(layer "B.Cu")
	)
	(gr_line
		(start 77.16774 -30.08122)
		(end 77.26426 -30.17774)
		(stroke
			(width 0.0508)
			(type default)
		)
		(layer "B.Cu")
	)
	(gr_line
		(start 77.209142 -29.489908)
		(end 77.23505 -29.464)
		(stroke
			(width 0.0508)
			(type default)
		)
		(layer "B.Cu")
	)
	(gr_line
		(start 77.23505 -29.4386)
		(end 77.23505 -29.464)
		(stroke
			(width 0.0508)
			(type default)
		)
		(layer "B.Cu")
	)
	(gr_line
		(start 77.26426 -30.17774)
		(end 77.26426 -30.48254)
		(stroke
			(width 0.0508)
			(type default)
		)
		(layer "B.Cu")
	)
	(gr_line
		(start 77.349858 -8.447278)
		(end 77.605382 -8.702802)
		(stroke
			(width 0.06985)
			(type default)
		)
		(layer "B.Cu")
	)
	(gr_line
		(start 77.349858 -5.814568)
		(end 77.349858 -8.447278)
		(stroke
			(width 0.06985)
			(type default)
		)
		(layer "B.Cu")
	)
	(gr_line
		(start 77.4192 -14.5796)
		(end 77.47 -14.5288)
		(stroke
			(width 0.06985)
			(type default)
		)
		(layer "B.Cu")
	)
	(gr_line
		(start 77.47 -13.9192)
		(end 77.47 -14.5288)
		(stroke
			(width 0.06985)
			(type default)
		)
		(layer "B.Cu")
	)
	(gr_line
		(start 77.47 -13.0048)
		(end 77.606652 -12.868148)
		(stroke
			(width 0.06985)
			(type default)
		)
		(layer "B.Cu")
	)
	(gr_line
		(start 78.094078 -8.702802)
		(end 78.349856 -8.447024)
		(stroke
			(width 0.06985)
			(type default)
		)
		(layer "B.Cu")
	)
	(gr_line
		(start 78.095348 -12.868148)
		(end 78.232 -13.0048)
		(stroke
			(width 0.06985)
			(type default)
		)
		(layer "B.Cu")
	)
	(gr_line
		(start 78.232 -14.5288)
		(end 78.2828 -14.5796)
		(stroke
			(width 0.06985)
			(type default)
		)
		(layer "B.Cu")
	)
	(gr_line
		(start 78.232 -13.9192)
		(end 78.232 -14.5288)
		(stroke
			(width 0.06985)
			(type default)
		)
		(layer "B.Cu")
	)
	(gr_line
		(start 78.349856 -5.814568)
		(end 78.349856 -8.447024)
		(stroke
			(width 0.06985)
			(type default)
		)
		(layer "B.Cu")
	)
	(gr_line
		(start 80.124554 -31.297626)
		(end 80.404208 -31.297626)
		(stroke
			(width 0.0508)
			(type default)
		)
		(layer "B.Cu")
	)
	(gr_line
		(start 80.2132 -14.5796)
		(end 80.264 -14.5288)
		(stroke
			(width 0.06985)
			(type default)
		)
		(layer "B.Cu")
	)
	(gr_line
		(start 80.264 -13.9192)
		(end 80.264 -14.5288)
		(stroke
			(width 0.06985)
			(type default)
		)
		(layer "B.Cu")
	)
	(gr_line
		(start 80.264 -13.0048)
		(end 80.400652 -12.868148)
		(stroke
			(width 0.06985)
			(type default)
		)
		(layer "B.Cu")
	)
	(gr_line
		(start 80.404208 -31.297626)
		(end 80.491076 -31.384494)
		(stroke
			(width 0.0508)
			(type default)
		)
		(layer "B.Cu")
	)
	(gr_line
		(start 80.492854 -31.386272)
		(end 80.525874 -31.419292)
		(stroke
			(width 0.0508)
			(type default)
		)
		(layer "B.Cu")
	)
	(gr_line
		(start 80.729074 -31.43758)
		(end 80.780382 -31.386272)
		(stroke
			(width 0.0508)
			(type default)
		)
		(layer "B.Cu")
	)
	(gr_line
		(start 80.78216 -31.384494)
		(end 80.867504 -31.29915)
		(stroke
			(width 0.0508)
			(type default)
		)
		(layer "B.Cu")
	)
	(gr_line
		(start 80.867504 -31.29915)
		(end 81.132172 -31.29915)
		(stroke
			(width 0.0508)
			(type default)
		)
		(layer "B.Cu")
	)
	(gr_line
		(start 80.889348 -12.868148)
		(end 81.026 -13.0048)
		(stroke
			(width 0.06985)
			(type default)
		)
		(layer "B.Cu")
	)
	(gr_line
		(start 81.026 -14.5288)
		(end 81.0768 -14.5796)
		(stroke
			(width 0.06985)
			(type default)
		)
		(layer "B.Cu")
	)
	(gr_line
		(start 81.026 -13.9192)
		(end 81.026 -14.5288)
		(stroke
			(width 0.06985)
			(type default)
		)
		(layer "B.Cu")
	)
	(gr_line
		(start 81.34985 -8.447024)
		(end 81.605628 -8.702802)
		(stroke
			(width 0.06985)
			(type default)
		)
		(layer "B.Cu")
	)
	(gr_line
		(start 81.34985 -5.814568)
		(end 81.34985 -8.447024)
		(stroke
			(width 0.06985)
			(type default)
		)
		(layer "B.Cu")
	)
	(gr_line
		(start 82.094324 -8.702802)
		(end 82.349848 -8.447278)
		(stroke
			(width 0.06985)
			(type default)
		)
		(layer "B.Cu")
	)
	(gr_line
		(start 82.296 -13.9446)
		(end 82.483452 -13.757148)
		(stroke
			(width 0.06985)
			(type default)
		)
		(layer "B.Cu")
	)
	(gr_line
		(start 82.349848 -5.814568)
		(end 82.349848 -8.447278)
		(stroke
			(width 0.06985)
			(type default)
		)
		(layer "B.Cu")
	)
	(gr_line
		(start 82.972148 -13.757148)
		(end 83.1596 -13.9446)
		(stroke
			(width 0.06985)
			(type default)
		)
		(layer "B.Cu")
	)
	(gr_line
		(start 89.350088 -8.447278)
		(end 89.605612 -8.702802)
		(stroke
			(width 0.06985)
			(type default)
		)
		(layer "B.Cu")
	)
	(gr_line
		(start 89.350088 -5.814568)
		(end 89.350088 -8.447278)
		(stroke
			(width 0.06985)
			(type default)
		)
		(layer "B.Cu")
	)
	(gr_line
		(start 90.094308 -8.702802)
		(end 90.350086 -8.447024)
		(stroke
			(width 0.06985)
			(type default)
		)
		(layer "B.Cu")
	)
	(gr_line
		(start 90.350086 -5.814568)
		(end 90.350086 -8.447024)
		(stroke
			(width 0.06985)
			(type default)
		)
		(layer "B.Cu")
	)
	(gr_line
		(start 130.932936 -5.818378)
		(end 131.132834 -5.61848)
		(stroke
			(width 0.0889)
			(type default)
		)
		(layer "B.Cu")
	)
	(gr_line
		(start 131.05003 -2.451608)
		(end 131.138676 -2.540254)
		(stroke
			(width 0.0889)
			(type default)
		)
		(layer "B.Cu")
	)
	(gr_line
		(start 131.05003 -1.690624)
		(end 131.05003 -2.451608)
		(stroke
			(width 0.0889)
			(type default)
		)
		(layer "B.Cu")
	)
	(gr_line
		(start 131.532884 -66.672206)
		(end 131.732782 -66.872104)
		(stroke
			(width 0.0889)
			(type default)
		)
		(layer "B.Cu")
	)
	(gr_line
		(start 131.567428 -5.61848)
		(end 131.767326 -5.818378)
		(stroke
			(width 0.0889)
			(type default)
		)
		(layer "B.Cu")
	)
	(gr_line
		(start 131.573524 -2.540254)
		(end 131.649978 -2.4638)
		(stroke
			(width 0.0889)
			(type default)
		)
		(layer "B.Cu")
	)
	(gr_line
		(start 131.649978 -70.058026)
		(end 131.649978 -70.79996)
		(stroke
			(width 0.0889)
			(type default)
		)
		(layer "B.Cu")
	)
	(gr_line
		(start 131.649978 -70.058026)
		(end 131.744974 -69.96303)
		(stroke
			(width 0.0889)
			(type default)
		)
		(layer "B.Cu")
	)
	(gr_line
		(start 131.649978 -1.690624)
		(end 131.649978 -2.4638)
		(stroke
			(width 0.0889)
			(type default)
		)
		(layer "B.Cu")
	)
	(gr_line
		(start 132.167376 -66.872104)
		(end 132.367274 -66.672206)
		(stroke
			(width 0.0889)
			(type default)
		)
		(layer "B.Cu")
	)
	(gr_line
		(start 132.179822 -69.96303)
		(end 132.25018 -70.033388)
		(stroke
			(width 0.0889)
			(type default)
		)
		(layer "B.Cu")
	)
	(gr_line
		(start 132.25018 -70.033388)
		(end 132.25018 -70.79996)
		(stroke
			(width 0.0889)
			(type default)
		)
		(layer "B.Cu")
	)
	(gr_line
		(start 141.132814 -66.672206)
		(end 141.332712 -66.872104)
		(stroke
			(width 0.0889)
			(type default)
		)
		(layer "B.Cu")
	)
	(gr_line
		(start 141.250162 -70.008242)
		(end 141.250162 -70.79996)
		(stroke
			(width 0.0889)
			(type default)
		)
		(layer "B.Cu")
	)
	(gr_line
		(start 141.250162 -70.008242)
		(end 141.32687 -69.931534)
		(stroke
			(width 0.0889)
			(type default)
		)
		(layer "B.Cu")
	)
	(gr_line
		(start 141.761464 -69.931534)
		(end 141.85011 -70.02018)
		(stroke
			(width 0.0889)
			(type default)
		)
		(layer "B.Cu")
	)
	(gr_line
		(start 141.767306 -66.872104)
		(end 141.967204 -66.672206)
		(stroke
			(width 0.0889)
			(type default)
		)
		(layer "B.Cu")
	)
	(gr_line
		(start 141.85011 -70.02018)
		(end 141.85011 -70.79996)
		(stroke
			(width 0.0889)
			(type default)
		)
		(layer "B.Cu")
	)
	(gr_line
		(start 145.932906 -5.818378)
		(end 146.132804 -5.61848)
		(stroke
			(width 0.0889)
			(type default)
		)
		(layer "B.Cu")
	)
	(gr_line
		(start 146.05 -2.465578)
		(end 146.111976 -2.527554)
		(stroke
			(width 0.0889)
			(type default)
		)
		(layer "B.Cu")
	)
	(gr_line
		(start 146.05 -1.690624)
		(end 146.05 -2.465578)
		(stroke
			(width 0.0889)
			(type default)
		)
		(layer "B.Cu")
	)
	(gr_line
		(start 146.546824 -2.527554)
		(end 146.649948 -2.42443)
		(stroke
			(width 0.0889)
			(type default)
		)
		(layer "B.Cu")
	)
	(gr_line
		(start 146.567398 -5.61848)
		(end 146.767296 -5.818378)
		(stroke
			(width 0.0889)
			(type default)
		)
		(layer "B.Cu")
	)
	(gr_line
		(start 146.649948 -1.690624)
		(end 146.649948 -2.42443)
		(stroke
			(width 0.0889)
			(type default)
		)
		(layer "B.Cu")
	)
	(gr_line
		(start 153.68651 -69.333618)
		(end 153.763218 -69.333618)
		(stroke
			(width 0.10795)
			(type default)
		)
		(layer "B.Cu")
	)
	(gr_line
		(start 153.6954 -68.6054)
		(end 154.373834 -69.283834)
		(stroke
			(width 0.10795)
			(type default)
		)
		(layer "B.Cu")
	)
	(gr_line
		(start 153.763218 -69.333618)
		(end 154.002994 -69.573394)
		(stroke
			(width 0.10795)
			(type default)
		)
		(layer "B.Cu")
	)
	(gr_line
		(start 153.850086 -70.050914)
		(end 153.850086 -70.79996)
		(stroke
			(width 0.10795)
			(type default)
		)
		(layer "B.Cu")
	)
	(gr_line
		(start 153.850086 -70.050914)
		(end 153.899362 -70.001638)
		(stroke
			(width 0.10795)
			(type default)
		)
		(layer "B.Cu")
	)
	(gr_line
		(start 154.15006 -63.373)
		(end 154.176984 -63.399924)
		(stroke
			(width 0.10795)
			(type default)
		)
		(layer "B.Cu")
	)
	(gr_line
		(start 154.15006 -62.599824)
		(end 154.15006 -63.373)
		(stroke
			(width 0.10795)
			(type default)
		)
		(layer "B.Cu")
	)
	(gr_line
		(start 154.22626 -64.15786)
		(end 154.813 -64.7446)
		(stroke
			(width 0.10795)
			(type default)
		)
		(layer "B.Cu")
	)
	(gr_line
		(start 154.423872 -70.001638)
		(end 154.450034 -70.0278)
		(stroke
			(width 0.10795)
			(type default)
		)
		(layer "B.Cu")
	)
	(gr_line
		(start 154.450034 -70.0278)
		(end 154.450034 -70.79996)
		(stroke
			(width 0.10795)
			(type default)
		)
		(layer "B.Cu")
	)
	(gr_line
		(start 154.5971 -63.881762)
		(end 154.750262 -64.034924)
		(stroke
			(width 0.10795)
			(type default)
		)
		(layer "B.Cu")
	)
	(gr_line
		(start 154.701494 -63.399924)
		(end 154.750008 -63.35141)
		(stroke
			(width 0.10795)
			(type default)
		)
		(layer "B.Cu")
	)
	(gr_line
		(start 154.750008 -62.599824)
		(end 154.750008 -63.35141)
		(stroke
			(width 0.10795)
			(type default)
		)
		(layer "B.Cu")
	)
	(gr_line
		(start 154.750262 -64.034924)
		(end 154.923998 -64.034924)
		(stroke
			(width 0.10795)
			(type default)
		)
		(layer "B.Cu")
	)
	(gr_line
		(start 163.6014 -7.697978)
		(end 163.95065 -8.047228)
		(stroke
			(width 0.10795)
			(type default)
		)
		(layer "B.Cu")
	)
	(gr_line
		(start 163.74999 -9.329166)
		(end 163.74999 -9.89076)
		(stroke
			(width 0.10795)
			(type default)
		)
		(layer "B.Cu")
	)
	(gr_line
		(start 163.74999 -8.70585)
		(end 163.74999 -8.753856)
		(stroke
			(width 0.10795)
			(type default)
		)
		(layer "B.Cu")
	)
	(gr_line
		(start 163.95065 -8.33755)
		(end 163.95065 -8.385556)
		(stroke
			(width 0.10795)
			(type default)
		)
		(layer "B.Cu")
	)
	(gr_line
		(start 163.95065 -8.047228)
		(end 163.95065 -8.33501)
		(stroke
			(width 0.10795)
			(type default)
		)
		(layer "B.Cu")
	)
	(gr_line
		(start 164.049964 -2.516378)
		(end 164.050726 -2.51714)
		(stroke
			(width 0.10795)
			(type default)
		)
		(layer "B.Cu")
	)
	(gr_line
		(start 164.049964 -1.690624)
		(end 164.049964 -2.516378)
		(stroke
			(width 0.10795)
			(type default)
		)
		(layer "B.Cu")
	)
	(gr_line
		(start 164.12083 -8.960866)
		(end 164.349938 -9.189974)
		(stroke
			(width 0.10795)
			(type default)
		)
		(layer "B.Cu")
	)
	(gr_line
		(start 164.126164 -3.367024)
		(end 164.6936 -3.93446)
		(stroke
			(width 0.10795)
			(type default)
		)
		(layer "B.Cu")
	)
	(gr_line
		(start 164.126164 -3.346196)
		(end 164.126164 -3.367024)
		(stroke
			(width 0.10795)
			(type default)
		)
		(layer "B.Cu")
	)
	(gr_line
		(start 164.349938 -9.189974)
		(end 164.349938 -9.89076)
		(stroke
			(width 0.10795)
			(type default)
		)
		(layer "B.Cu")
	)
	(gr_line
		(start 164.497004 -2.977896)
		(end 164.746686 -3.227578)
		(stroke
			(width 0.10795)
			(type default)
		)
		(layer "B.Cu")
	)
	(gr_line
		(start 164.575236 -2.51714)
		(end 164.649912 -2.442464)
		(stroke
			(width 0.10795)
			(type default)
		)
		(layer "B.Cu")
	)
	(gr_line
		(start 164.649912 -1.690624)
		(end 164.649912 -2.442464)
		(stroke
			(width 0.10795)
			(type default)
		)
		(layer "B.Cu")
	)
	(gr_line
		(start 164.746686 -3.227578)
		(end 164.7952 -3.227578)
		(stroke
			(width 0.10795)
			(type default)
		)
		(layer "B.Cu")
	)
	(gr_line
		(start 171.732702 -66.672206)
		(end 171.9326 -66.872104)
		(stroke
			(width 0.0889)
			(type default)
		)
		(layer "B.Cu")
	)
	(gr_line
		(start 171.85005 -70.066154)
		(end 171.85005 -70.79996)
		(stroke
			(width 0.0889)
			(type default)
		)
		(layer "B.Cu")
	)
	(gr_line
		(start 171.85005 -70.066154)
		(end 171.953174 -69.96303)
		(stroke
			(width 0.0889)
			(type default)
		)
		(layer "B.Cu")
	)
	(gr_line
		(start 172.367194 -66.872104)
		(end 172.567092 -66.672206)
		(stroke
			(width 0.0889)
			(type default)
		)
		(layer "B.Cu")
	)
	(gr_line
		(start 172.388022 -69.96303)
		(end 172.449998 -70.025006)
		(stroke
			(width 0.0889)
			(type default)
		)
		(layer "B.Cu")
	)
	(gr_line
		(start 172.449998 -70.025006)
		(end 172.449998 -70.79996)
		(stroke
			(width 0.0889)
			(type default)
		)
		(layer "B.Cu")
	)
	(gr_line
		(start 176.537366 -5.804662)
		(end 176.732184 -5.609844)
		(stroke
			(width 0.0889)
			(type default)
		)
		(layer "B.Cu")
	)
	(gr_line
		(start 176.649888 -2.470404)
		(end 176.738534 -2.55905)
		(stroke
			(width 0.0889)
			(type default)
		)
		(layer "B.Cu")
	)
	(gr_line
		(start 176.649888 -1.690624)
		(end 176.649888 -2.470404)
		(stroke
			(width 0.0889)
			(type default)
		)
		(layer "B.Cu")
	)
	(gr_line
		(start 176.832768 -66.672206)
		(end 177.18786 -66.317114)
		(stroke
			(width 0.0889)
			(type default)
		)
		(layer "B.Cu")
	)
	(gr_line
		(start 176.950116 -63.349124)
		(end 176.98847 -63.387478)
		(stroke
			(width 0.0889)
			(type default)
		)
		(layer "B.Cu")
	)
	(gr_line
		(start 176.950116 -62.599824)
		(end 176.950116 -63.349124)
		(stroke
			(width 0.0889)
			(type default)
		)
		(layer "B.Cu")
	)
	(gr_line
		(start 177.167032 -5.609844)
		(end 177.362358 -5.80517)
		(stroke
			(width 0.0889)
			(type default)
		)
		(layer "B.Cu")
	)
	(gr_line
		(start 177.173128 -2.55905)
		(end 177.249836 -2.482342)
		(stroke
			(width 0.0889)
			(type default)
		)
		(layer "B.Cu")
	)
	(gr_line
		(start 177.249836 -1.690624)
		(end 177.249836 -2.482342)
		(stroke
			(width 0.0889)
			(type default)
		)
		(layer "B.Cu")
	)
	(gr_line
		(start 177.29581 -63.629794)
		(end 177.550064 -63.37554)
		(stroke
			(width 0.0889)
			(type default)
		)
		(layer "B.Cu")
	)
	(gr_line
		(start 177.4952 -66.500248)
		(end 177.667158 -66.672206)
		(stroke
			(width 0.0889)
			(type default)
		)
		(layer "B.Cu")
	)
	(gr_line
		(start 177.550064 -62.599824)
		(end 177.550064 -63.37554)
		(stroke
			(width 0.0889)
			(type default)
		)
		(layer "B.Cu")
	)
	(gr_arc
		(start 1.54686 -67.178682)
		(mid 1.9304 -67.562222)
		(end 2.31394 -67.178682)
		(stroke
			(width 0.2)
			(type default)
		)
		(layer "In1.Cu")
	)
	(gr_line
		(start 1.54686 -66.221102)
		(end 1.54686 -67.178682)
		(stroke
			(width 0.2)
			(type default)
		)
		(layer "In1.Cu")
	)
	(gr_arc
		(start 1.54686 -64.178434)
		(mid 1.930273 -64.562228)
		(end 2.31394 -64.178688)
		(stroke
			(width 0.2)
			(type default)
		)
		(layer "In1.Cu")
	)
	(gr_line
		(start 1.54686 -63.221108)
		(end 1.54686 -64.178434)
		(stroke
			(width 0.2)
			(type default)
		)
		(layer "In1.Cu")
	)
	(gr_arc
		(start 1.54686 -61.178694)
		(mid 1.9304 -61.562234)
		(end 2.31394 -61.178694)
		(stroke
			(width 0.2)
			(type default)
		)
		(layer "In1.Cu")
	)
	(gr_line
		(start 1.54686 -60.221114)
		(end 1.54686 -61.178694)
		(stroke
			(width 0.2)
			(type default)
		)
		(layer "In1.Cu")
	)
	(gr_line
		(start 2.31394 -67.178682)
		(end 2.31394 -66.221356)
		(stroke
			(width 0.2)
			(type default)
		)
		(layer "In1.Cu")
	)
	(gr_arc
		(start 2.31394 -66.221356)
		(mid 1.930527 -65.837562)
		(end 1.54686 -66.221102)
		(stroke
			(width 0.2)
			(type default)
		)
		(layer "In1.Cu")
	)
	(gr_line
		(start 2.31394 -64.178688)
		(end 2.31394 -63.221108)
		(stroke
			(width 0.2)
			(type default)
		)
		(layer "In1.Cu")
	)
	(gr_arc
		(start 2.31394 -63.221108)
		(mid 1.9304 -62.837568)
		(end 1.54686 -63.221108)
		(stroke
			(width 0.2)
			(type default)
		)
		(layer "In1.Cu")
	)
	(gr_line
		(start 2.31394 -61.178694)
		(end 2.31394 -60.221368)
		(stroke
			(width 0.2)
			(type default)
		)
		(layer "In1.Cu")
	)
	(gr_arc
		(start 2.31394 -60.221368)
		(mid 1.930527 -59.837574)
		(end 1.54686 -60.221114)
		(stroke
			(width 0.2)
			(type default)
		)
		(layer "In1.Cu")
	)
	(gr_arc
		(start 2.94132 -59.664092)
		(mid 3.324733 -60.047886)
		(end 3.7084 -59.664346)
		(stroke
			(width 0.2)
			(type default)
		)
		(layer "In1.Cu")
	)
	(gr_line
		(start 2.94132 -58.706766)
		(end 2.94132 -59.664092)
		(stroke
			(width 0.2)
			(type default)
		)
		(layer "In1.Cu")
	)
	(gr_arc
		(start 3.06832 -65.664334)
		(mid 3.45186 -66.047874)
		(end 3.8354 -65.664334)
		(stroke
			(width 0.2)
			(type default)
		)
		(layer "In1.Cu")
	)
	(gr_line
		(start 3.06832 -64.706754)
		(end 3.06832 -65.664334)
		(stroke
			(width 0.2)
			(type default)
		)
		(layer "In1.Cu")
	)
	(gr_arc
		(start 3.06832 -62.66434)
		(mid 3.45186 -63.04788)
		(end 3.8354 -62.66434)
		(stroke
			(width 0.2)
			(type default)
		)
		(layer "In1.Cu")
	)
	(gr_line
		(start 3.06832 -61.70676)
		(end 3.06832 -62.66434)
		(stroke
			(width 0.2)
			(type default)
		)
		(layer "In1.Cu")
	)
	(gr_line
		(start 3.7084 -59.664346)
		(end 3.7084 -58.706766)
		(stroke
			(width 0.2)
			(type default)
		)
		(layer "In1.Cu")
	)
	(gr_arc
		(start 3.7084 -58.706766)
		(mid 3.32486 -58.323226)
		(end 2.94132 -58.706766)
		(stroke
			(width 0.2)
			(type default)
		)
		(layer "In1.Cu")
	)
	(gr_line
		(start 3.8354 -65.664334)
		(end 3.8354 -64.707008)
		(stroke
			(width 0.2)
			(type default)
		)
		(layer "In1.Cu")
	)
	(gr_arc
		(start 3.8354 -64.707008)
		(mid 3.451987 -64.323214)
		(end 3.06832 -64.706754)
		(stroke
			(width 0.2)
			(type default)
		)
		(layer "In1.Cu")
	)
	(gr_line
		(start 3.8354 -62.66434)
		(end 3.8354 -61.707014)
		(stroke
			(width 0.2)
			(type default)
		)
		(layer "In1.Cu")
	)
	(gr_arc
		(start 3.8354 -61.707014)
		(mid 3.451987 -61.32322)
		(end 3.06832 -61.70676)
		(stroke
			(width 0.2)
			(type default)
		)
		(layer "In1.Cu")
	)
	(gr_arc
		(start 7.747 -51.6128)
		(mid 8.128 -51.9938)
		(end 8.509 -51.6128)
		(stroke
			(width 0.2)
			(type default)
		)
		(layer "In1.Cu")
	)
	(gr_line
		(start 7.747 -50.6222)
		(end 7.747 -51.6128)
		(stroke
			(width 0.2)
			(type default)
		)
		(layer "In1.Cu")
	)
	(gr_arc
		(start 7.89686 -65.6082)
		(mid 7.912483 -65.645917)
		(end 7.9502 -65.66154)
		(stroke
			(width 0.2)
			(type default)
		)
		(layer "In1.Cu")
	)
	(gr_line
		(start 7.89686 -65.2018)
		(end 7.89686 -65.6082)
		(stroke
			(width 0.2)
			(type default)
		)
		(layer "In1.Cu")
	)
	(gr_arc
		(start 7.89686 -64.7192)
		(mid 7.912483 -64.756917)
		(end 7.9502 -64.77254)
		(stroke
			(width 0.2)
			(type default)
		)
		(layer "In1.Cu")
	)
	(gr_line
		(start 7.89686 -64.3128)
		(end 7.89686 -64.7192)
		(stroke
			(width 0.2)
			(type default)
		)
		(layer "In1.Cu")
	)
	(gr_arc
		(start 7.89686 -63.8302)
		(mid 7.912483 -63.867917)
		(end 7.9502 -63.88354)
		(stroke
			(width 0.2)
			(type default)
		)
		(layer "In1.Cu")
	)
	(gr_line
		(start 7.89686 -63.4238)
		(end 7.89686 -63.8302)
		(stroke
			(width 0.2)
			(type default)
		)
		(layer "In1.Cu")
	)
	(gr_arc
		(start 7.89686 -62.9412)
		(mid 7.912483 -62.978917)
		(end 7.9502 -62.99454)
		(stroke
			(width 0.2)
			(type default)
		)
		(layer "In1.Cu")
	)
	(gr_line
		(start 7.89686 -62.5348)
		(end 7.89686 -62.9412)
		(stroke
			(width 0.2)
			(type default)
		)
		(layer "In1.Cu")
	)
	(gr_arc
		(start 7.89686 -62.0522)
		(mid 7.912483 -62.089917)
		(end 7.9502 -62.10554)
		(stroke
			(width 0.2)
			(type default)
		)
		(layer "In1.Cu")
	)
	(gr_line
		(start 7.89686 -61.6458)
		(end 7.89686 -62.0522)
		(stroke
			(width 0.2)
			(type default)
		)
		(layer "In1.Cu")
	)
	(gr_arc
		(start 7.89686 -61.1632)
		(mid 7.912483 -61.200917)
		(end 7.9502 -61.21654)
		(stroke
			(width 0.2)
			(type default)
		)
		(layer "In1.Cu")
	)
	(gr_line
		(start 7.89686 -60.7568)
		(end 7.89686 -61.1632)
		(stroke
			(width 0.2)
			(type default)
		)
		(layer "In1.Cu")
	)
	(gr_arc
		(start 7.89686 -60.2742)
		(mid 7.912483 -60.311917)
		(end 7.9502 -60.32754)
		(stroke
			(width 0.2)
			(type default)
		)
		(layer "In1.Cu")
	)
	(gr_line
		(start 7.89686 -59.8678)
		(end 7.89686 -60.2742)
		(stroke
			(width 0.2)
			(type default)
		)
		(layer "In1.Cu")
	)
	(gr_arc
		(start 7.89686 -59.3852)
		(mid 7.912483 -59.422917)
		(end 7.9502 -59.43854)
		(stroke
			(width 0.2)
			(type default)
		)
		(layer "In1.Cu")
	)
	(gr_line
		(start 7.89686 -58.9788)
		(end 7.89686 -59.3852)
		(stroke
			(width 0.2)
			(type default)
		)
		(layer "In1.Cu")
	)
	(gr_arc
		(start 7.89686 -58.4962)
		(mid 7.912483 -58.533917)
		(end 7.9502 -58.54954)
		(stroke
			(width 0.2)
			(type default)
		)
		(layer "In1.Cu")
	)
	(gr_line
		(start 7.89686 -58.0898)
		(end 7.89686 -58.4962)
		(stroke
			(width 0.2)
			(type default)
		)
		(layer "In1.Cu")
	)
	(gr_arc
		(start 7.89686 -57.6072)
		(mid 7.912483 -57.644917)
		(end 7.9502 -57.66054)
		(stroke
			(width 0.2)
			(type default)
		)
		(layer "In1.Cu")
	)
	(gr_line
		(start 7.89686 -57.2008)
		(end 7.89686 -57.6072)
		(stroke
			(width 0.2)
			(type default)
		)
		(layer "In1.Cu")
	)
	(gr_arc
		(start 7.89686 -56.7182)
		(mid 7.912483 -56.755917)
		(end 7.9502 -56.77154)
		(stroke
			(width 0.2)
			(type default)
		)
		(layer "In1.Cu")
	)
	(gr_line
		(start 7.89686 -56.3118)
		(end 7.89686 -56.7182)
		(stroke
			(width 0.2)
			(type default)
		)
		(layer "In1.Cu")
	)
	(gr_arc
		(start 7.89686 -55.8292)
		(mid 7.912483 -55.866917)
		(end 7.9502 -55.88254)
		(stroke
			(width 0.2)
			(type default)
		)
		(layer "In1.Cu")
	)
	(gr_line
		(start 7.89686 -55.4228)
		(end 7.89686 -55.8292)
		(stroke
			(width 0.2)
			(type default)
		)
		(layer "In1.Cu")
	)
	(gr_line
		(start 7.9502 -65.66154)
		(end 8.3058 -65.66154)
		(stroke
			(width 0.2)
			(type default)
		)
		(layer "In1.Cu")
	)
	(gr_arc
		(start 7.9502 -65.14846)
		(mid 7.912483 -65.164083)
		(end 7.89686 -65.2018)
		(stroke
			(width 0.2)
			(type default)
		)
		(layer "In1.Cu")
	)
	(gr_line
		(start 7.9502 -64.77254)
		(end 8.3058 -64.77254)
		(stroke
			(width 0.2)
			(type default)
		)
		(layer "In1.Cu")
	)
	(gr_arc
		(start 7.9502 -64.25946)
		(mid 7.912483 -64.275083)
		(end 7.89686 -64.3128)
		(stroke
			(width 0.2)
			(type default)
		)
		(layer "In1.Cu")
	)
	(gr_line
		(start 7.9502 -63.88354)
		(end 8.3058 -63.88354)
		(stroke
			(width 0.2)
			(type default)
		)
		(layer "In1.Cu")
	)
	(gr_arc
		(start 7.9502 -63.37046)
		(mid 7.912483 -63.386083)
		(end 7.89686 -63.4238)
		(stroke
			(width 0.2)
			(type default)
		)
		(layer "In1.Cu")
	)
	(gr_line
		(start 7.9502 -62.99454)
		(end 8.3058 -62.99454)
		(stroke
			(width 0.2)
			(type default)
		)
		(layer "In1.Cu")
	)
	(gr_arc
		(start 7.9502 -62.48146)
		(mid 7.912483 -62.497083)
		(end 7.89686 -62.5348)
		(stroke
			(width 0.2)
			(type default)
		)
		(layer "In1.Cu")
	)
	(gr_line
		(start 7.9502 -62.10554)
		(end 8.3058 -62.10554)
		(stroke
			(width 0.2)
			(type default)
		)
		(layer "In1.Cu")
	)
	(gr_arc
		(start 7.9502 -61.59246)
		(mid 7.912483 -61.608083)
		(end 7.89686 -61.6458)
		(stroke
			(width 0.2)
			(type default)
		)
		(layer "In1.Cu")
	)
	(gr_line
		(start 7.9502 -61.21654)
		(end 8.3058 -61.21654)
		(stroke
			(width 0.2)
			(type default)
		)
		(layer "In1.Cu")
	)
	(gr_arc
		(start 7.9502 -60.70346)
		(mid 7.912483 -60.719083)
		(end 7.89686 -60.7568)
		(stroke
			(width 0.2)
			(type default)
		)
		(layer "In1.Cu")
	)
	(gr_line
		(start 7.9502 -60.32754)
		(end 8.3058 -60.32754)
		(stroke
			(width 0.2)
			(type default)
		)
		(layer "In1.Cu")
	)
	(gr_arc
		(start 7.9502 -59.81446)
		(mid 7.912483 -59.830083)
		(end 7.89686 -59.8678)
		(stroke
			(width 0.2)
			(type default)
		)
		(layer "In1.Cu")
	)
	(gr_line
		(start 7.9502 -59.43854)
		(end 8.3058 -59.43854)
		(stroke
			(width 0.2)
			(type default)
		)
		(layer "In1.Cu")
	)
	(gr_arc
		(start 7.9502 -58.92546)
		(mid 7.912483 -58.941083)
		(end 7.89686 -58.9788)
		(stroke
			(width 0.2)
			(type default)
		)
		(layer "In1.Cu")
	)
	(gr_line
		(start 7.9502 -58.54954)
		(end 8.3058 -58.54954)
		(stroke
			(width 0.2)
			(type default)
		)
		(layer "In1.Cu")
	)
	(gr_arc
		(start 7.9502 -58.03646)
		(mid 7.912483 -58.052083)
		(end 7.89686 -58.0898)
		(stroke
			(width 0.2)
			(type default)
		)
		(layer "In1.Cu")
	)
	(gr_line
		(start 7.9502 -57.66054)
		(end 8.3058 -57.66054)
		(stroke
			(width 0.2)
			(type default)
		)
		(layer "In1.Cu")
	)
	(gr_arc
		(start 7.9502 -57.14746)
		(mid 7.912483 -57.163083)
		(end 7.89686 -57.2008)
		(stroke
			(width 0.2)
			(type default)
		)
		(layer "In1.Cu")
	)
	(gr_line
		(start 7.9502 -56.77154)
		(end 8.3058 -56.77154)
		(stroke
			(width 0.2)
			(type default)
		)
		(layer "In1.Cu")
	)
	(gr_arc
		(start 7.9502 -56.25846)
		(mid 7.912483 -56.274083)
		(end 7.89686 -56.3118)
		(stroke
			(width 0.2)
			(type default)
		)
		(layer "In1.Cu")
	)
	(gr_line
		(start 7.9502 -55.88254)
		(end 8.3058 -55.88254)
		(stroke
			(width 0.2)
			(type default)
		)
		(layer "In1.Cu")
	)
	(gr_arc
		(start 7.9502 -55.36946)
		(mid 7.912483 -55.385083)
		(end 7.89686 -55.4228)
		(stroke
			(width 0.2)
			(type default)
		)
		(layer "In1.Cu")
	)
	(gr_arc
		(start 8.3058 -65.66154)
		(mid 8.343517 -65.645917)
		(end 8.35914 -65.6082)
		(stroke
			(width 0.2)
			(type default)
		)
		(layer "In1.Cu")
	)
	(gr_line
		(start 8.3058 -65.14846)
		(end 7.9502 -65.14846)
		(stroke
			(width 0.2)
			(type default)
		)
		(layer "In1.Cu")
	)
	(gr_arc
		(start 8.3058 -64.77254)
		(mid 8.343517 -64.756917)
		(end 8.35914 -64.7192)
		(stroke
			(width 0.2)
			(type default)
		)
		(layer "In1.Cu")
	)
	(gr_line
		(start 8.3058 -64.25946)
		(end 7.9502 -64.25946)
		(stroke
			(width 0.2)
			(type default)
		)
		(layer "In1.Cu")
	)
	(gr_arc
		(start 8.3058 -63.88354)
		(mid 8.343517 -63.867917)
		(end 8.35914 -63.8302)
		(stroke
			(width 0.2)
			(type default)
		)
		(layer "In1.Cu")
	)
	(gr_line
		(start 8.3058 -63.37046)
		(end 7.9502 -63.37046)
		(stroke
			(width 0.2)
			(type default)
		)
		(layer "In1.Cu")
	)
	(gr_arc
		(start 8.3058 -62.99454)
		(mid 8.343517 -62.978917)
		(end 8.35914 -62.9412)
		(stroke
			(width 0.2)
			(type default)
		)
		(layer "In1.Cu")
	)
	(gr_line
		(start 8.3058 -62.48146)
		(end 7.9502 -62.48146)
		(stroke
			(width 0.2)
			(type default)
		)
		(layer "In1.Cu")
	)
	(gr_arc
		(start 8.3058 -62.10554)
		(mid 8.343517 -62.089917)
		(end 8.35914 -62.0522)
		(stroke
			(width 0.2)
			(type default)
		)
		(layer "In1.Cu")
	)
	(gr_line
		(start 8.3058 -61.59246)
		(end 7.9502 -61.59246)
		(stroke
			(width 0.2)
			(type default)
		)
		(layer "In1.Cu")
	)
	(gr_arc
		(start 8.3058 -61.21654)
		(mid 8.343517 -61.200917)
		(end 8.35914 -61.1632)
		(stroke
			(width 0.2)
			(type default)
		)
		(layer "In1.Cu")
	)
	(gr_line
		(start 8.3058 -60.70346)
		(end 7.9502 -60.70346)
		(stroke
			(width 0.2)
			(type default)
		)
		(layer "In1.Cu")
	)
	(gr_arc
		(start 8.3058 -60.32754)
		(mid 8.343517 -60.311917)
		(end 8.35914 -60.2742)
		(stroke
			(width 0.2)
			(type default)
		)
		(layer "In1.Cu")
	)
	(gr_line
		(start 8.3058 -59.81446)
		(end 7.9502 -59.81446)
		(stroke
			(width 0.2)
			(type default)
		)
		(layer "In1.Cu")
	)
	(gr_arc
		(start 8.3058 -59.43854)
		(mid 8.343517 -59.422917)
		(end 8.35914 -59.3852)
		(stroke
			(width 0.2)
			(type default)
		)
		(layer "In1.Cu")
	)
	(gr_line
		(start 8.3058 -58.92546)
		(end 7.9502 -58.92546)
		(stroke
			(width 0.2)
			(type default)
		)
		(layer "In1.Cu")
	)
	(gr_arc
		(start 8.3058 -58.54954)
		(mid 8.343517 -58.533917)
		(end 8.35914 -58.4962)
		(stroke
			(width 0.2)
			(type default)
		)
		(layer "In1.Cu")
	)
	(gr_line
		(start 8.3058 -58.03646)
		(end 7.9502 -58.03646)
		(stroke
			(width 0.2)
			(type default)
		)
		(layer "In1.Cu")
	)
	(gr_arc
		(start 8.3058 -57.66054)
		(mid 8.343517 -57.644917)
		(end 8.35914 -57.6072)
		(stroke
			(width 0.2)
			(type default)
		)
		(layer "In1.Cu")
	)
	(gr_line
		(start 8.3058 -57.14746)
		(end 7.9502 -57.14746)
		(stroke
			(width 0.2)
			(type default)
		)
		(layer "In1.Cu")
	)
	(gr_arc
		(start 8.3058 -56.77154)
		(mid 8.343517 -56.755917)
		(end 8.35914 -56.7182)
		(stroke
			(width 0.2)
			(type default)
		)
		(layer "In1.Cu")
	)
	(gr_line
		(start 8.3058 -56.25846)
		(end 7.9502 -56.25846)
		(stroke
			(width 0.2)
			(type default)
		)
		(layer "In1.Cu")
	)
	(gr_arc
		(start 8.3058 -55.88254)
		(mid 8.343517 -55.866917)
		(end 8.35914 -55.8292)
		(stroke
			(width 0.2)
			(type default)
		)
		(layer "In1.Cu")
	)
	(gr_line
		(start 8.3058 -55.36946)
		(end 7.9502 -55.36946)
		(stroke
			(width 0.2)
			(type default)
		)
		(layer "In1.Cu")
	)
	(gr_line
		(start 8.35914 -65.6082)
		(end 8.35914 -65.2018)
		(stroke
			(width 0.2)
			(type default)
		)
		(layer "In1.Cu")
	)
	(gr_arc
		(start 8.35914 -65.2018)
		(mid 8.343517 -65.164083)
		(end 8.3058 -65.14846)
		(stroke
			(width 0.2)
			(type default)
		)
		(layer "In1.Cu")
	)
	(gr_line
		(start 8.35914 -64.7192)
		(end 8.35914 -64.3128)
		(stroke
			(width 0.2)
			(type default)
		)
		(layer "In1.Cu")
	)
	(gr_arc
		(start 8.35914 -64.3128)
		(mid 8.343517 -64.275083)
		(end 8.3058 -64.25946)
		(stroke
			(width 0.2)
			(type default)
		)
		(layer "In1.Cu")
	)
	(gr_line
		(start 8.35914 -63.8302)
		(end 8.35914 -63.4238)
		(stroke
			(width 0.2)
			(type default)
		)
		(layer "In1.Cu")
	)
	(gr_arc
		(start 8.35914 -63.4238)
		(mid 8.343517 -63.386083)
		(end 8.3058 -63.37046)
		(stroke
			(width 0.2)
			(type default)
		)
		(layer "In1.Cu")
	)
	(gr_line
		(start 8.35914 -62.9412)
		(end 8.35914 -62.5348)
		(stroke
			(width 0.2)
			(type default)
		)
		(layer "In1.Cu")
	)
	(gr_arc
		(start 8.35914 -62.5348)
		(mid 8.343517 -62.497083)
		(end 8.3058 -62.48146)
		(stroke
			(width 0.2)
			(type default)
		)
		(layer "In1.Cu")
	)
	(gr_line
		(start 8.35914 -62.0522)
		(end 8.35914 -61.6458)
		(stroke
			(width 0.2)
			(type default)
		)
		(layer "In1.Cu")
	)
	(gr_arc
		(start 8.35914 -61.6458)
		(mid 8.343517 -61.608083)
		(end 8.3058 -61.59246)
		(stroke
			(width 0.2)
			(type default)
		)
		(layer "In1.Cu")
	)
	(gr_line
		(start 8.35914 -61.1632)
		(end 8.35914 -60.7568)
		(stroke
			(width 0.2)
			(type default)
		)
		(layer "In1.Cu")
	)
	(gr_arc
		(start 8.35914 -60.7568)
		(mid 8.343517 -60.719083)
		(end 8.3058 -60.70346)
		(stroke
			(width 0.2)
			(type default)
		)
		(layer "In1.Cu")
	)
	(gr_line
		(start 8.35914 -60.2742)
		(end 8.35914 -59.8678)
		(stroke
			(width 0.2)
			(type default)
		)
		(layer "In1.Cu")
	)
	(gr_arc
		(start 8.35914 -59.8678)
		(mid 8.343517 -59.830083)
		(end 8.3058 -59.81446)
		(stroke
			(width 0.2)
			(type default)
		)
		(layer "In1.Cu")
	)
	(gr_line
		(start 8.35914 -59.3852)
		(end 8.35914 -58.9788)
		(stroke
			(width 0.2)
			(type default)
		)
		(layer "In1.Cu")
	)
	(gr_arc
		(start 8.35914 -58.9788)
		(mid 8.343517 -58.941083)
		(end 8.3058 -58.92546)
		(stroke
			(width 0.2)
			(type default)
		)
		(layer "In1.Cu")
	)
	(gr_line
		(start 8.35914 -58.4962)
		(end 8.35914 -58.0898)
		(stroke
			(width 0.2)
			(type default)
		)
		(layer "In1.Cu")
	)
	(gr_arc
		(start 8.35914 -58.0898)
		(mid 8.343517 -58.052083)
		(end 8.3058 -58.03646)
		(stroke
			(width 0.2)
			(type default)
		)
		(layer "In1.Cu")
	)
	(gr_line
		(start 8.35914 -57.6072)
		(end 8.35914 -57.2008)
		(stroke
			(width 0.2)
			(type default)
		)
		(layer "In1.Cu")
	)
	(gr_arc
		(start 8.35914 -57.2008)
		(mid 8.343517 -57.163083)
		(end 8.3058 -57.14746)
		(stroke
			(width 0.2)
			(type default)
		)
		(layer "In1.Cu")
	)
	(gr_line
		(start 8.35914 -56.7182)
		(end 8.35914 -56.3118)
		(stroke
			(width 0.2)
			(type default)
		)
		(layer "In1.Cu")
	)
	(gr_arc
		(start 8.35914 -56.3118)
		(mid 8.343517 -56.274083)
		(end 8.3058 -56.25846)
		(stroke
			(width 0.2)
			(type default)
		)
		(layer "In1.Cu")
	)
	(gr_line
		(start 8.35914 -55.8292)
		(end 8.35914 -55.4228)
		(stroke
			(width 0.2)
			(type default)
		)
		(layer "In1.Cu")
	)
	(gr_arc
		(start 8.35914 -55.4228)
		(mid 8.343517 -55.385083)
		(end 8.3058 -55.36946)
		(stroke
			(width 0.2)
			(type default)
		)
		(layer "In1.Cu")
	)
	(gr_arc
		(start 8.4582 -53.8988)
		(mid 8.8392 -54.2798)
		(end 9.2202 -53.8988)
		(stroke
			(width 0.2)
			(type default)
		)
		(layer "In1.Cu")
	)
	(gr_line
		(start 8.4582 -52.9082)
		(end 8.4582 -53.8988)
		(stroke
			(width 0.2)
			(type default)
		)
		(layer "In1.Cu")
	)
	(gr_line
		(start 8.509 -51.6128)
		(end 8.509 -50.622454)
		(stroke
			(width 0.2)
			(type default)
		)
		(layer "In1.Cu")
	)
	(gr_arc
		(start 8.509 -50.622454)
		(mid 8.128127 -50.2412)
		(end 7.747 -50.6222)
		(stroke
			(width 0.2)
			(type default)
		)
		(layer "In1.Cu")
	)
	(gr_arc
		(start 8.65886 -65.6082)
		(mid 8.674483 -65.645917)
		(end 8.7122 -65.66154)
		(stroke
			(width 0.2)
			(type default)
		)
		(layer "In1.Cu")
	)
	(gr_line
		(start 8.65886 -65.2018)
		(end 8.65886 -65.6082)
		(stroke
			(width 0.2)
			(type default)
		)
		(layer "In1.Cu")
	)
	(gr_arc
		(start 8.65886 -64.7192)
		(mid 8.674483 -64.756917)
		(end 8.7122 -64.77254)
		(stroke
			(width 0.2)
			(type default)
		)
		(layer "In1.Cu")
	)
	(gr_line
		(start 8.65886 -64.3128)
		(end 8.65886 -64.7192)
		(stroke
			(width 0.2)
			(type default)
		)
		(layer "In1.Cu")
	)
	(gr_arc
		(start 8.65886 -63.8302)
		(mid 8.674483 -63.867917)
		(end 8.7122 -63.88354)
		(stroke
			(width 0.2)
			(type default)
		)
		(layer "In1.Cu")
	)
	(gr_line
		(start 8.65886 -63.4238)
		(end 8.65886 -63.8302)
		(stroke
			(width 0.2)
			(type default)
		)
		(layer "In1.Cu")
	)
	(gr_arc
		(start 8.65886 -62.9412)
		(mid 8.674483 -62.978917)
		(end 8.7122 -62.99454)
		(stroke
			(width 0.2)
			(type default)
		)
		(layer "In1.Cu")
	)
	(gr_line
		(start 8.65886 -62.5348)
		(end 8.65886 -62.9412)
		(stroke
			(width 0.2)
			(type default)
		)
		(layer "In1.Cu")
	)
	(gr_arc
		(start 8.65886 -62.0522)
		(mid 8.674483 -62.089917)
		(end 8.7122 -62.10554)
		(stroke
			(width 0.2)
			(type default)
		)
		(layer "In1.Cu")
	)
	(gr_line
		(start 8.65886 -61.6458)
		(end 8.65886 -62.0522)
		(stroke
			(width 0.2)
			(type default)
		)
		(layer "In1.Cu")
	)
	(gr_arc
		(start 8.65886 -61.1632)
		(mid 8.674483 -61.200917)
		(end 8.7122 -61.21654)
		(stroke
			(width 0.2)
			(type default)
		)
		(layer "In1.Cu")
	)
	(gr_line
		(start 8.65886 -60.7568)
		(end 8.65886 -61.1632)
		(stroke
			(width 0.2)
			(type default)
		)
		(layer "In1.Cu")
	)
	(gr_arc
		(start 8.65886 -60.2742)
		(mid 8.674483 -60.311917)
		(end 8.7122 -60.32754)
		(stroke
			(width 0.2)
			(type default)
		)
		(layer "In1.Cu")
	)
	(gr_line
		(start 8.65886 -59.8678)
		(end 8.65886 -60.2742)
		(stroke
			(width 0.2)
			(type default)
		)
		(layer "In1.Cu")
	)
	(gr_arc
		(start 8.65886 -59.3852)
		(mid 8.674483 -59.422917)
		(end 8.7122 -59.43854)
		(stroke
			(width 0.2)
			(type default)
		)
		(layer "In1.Cu")
	)
	(gr_line
		(start 8.65886 -58.9788)
		(end 8.65886 -59.3852)
		(stroke
			(width 0.2)
			(type default)
		)
		(layer "In1.Cu")
	)
	(gr_arc
		(start 8.65886 -58.4962)
		(mid 8.674483 -58.533917)
		(end 8.7122 -58.54954)
		(stroke
			(width 0.2)
			(type default)
		)
		(layer "In1.Cu")
	)
	(gr_line
		(start 8.65886 -58.0898)
		(end 8.65886 -58.4962)
		(stroke
			(width 0.2)
			(type default)
		)
		(layer "In1.Cu")
	)
	(gr_arc
		(start 8.65886 -57.6072)
		(mid 8.674483 -57.644917)
		(end 8.7122 -57.66054)
		(stroke
			(width 0.2)
			(type default)
		)
		(layer "In1.Cu")
	)
	(gr_line
		(start 8.65886 -57.2008)
		(end 8.65886 -57.6072)
		(stroke
			(width 0.2)
			(type default)
		)
		(layer "In1.Cu")
	)
	(gr_arc
		(start 8.65886 -56.7182)
		(mid 8.674483 -56.755917)
		(end 8.7122 -56.77154)
		(stroke
			(width 0.2)
			(type default)
		)
		(layer "In1.Cu")
	)
	(gr_line
		(start 8.65886 -56.3118)
		(end 8.65886 -56.7182)
		(stroke
			(width 0.2)
			(type default)
		)
		(layer "In1.Cu")
	)
	(gr_arc
		(start 8.65886 -55.8292)
		(mid 8.674483 -55.866917)
		(end 8.7122 -55.88254)
		(stroke
			(width 0.2)
			(type default)
		)
		(layer "In1.Cu")
	)
	(gr_line
		(start 8.65886 -55.4228)
		(end 8.65886 -55.8292)
		(stroke
			(width 0.2)
			(type default)
		)
		(layer "In1.Cu")
	)
	(gr_line
		(start 8.7122 -65.66154)
		(end 9.0678 -65.66154)
		(stroke
			(width 0.2)
			(type default)
		)
		(layer "In1.Cu")
	)
	(gr_arc
		(start 8.7122 -65.14846)
		(mid 8.674483 -65.164083)
		(end 8.65886 -65.2018)
		(stroke
			(width 0.2)
			(type default)
		)
		(layer "In1.Cu")
	)
	(gr_line
		(start 8.7122 -64.77254)
		(end 9.0678 -64.77254)
		(stroke
			(width 0.2)
			(type default)
		)
		(layer "In1.Cu")
	)
	(gr_arc
		(start 8.7122 -64.25946)
		(mid 8.674483 -64.275083)
		(end 8.65886 -64.3128)
		(stroke
			(width 0.2)
			(type default)
		)
		(layer "In1.Cu")
	)
	(gr_line
		(start 8.7122 -63.88354)
		(end 9.0678 -63.88354)
		(stroke
			(width 0.2)
			(type default)
		)
		(layer "In1.Cu")
	)
	(gr_arc
		(start 8.7122 -63.37046)
		(mid 8.674483 -63.386083)
		(end 8.65886 -63.4238)
		(stroke
			(width 0.2)
			(type default)
		)
		(layer "In1.Cu")
	)
	(gr_line
		(start 8.7122 -62.99454)
		(end 9.0678 -62.99454)
		(stroke
			(width 0.2)
			(type default)
		)
		(layer "In1.Cu")
	)
	(gr_arc
		(start 8.7122 -62.48146)
		(mid 8.674483 -62.497083)
		(end 8.65886 -62.5348)
		(stroke
			(width 0.2)
			(type default)
		)
		(layer "In1.Cu")
	)
	(gr_line
		(start 8.7122 -62.10554)
		(end 9.0678 -62.10554)
		(stroke
			(width 0.2)
			(type default)
		)
		(layer "In1.Cu")
	)
	(gr_arc
		(start 8.7122 -61.59246)
		(mid 8.674483 -61.608083)
		(end 8.65886 -61.6458)
		(stroke
			(width 0.2)
			(type default)
		)
		(layer "In1.Cu")
	)
	(gr_line
		(start 8.7122 -61.21654)
		(end 9.0678 -61.21654)
		(stroke
			(width 0.2)
			(type default)
		)
		(layer "In1.Cu")
	)
	(gr_arc
		(start 8.7122 -60.70346)
		(mid 8.674483 -60.719083)
		(end 8.65886 -60.7568)
		(stroke
			(width 0.2)
			(type default)
		)
		(layer "In1.Cu")
	)
	(gr_line
		(start 8.7122 -60.32754)
		(end 9.0678 -60.32754)
		(stroke
			(width 0.2)
			(type default)
		)
		(layer "In1.Cu")
	)
	(gr_arc
		(start 8.7122 -59.81446)
		(mid 8.674483 -59.830083)
		(end 8.65886 -59.8678)
		(stroke
			(width 0.2)
			(type default)
		)
		(layer "In1.Cu")
	)
	(gr_line
		(start 8.7122 -59.43854)
		(end 9.0678 -59.43854)
		(stroke
			(width 0.2)
			(type default)
		)
		(layer "In1.Cu")
	)
	(gr_arc
		(start 8.7122 -58.92546)
		(mid 8.674483 -58.941083)
		(end 8.65886 -58.9788)
		(stroke
			(width 0.2)
			(type default)
		)
		(layer "In1.Cu")
	)
	(gr_line
		(start 8.7122 -58.54954)
		(end 9.0678 -58.54954)
		(stroke
			(width 0.2)
			(type default)
		)
		(layer "In1.Cu")
	)
	(gr_arc
		(start 8.7122 -58.03646)
		(mid 8.674483 -58.052083)
		(end 8.65886 -58.0898)
		(stroke
			(width 0.2)
			(type default)
		)
		(layer "In1.Cu")
	)
	(gr_line
		(start 8.7122 -57.66054)
		(end 9.0678 -57.66054)
		(stroke
			(width 0.2)
			(type default)
		)
		(layer "In1.Cu")
	)
	(gr_arc
		(start 8.7122 -57.14746)
		(mid 8.674483 -57.163083)
		(end 8.65886 -57.2008)
		(stroke
			(width 0.2)
			(type default)
		)
		(layer "In1.Cu")
	)
	(gr_line
		(start 8.7122 -56.77154)
		(end 9.0678 -56.77154)
		(stroke
			(width 0.2)
			(type default)
		)
		(layer "In1.Cu")
	)
	(gr_arc
		(start 8.7122 -56.25846)
		(mid 8.674483 -56.274083)
		(end 8.65886 -56.3118)
		(stroke
			(width 0.2)
			(type default)
		)
		(layer "In1.Cu")
	)
	(gr_line
		(start 8.7122 -55.88254)
		(end 9.0678 -55.88254)
		(stroke
			(width 0.2)
			(type default)
		)
		(layer "In1.Cu")
	)
	(gr_arc
		(start 8.7122 -55.36946)
		(mid 8.674483 -55.385083)
		(end 8.65886 -55.4228)
		(stroke
			(width 0.2)
			(type default)
		)
		(layer "In1.Cu")
	)
	(gr_arc
		(start 9.0678 -65.66154)
		(mid 9.105517 -65.645917)
		(end 9.12114 -65.6082)
		(stroke
			(width 0.2)
			(type default)
		)
		(layer "In1.Cu")
	)
	(gr_line
		(start 9.0678 -65.14846)
		(end 8.7122 -65.14846)
		(stroke
			(width 0.2)
			(type default)
		)
		(layer "In1.Cu")
	)
	(gr_arc
		(start 9.0678 -64.77254)
		(mid 9.105517 -64.756917)
		(end 9.12114 -64.7192)
		(stroke
			(width 0.2)
			(type default)
		)
		(layer "In1.Cu")
	)
	(gr_line
		(start 9.0678 -64.25946)
		(end 8.7122 -64.25946)
		(stroke
			(width 0.2)
			(type default)
		)
		(layer "In1.Cu")
	)
	(gr_arc
		(start 9.0678 -63.88354)
		(mid 9.105517 -63.867917)
		(end 9.12114 -63.8302)
		(stroke
			(width 0.2)
			(type default)
		)
		(layer "In1.Cu")
	)
	(gr_line
		(start 9.0678 -63.37046)
		(end 8.7122 -63.37046)
		(stroke
			(width 0.2)
			(type default)
		)
		(layer "In1.Cu")
	)
	(gr_arc
		(start 9.0678 -62.99454)
		(mid 9.105517 -62.978917)
		(end 9.12114 -62.9412)
		(stroke
			(width 0.2)
			(type default)
		)
		(layer "In1.Cu")
	)
	(gr_line
		(start 9.0678 -62.48146)
		(end 8.7122 -62.48146)
		(stroke
			(width 0.2)
			(type default)
		)
		(layer "In1.Cu")
	)
	(gr_arc
		(start 9.0678 -62.10554)
		(mid 9.105517 -62.089917)
		(end 9.12114 -62.0522)
		(stroke
			(width 0.2)
			(type default)
		)
		(layer "In1.Cu")
	)
	(gr_line
		(start 9.0678 -61.59246)
		(end 8.7122 -61.59246)
		(stroke
			(width 0.2)
			(type default)
		)
		(layer "In1.Cu")
	)
	(gr_arc
		(start 9.0678 -61.21654)
		(mid 9.105517 -61.200917)
		(end 9.12114 -61.1632)
		(stroke
			(width 0.2)
			(type default)
		)
		(layer "In1.Cu")
	)
	(gr_line
		(start 9.0678 -60.70346)
		(end 8.7122 -60.70346)
		(stroke
			(width 0.2)
			(type default)
		)
		(layer "In1.Cu")
	)
	(gr_arc
		(start 9.0678 -60.32754)
		(mid 9.105517 -60.311917)
		(end 9.12114 -60.2742)
		(stroke
			(width 0.2)
			(type default)
		)
		(layer "In1.Cu")
	)
	(gr_line
		(start 9.0678 -59.81446)
		(end 8.7122 -59.81446)
		(stroke
			(width 0.2)
			(type default)
		)
		(layer "In1.Cu")
	)
	(gr_arc
		(start 9.0678 -59.43854)
		(mid 9.105517 -59.422917)
		(end 9.12114 -59.3852)
		(stroke
			(width 0.2)
			(type default)
		)
		(layer "In1.Cu")
	)
	(gr_line
		(start 9.0678 -58.92546)
		(end 8.7122 -58.92546)
		(stroke
			(width 0.2)
			(type default)
		)
		(layer "In1.Cu")
	)
	(gr_arc
		(start 9.0678 -58.54954)
		(mid 9.105517 -58.533917)
		(end 9.12114 -58.4962)
		(stroke
			(width 0.2)
			(type default)
		)
		(layer "In1.Cu")
	)
	(gr_line
		(start 9.0678 -58.03646)
		(end 8.7122 -58.03646)
		(stroke
			(width 0.2)
			(type default)
		)
		(layer "In1.Cu")
	)
	(gr_arc
		(start 9.0678 -57.66054)
		(mid 9.105517 -57.644917)
		(end 9.12114 -57.6072)
		(stroke
			(width 0.2)
			(type default)
		)
		(layer "In1.Cu")
	)
	(gr_line
		(start 9.0678 -57.14746)
		(end 8.7122 -57.14746)
		(stroke
			(width 0.2)
			(type default)
		)
		(layer "In1.Cu")
	)
	(gr_arc
		(start 9.0678 -56.77154)
		(mid 9.105517 -56.755917)
		(end 9.12114 -56.7182)
		(stroke
			(width 0.2)
			(type default)
		)
		(layer "In1.Cu")
	)
	(gr_line
		(start 9.0678 -56.25846)
		(end 8.7122 -56.25846)
		(stroke
			(width 0.2)
			(type default)
		)
		(layer "In1.Cu")
	)
	(gr_arc
		(start 9.0678 -55.88254)
		(mid 9.105517 -55.866917)
		(end 9.12114 -55.8292)
		(stroke
			(width 0.2)
			(type default)
		)
		(layer "In1.Cu")
	)
	(gr_line
		(start 9.0678 -55.36946)
		(end 8.7122 -55.36946)
		(stroke
			(width 0.2)
			(type default)
		)
		(layer "In1.Cu")
	)
	(gr_line
		(start 9.12114 -65.6082)
		(end 9.12114 -65.2018)
		(stroke
			(width 0.2)
			(type default)
		)
		(layer "In1.Cu")
	)
	(gr_arc
		(start 9.12114 -65.2018)
		(mid 9.105517 -65.164083)
		(end 9.0678 -65.14846)
		(stroke
			(width 0.2)
			(type default)
		)
		(layer "In1.Cu")
	)
	(gr_line
		(start 9.12114 -64.7192)
		(end 9.12114 -64.3128)
		(stroke
			(width 0.2)
			(type default)
		)
		(layer "In1.Cu")
	)
	(gr_arc
		(start 9.12114 -64.3128)
		(mid 9.105517 -64.275083)
		(end 9.0678 -64.25946)
		(stroke
			(width 0.2)
			(type default)
		)
		(layer "In1.Cu")
	)
	(gr_line
		(start 9.12114 -63.8302)
		(end 9.12114 -63.4238)
		(stroke
			(width 0.2)
			(type default)
		)
		(layer "In1.Cu")
	)
	(gr_arc
		(start 9.12114 -63.4238)
		(mid 9.105517 -63.386083)
		(end 9.0678 -63.37046)
		(stroke
			(width 0.2)
			(type default)
		)
		(layer "In1.Cu")
	)
	(gr_line
		(start 9.12114 -62.9412)
		(end 9.12114 -62.5348)
		(stroke
			(width 0.2)
			(type default)
		)
		(layer "In1.Cu")
	)
	(gr_arc
		(start 9.12114 -62.5348)
		(mid 9.105517 -62.497083)
		(end 9.0678 -62.48146)
		(stroke
			(width 0.2)
			(type default)
		)
		(layer "In1.Cu")
	)
	(gr_line
		(start 9.12114 -62.0522)
		(end 9.12114 -61.6458)
		(stroke
			(width 0.2)
			(type default)
		)
		(layer "In1.Cu")
	)
	(gr_arc
		(start 9.12114 -61.6458)
		(mid 9.105517 -61.608083)
		(end 9.0678 -61.59246)
		(stroke
			(width 0.2)
			(type default)
		)
		(layer "In1.Cu")
	)
	(gr_line
		(start 9.12114 -61.1632)
		(end 9.12114 -60.7568)
		(stroke
			(width 0.2)
			(type default)
		)
		(layer "In1.Cu")
	)
	(gr_arc
		(start 9.12114 -60.7568)
		(mid 9.105517 -60.719083)
		(end 9.0678 -60.70346)
		(stroke
			(width 0.2)
			(type default)
		)
		(layer "In1.Cu")
	)
	(gr_line
		(start 9.12114 -60.2742)
		(end 9.12114 -59.8678)
		(stroke
			(width 0.2)
			(type default)
		)
		(layer "In1.Cu")
	)
	(gr_arc
		(start 9.12114 -59.8678)
		(mid 9.105517 -59.830083)
		(end 9.0678 -59.81446)
		(stroke
			(width 0.2)
			(type default)
		)
		(layer "In1.Cu")
	)
	(gr_line
		(start 9.12114 -59.3852)
		(end 9.12114 -58.9788)
		(stroke
			(width 0.2)
			(type default)
		)
		(layer "In1.Cu")
	)
	(gr_arc
		(start 9.12114 -58.9788)
		(mid 9.105517 -58.941083)
		(end 9.0678 -58.92546)
		(stroke
			(width 0.2)
			(type default)
		)
		(layer "In1.Cu")
	)
	(gr_line
		(start 9.12114 -58.4962)
		(end 9.12114 -58.0898)
		(stroke
			(width 0.2)
			(type default)
		)
		(layer "In1.Cu")
	)
	(gr_arc
		(start 9.12114 -58.0898)
		(mid 9.105517 -58.052083)
		(end 9.0678 -58.03646)
		(stroke
			(width 0.2)
			(type default)
		)
		(layer "In1.Cu")
	)
	(gr_line
		(start 9.12114 -57.6072)
		(end 9.12114 -57.2008)
		(stroke
			(width 0.2)
			(type default)
		)
		(layer "In1.Cu")
	)
	(gr_arc
		(start 9.12114 -57.2008)
		(mid 9.105517 -57.163083)
		(end 9.0678 -57.14746)
		(stroke
			(width 0.2)
			(type default)
		)
		(layer "In1.Cu")
	)
	(gr_line
		(start 9.12114 -56.7182)
		(end 9.12114 -56.3118)
		(stroke
			(width 0.2)
			(type default)
		)
		(layer "In1.Cu")
	)
	(gr_arc
		(start 9.12114 -56.3118)
		(mid 9.105517 -56.274083)
		(end 9.0678 -56.25846)
		(stroke
			(width 0.2)
			(type default)
		)
		(layer "In1.Cu")
	)
	(gr_line
		(start 9.12114 -55.8292)
		(end 9.12114 -55.4228)
		(stroke
			(width 0.2)
			(type default)
		)
		(layer "In1.Cu")
	)
	(gr_arc
		(start 9.12114 -55.4228)
		(mid 9.105517 -55.385083)
		(end 9.0678 -55.36946)
		(stroke
			(width 0.2)
			(type default)
		)
		(layer "In1.Cu")
	)
	(gr_line
		(start 9.2202 -53.8988)
		(end 9.2202 -52.908454)
		(stroke
			(width 0.2)
			(type default)
		)
		(layer "In1.Cu")
	)
	(gr_arc
		(start 9.2202 -52.908454)
		(mid 8.839327 -52.5272)
		(end 8.4582 -52.9082)
		(stroke
			(width 0.2)
			(type default)
		)
		(layer "In1.Cu")
	)
	(gr_line
		(start 9.240774 -62.748922)
		(end 9.266174 -63.637668)
		(stroke
			(width 0.2)
			(type default)
		)
		(layer "In1.Cu")
	)
	(gr_line
		(start 9.240774 -59.192922)
		(end 9.266174 -60.081668)
		(stroke
			(width 0.2)
			(type default)
		)
		(layer "In1.Cu")
	)
	(gr_arc
		(start 9.24306 -65.405)
		(mid 9.6266 -65.78854)
		(end 10.01014 -65.405)
		(stroke
			(width 0.2)
			(type default)
		)
		(layer "In1.Cu")
	)
	(gr_line
		(start 9.24306 -64.516)
		(end 9.24306 -65.405)
		(stroke
			(width 0.2)
			(type default)
		)
		(layer "In1.Cu")
	)
	(gr_arc
		(start 9.24306 -61.849)
		(mid 9.6266 -62.23254)
		(end 10.01014 -61.849)
		(stroke
			(width 0.2)
			(type default)
		)
		(layer "In1.Cu")
	)
	(gr_line
		(start 9.24306 -60.96)
		(end 9.24306 -61.849)
		(stroke
			(width 0.2)
			(type default)
		)
		(layer "In1.Cu")
	)
	(gr_arc
		(start 9.24306 -58.293)
		(mid 9.6266 -58.67654)
		(end 10.01014 -58.293)
		(stroke
			(width 0.2)
			(type default)
		)
		(layer "In1.Cu")
	)
	(gr_line
		(start 9.24306 -57.404)
		(end 9.24306 -58.293)
		(stroke
			(width 0.2)
			(type default)
		)
		(layer "In1.Cu")
	)
	(gr_arc
		(start 9.24306 -56.515)
		(mid 9.6266 -56.89854)
		(end 10.01014 -56.515)
		(stroke
			(width 0.2)
			(type default)
		)
		(layer "In1.Cu")
	)
	(gr_line
		(start 9.24306 -55.626)
		(end 9.24306 -56.515)
		(stroke
			(width 0.2)
			(type default)
		)
		(layer "In1.Cu")
	)
	(gr_line
		(start 9.243314 -62.748922)
		(end 9.240774 -62.748922)
		(stroke
			(width 0.2)
			(type default)
		)
		(layer "In1.Cu")
	)
	(gr_line
		(start 9.243314 -59.192922)
		(end 9.240774 -59.192922)
		(stroke
			(width 0.2)
			(type default)
		)
		(layer "In1.Cu")
	)
	(gr_line
		(start 9.266174 -63.637668)
		(end 9.266428 -63.637922)
		(stroke
			(width 0.2)
			(type default)
		)
		(layer "In1.Cu")
	)
	(gr_line
		(start 9.266174 -60.081668)
		(end 9.266428 -60.081922)
		(stroke
			(width 0.2)
			(type default)
		)
		(layer "In1.Cu")
	)
	(gr_line
		(start 9.266428 -63.637922)
		(end 9.268714 -63.637922)
		(stroke
			(width 0.2)
			(type default)
		)
		(layer "In1.Cu")
	)
	(gr_line
		(start 9.266428 -60.081922)
		(end 9.268714 -60.081922)
		(stroke
			(width 0.2)
			(type default)
		)
		(layer "In1.Cu")
	)
	(gr_arc
		(start 9.268714 -63.637922)
		(mid 9.662922 -64.010286)
		(end 10.035286 -63.616078)
		(stroke
			(width 0.2)
			(type default)
		)
		(layer "In1.Cu")
	)
	(gr_arc
		(start 9.268714 -60.081922)
		(mid 9.662922 -60.454286)
		(end 10.035286 -60.060078)
		(stroke
			(width 0.2)
			(type default)
		)
		(layer "In1.Cu")
	)
	(gr_circle
		(center 9.5504 -51.7398)
		(end 9.90854 -51.7398)
		(stroke
			(width 0.2)
			(type default)
		)
		(fill no)
		(layer "In1.Cu")
	)
	(gr_circle
		(center 9.5504 -50.4952)
		(end 9.90854 -50.4952)
		(stroke
			(width 0.2)
			(type default)
		)
		(fill no)
		(layer "In1.Cu")
	)
	(gr_arc
		(start 10.009886 -62.727078)
		(mid 9.615678 -62.354714)
		(end 9.243314 -62.748922)
		(stroke
			(width 0.2)
			(type default)
		)
		(layer "In1.Cu")
	)
	(gr_arc
		(start 10.009886 -59.171078)
		(mid 9.615678 -58.798714)
		(end 9.243314 -59.192922)
		(stroke
			(width 0.2)
			(type default)
		)
		(layer "In1.Cu")
	)
	(gr_line
		(start 10.01014 -65.405)
		(end 10.01014 -64.516254)
		(stroke
			(width 0.2)
			(type default)
		)
		(layer "In1.Cu")
	)
	(gr_arc
		(start 10.01014 -64.516254)
		(mid 9.626727 -64.13246)
		(end 9.24306 -64.516)
		(stroke
			(width 0.2)
			(type default)
		)
		(layer "In1.Cu")
	)
	(gr_line
		(start 10.01014 -61.849)
		(end 10.01014 -60.960254)
		(stroke
			(width 0.2)
			(type default)
		)
		(layer "In1.Cu")
	)
	(gr_arc
		(start 10.01014 -60.960254)
		(mid 9.626727 -60.57646)
		(end 9.24306 -60.96)
		(stroke
			(width 0.2)
			(type default)
		)
		(layer "In1.Cu")
	)
	(gr_line
		(start 10.01014 -58.293)
		(end 10.01014 -57.404254)
		(stroke
			(width 0.2)
			(type default)
		)
		(layer "In1.Cu")
	)
	(gr_arc
		(start 10.01014 -57.404254)
		(mid 9.626727 -57.02046)
		(end 9.24306 -57.404)
		(stroke
			(width 0.2)
			(type default)
		)
		(layer "In1.Cu")
	)
	(gr_line
		(start 10.01014 -56.515)
		(end 10.01014 -55.626254)
		(stroke
			(width 0.2)
			(type default)
		)
		(layer "In1.Cu")
	)
	(gr_arc
		(start 10.01014 -55.626254)
		(mid 9.626727 -55.24246)
		(end 9.24306 -55.626)
		(stroke
			(width 0.2)
			(type default)
		)
		(layer "In1.Cu")
	)
	(gr_line
		(start 10.012426 -62.727078)
		(end 10.009886 -62.727078)
		(stroke
			(width 0.2)
			(type default)
		)
		(layer "In1.Cu")
	)
	(gr_line
		(start 10.012426 -59.171078)
		(end 10.009886 -59.171078)
		(stroke
			(width 0.2)
			(type default)
		)
		(layer "In1.Cu")
	)
	(gr_line
		(start 10.035286 -63.616078)
		(end 10.037826 -63.616078)
		(stroke
			(width 0.2)
			(type default)
		)
		(layer "In1.Cu")
	)
	(gr_line
		(start 10.035286 -60.060078)
		(end 10.037826 -60.060078)
		(stroke
			(width 0.2)
			(type default)
		)
		(layer "In1.Cu")
	)
	(gr_line
		(start 10.037826 -63.616078)
		(end 10.012426 -62.727078)
		(stroke
			(width 0.2)
			(type default)
		)
		(layer "In1.Cu")
	)
	(gr_line
		(start 10.037826 -60.060078)
		(end 10.012426 -59.171078)
		(stroke
			(width 0.2)
			(type default)
		)
		(layer "In1.Cu")
	)
	(gr_arc
		(start 10.05586 -51.943)
		(mid 10.071483 -51.980717)
		(end 10.1092 -51.99634)
		(stroke
			(width 0.2)
			(type default)
		)
		(layer "In1.Cu")
	)
	(gr_line
		(start 10.05586 -51.5366)
		(end 10.05586 -51.943)
		(stroke
			(width 0.2)
			(type default)
		)
		(layer "In1.Cu")
	)
	(gr_arc
		(start 10.05586 -50.6984)
		(mid 10.071483 -50.736117)
		(end 10.1092 -50.75174)
		(stroke
			(width 0.2)
			(type default)
		)
		(layer "In1.Cu")
	)
	(gr_line
		(start 10.05586 -50.292)
		(end 10.05586 -50.6984)
		(stroke
			(width 0.2)
			(type default)
		)
		(layer "In1.Cu")
	)
	(gr_line
		(start 10.1092 -51.99634)
		(end 10.4648 -51.99634)
		(stroke
			(width 0.2)
			(type default)
		)
		(layer "In1.Cu")
	)
	(gr_arc
		(start 10.1092 -51.48326)
		(mid 10.071483 -51.498883)
		(end 10.05586 -51.5366)
		(stroke
			(width 0.2)
			(type default)
		)
		(layer "In1.Cu")
	)
	(gr_line
		(start 10.1092 -50.75174)
		(end 10.4648 -50.75174)
		(stroke
			(width 0.2)
			(type default)
		)
		(layer "In1.Cu")
	)
	(gr_arc
		(start 10.1092 -50.23866)
		(mid 10.071483 -50.254283)
		(end 10.05586 -50.292)
		(stroke
			(width 0.2)
			(type default)
		)
		(layer "In1.Cu")
	)
	(gr_circle
		(center 10.2616 -54.0258)
		(end 10.61974 -54.0258)
		(stroke
			(width 0.2)
			(type default)
		)
		(fill no)
		(layer "In1.Cu")
	)
	(gr_circle
		(center 10.2616 -52.7812)
		(end 10.61974 -52.7812)
		(stroke
			(width 0.2)
			(type default)
		)
		(fill no)
		(layer "In1.Cu")
	)
	(gr_arc
		(start 10.4648 -51.99634)
		(mid 10.502517 -51.980717)
		(end 10.51814 -51.943)
		(stroke
			(width 0.2)
			(type default)
		)
		(layer "In1.Cu")
	)
	(gr_line
		(start 10.4648 -51.48326)
		(end 10.1092 -51.48326)
		(stroke
			(width 0.2)
			(type default)
		)
		(layer "In1.Cu")
	)
	(gr_arc
		(start 10.4648 -50.75174)
		(mid 10.502517 -50.736117)
		(end 10.51814 -50.6984)
		(stroke
			(width 0.2)
			(type default)
		)
		(layer "In1.Cu")
	)
	(gr_line
		(start 10.4648 -50.23866)
		(end 10.1092 -50.23866)
		(stroke
			(width 0.2)
			(type default)
		)
		(layer "In1.Cu")
	)
	(gr_line
		(start 10.51814 -51.943)
		(end 10.51814 -51.5366)
		(stroke
			(width 0.2)
			(type default)
		)
		(layer "In1.Cu")
	)
	(gr_arc
		(start 10.51814 -51.5366)
		(mid 10.502517 -51.498883)
		(end 10.4648 -51.48326)
		(stroke
			(width 0.2)
			(type default)
		)
		(layer "In1.Cu")
	)
	(gr_line
		(start 10.51814 -50.6984)
		(end 10.51814 -50.292)
		(stroke
			(width 0.2)
			(type default)
		)
		(layer "In1.Cu")
	)
	(gr_arc
		(start 10.51814 -50.292)
		(mid 10.502517 -50.254283)
		(end 10.4648 -50.23866)
		(stroke
			(width 0.2)
			(type default)
		)
		(layer "In1.Cu")
	)
	(gr_arc
		(start 10.76706 -54.229)
		(mid 10.782683 -54.266717)
		(end 10.8204 -54.28234)
		(stroke
			(width 0.2)
			(type default)
		)
		(layer "In1.Cu")
	)
	(gr_line
		(start 10.76706 -53.8226)
		(end 10.76706 -54.229)
		(stroke
			(width 0.2)
			(type default)
		)
		(layer "In1.Cu")
	)
	(gr_arc
		(start 10.76706 -52.9844)
		(mid 10.782683 -53.022117)
		(end 10.8204 -53.03774)
		(stroke
			(width 0.2)
			(type default)
		)
		(layer "In1.Cu")
	)
	(gr_line
		(start 10.76706 -52.578)
		(end 10.76706 -52.9844)
		(stroke
			(width 0.2)
			(type default)
		)
		(layer "In1.Cu")
	)
	(gr_arc
		(start 10.81786 -51.943)
		(mid 10.833483 -51.980717)
		(end 10.8712 -51.99634)
		(stroke
			(width 0.2)
			(type default)
		)
		(layer "In1.Cu")
	)
	(gr_line
		(start 10.81786 -51.5366)
		(end 10.81786 -51.943)
		(stroke
			(width 0.2)
			(type default)
		)
		(layer "In1.Cu")
	)
	(gr_arc
		(start 10.81786 -50.6984)
		(mid 10.833483 -50.736117)
		(end 10.8712 -50.75174)
		(stroke
			(width 0.2)
			(type default)
		)
		(layer "In1.Cu")
	)
	(gr_line
		(start 10.81786 -50.292)
		(end 10.81786 -50.6984)
		(stroke
			(width 0.2)
			(type default)
		)
		(layer "In1.Cu")
	)
	(gr_line
		(start 10.8204 -54.28234)
		(end 11.176 -54.28234)
		(stroke
			(width 0.2)
			(type default)
		)
		(layer "In1.Cu")
	)
	(gr_arc
		(start 10.8204 -53.76926)
		(mid 10.782683 -53.784883)
		(end 10.76706 -53.8226)
		(stroke
			(width 0.2)
			(type default)
		)
		(layer "In1.Cu")
	)
	(gr_line
		(start 10.8204 -53.03774)
		(end 11.176 -53.03774)
		(stroke
			(width 0.2)
			(type default)
		)
		(layer "In1.Cu")
	)
	(gr_arc
		(start 10.8204 -52.52466)
		(mid 10.782683 -52.540283)
		(end 10.76706 -52.578)
		(stroke
			(width 0.2)
			(type default)
		)
		(layer "In1.Cu")
	)
	(gr_line
		(start 10.8712 -51.99634)
		(end 11.2268 -51.99634)
		(stroke
			(width 0.2)
			(type default)
		)
		(layer "In1.Cu")
	)
	(gr_arc
		(start 10.8712 -51.48326)
		(mid 10.833483 -51.498883)
		(end 10.81786 -51.5366)
		(stroke
			(width 0.2)
			(type default)
		)
		(layer "In1.Cu")
	)
	(gr_line
		(start 10.8712 -50.75174)
		(end 11.2268 -50.75174)
		(stroke
			(width 0.2)
			(type default)
		)
		(layer "In1.Cu")
	)
	(gr_arc
		(start 10.8712 -50.23866)
		(mid 10.833483 -50.254283)
		(end 10.81786 -50.292)
		(stroke
			(width 0.2)
			(type default)
		)
		(layer "In1.Cu")
	)
	(gr_arc
		(start 11.176 -54.28234)
		(mid 11.213717 -54.266717)
		(end 11.22934 -54.229)
		(stroke
			(width 0.2)
			(type default)
		)
		(layer "In1.Cu")
	)
	(gr_line
		(start 11.176 -53.76926)
		(end 10.8204 -53.76926)
		(stroke
			(width 0.2)
			(type default)
		)
		(layer "In1.Cu")
	)
	(gr_arc
		(start 11.176 -53.03774)
		(mid 11.213717 -53.022117)
		(end 11.22934 -52.9844)
		(stroke
			(width 0.2)
			(type default)
		)
		(layer "In1.Cu")
	)
	(gr_line
		(start 11.176 -52.52466)
		(end 10.8204 -52.52466)
		(stroke
			(width 0.2)
			(type default)
		)
		(layer "In1.Cu")
	)
	(gr_arc
		(start 11.2268 -51.99634)
		(mid 11.264517 -51.980717)
		(end 11.28014 -51.943)
		(stroke
			(width 0.2)
			(type default)
		)
		(layer "In1.Cu")
	)
	(gr_line
		(start 11.2268 -51.48326)
		(end 10.8712 -51.48326)
		(stroke
			(width 0.2)
			(type default)
		)
		(layer "In1.Cu")
	)
	(gr_arc
		(start 11.2268 -50.75174)
		(mid 11.264517 -50.736117)
		(end 11.28014 -50.6984)
		(stroke
			(width 0.2)
			(type default)
		)
		(layer "In1.Cu")
	)
	(gr_line
		(start 11.2268 -50.23866)
		(end 10.8712 -50.23866)
		(stroke
			(width 0.2)
			(type default)
		)
		(layer "In1.Cu")
	)
	(gr_line
		(start 11.22934 -54.229)
		(end 11.22934 -53.8226)
		(stroke
			(width 0.2)
			(type default)
		)
		(layer "In1.Cu")
	)
	(gr_arc
		(start 11.22934 -53.8226)
		(mid 11.213717 -53.784883)
		(end 11.176 -53.76926)
		(stroke
			(width 0.2)
			(type default)
		)
		(layer "In1.Cu")
	)
	(gr_line
		(start 11.22934 -52.9844)
		(end 11.22934 -52.578)
		(stroke
			(width 0.2)
			(type default)
		)
		(layer "In1.Cu")
	)
	(gr_arc
		(start 11.22934 -52.578)
		(mid 11.213717 -52.540283)
		(end 11.176 -52.52466)
		(stroke
			(width 0.2)
			(type default)
		)
		(layer "In1.Cu")
	)
	(gr_line
		(start 11.28014 -51.943)
		(end 11.28014 -51.5366)
		(stroke
			(width 0.2)
			(type default)
		)
		(layer "In1.Cu")
	)
	(gr_arc
		(start 11.28014 -51.5366)
		(mid 11.264517 -51.498883)
		(end 11.2268 -51.48326)
		(stroke
			(width 0.2)
			(type default)
		)
		(layer "In1.Cu")
	)
	(gr_line
		(start 11.28014 -50.6984)
		(end 11.28014 -50.292)
		(stroke
			(width 0.2)
			(type default)
		)
		(layer "In1.Cu")
	)
	(gr_arc
		(start 11.28014 -50.292)
		(mid 11.264517 -50.254283)
		(end 11.2268 -50.23866)
		(stroke
			(width 0.2)
			(type default)
		)
		(layer "In1.Cu")
	)
	(gr_arc
		(start 11.52906 -54.229)
		(mid 11.544683 -54.266717)
		(end 11.5824 -54.28234)
		(stroke
			(width 0.2)
			(type default)
		)
		(layer "In1.Cu")
	)
	(gr_line
		(start 11.52906 -53.8226)
		(end 11.52906 -54.229)
		(stroke
			(width 0.2)
			(type default)
		)
		(layer "In1.Cu")
	)
	(gr_arc
		(start 11.52906 -52.9844)
		(mid 11.544683 -53.022117)
		(end 11.5824 -53.03774)
		(stroke
			(width 0.2)
			(type default)
		)
		(layer "In1.Cu")
	)
	(gr_line
		(start 11.52906 -52.578)
		(end 11.52906 -52.9844)
		(stroke
			(width 0.2)
			(type default)
		)
		(layer "In1.Cu")
	)
	(gr_arc
		(start 11.57986 -51.943)
		(mid 11.595483 -51.980717)
		(end 11.6332 -51.99634)
		(stroke
			(width 0.2)
			(type default)
		)
		(layer "In1.Cu")
	)
	(gr_line
		(start 11.57986 -51.5366)
		(end 11.57986 -51.943)
		(stroke
			(width 0.2)
			(type default)
		)
		(layer "In1.Cu")
	)
	(gr_arc
		(start 11.57986 -50.6984)
		(mid 11.595483 -50.736117)
		(end 11.6332 -50.75174)
		(stroke
			(width 0.2)
			(type default)
		)
		(layer "In1.Cu")
	)
	(gr_line
		(start 11.57986 -50.292)
		(end 11.57986 -50.6984)
		(stroke
			(width 0.2)
			(type default)
		)
		(layer "In1.Cu")
	)
	(gr_line
		(start 11.5824 -54.28234)
		(end 11.938 -54.28234)
		(stroke
			(width 0.2)
			(type default)
		)
		(layer "In1.Cu")
	)
	(gr_arc
		(start 11.5824 -53.76926)
		(mid 11.544683 -53.784883)
		(end 11.52906 -53.8226)
		(stroke
			(width 0.2)
			(type default)
		)
		(layer "In1.Cu")
	)
	(gr_line
		(start 11.5824 -53.03774)
		(end 11.938 -53.03774)
		(stroke
			(width 0.2)
			(type default)
		)
		(layer "In1.Cu")
	)
	(gr_arc
		(start 11.5824 -52.52466)
		(mid 11.544683 -52.540283)
		(end 11.52906 -52.578)
		(stroke
			(width 0.2)
			(type default)
		)
		(layer "In1.Cu")
	)
	(gr_line
		(start 11.6332 -51.99634)
		(end 11.9888 -51.99634)
		(stroke
			(width 0.2)
			(type default)
		)
		(layer "In1.Cu")
	)
	(gr_arc
		(start 11.6332 -51.48326)
		(mid 11.595483 -51.498883)
		(end 11.57986 -51.5366)
		(stroke
			(width 0.2)
			(type default)
		)
		(layer "In1.Cu")
	)
	(gr_line
		(start 11.6332 -50.75174)
		(end 11.9888 -50.75174)
		(stroke
			(width 0.2)
			(type default)
		)
		(layer "In1.Cu")
	)
	(gr_arc
		(start 11.6332 -50.23866)
		(mid 11.595483 -50.254283)
		(end 11.57986 -50.292)
		(stroke
			(width 0.2)
			(type default)
		)
		(layer "In1.Cu")
	)
	(gr_arc
		(start 11.938 -54.28234)
		(mid 11.975717 -54.266717)
		(end 11.99134 -54.229)
		(stroke
			(width 0.2)
			(type default)
		)
		(layer "In1.Cu")
	)
	(gr_line
		(start 11.938 -53.76926)
		(end 11.5824 -53.76926)
		(stroke
			(width 0.2)
			(type default)
		)
		(layer "In1.Cu")
	)
	(gr_arc
		(start 11.938 -53.03774)
		(mid 11.975717 -53.022117)
		(end 11.99134 -52.9844)
		(stroke
			(width 0.2)
			(type default)
		)
		(layer "In1.Cu")
	)
	(gr_line
		(start 11.938 -52.52466)
		(end 11.5824 -52.52466)
		(stroke
			(width 0.2)
			(type default)
		)
		(layer "In1.Cu")
	)
	(gr_arc
		(start 11.9888 -51.99634)
		(mid 12.026517 -51.980717)
		(end 12.04214 -51.943)
		(stroke
			(width 0.2)
			(type default)
		)
		(layer "In1.Cu")
	)
	(gr_line
		(start 11.9888 -51.48326)
		(end 11.6332 -51.48326)
		(stroke
			(width 0.2)
			(type default)
		)
		(layer "In1.Cu")
	)
	(gr_arc
		(start 11.9888 -50.75174)
		(mid 12.026517 -50.736117)
		(end 12.04214 -50.6984)
		(stroke
			(width 0.2)
			(type default)
		)
		(layer "In1.Cu")
	)
	(gr_line
		(start 11.9888 -50.23866)
		(end 11.6332 -50.23866)
		(stroke
			(width 0.2)
			(type default)
		)
		(layer "In1.Cu")
	)
	(gr_line
		(start 11.99134 -54.229)
		(end 11.99134 -53.8226)
		(stroke
			(width 0.2)
			(type default)
		)
		(layer "In1.Cu")
	)
	(gr_arc
		(start 11.99134 -53.8226)
		(mid 11.975717 -53.784883)
		(end 11.938 -53.76926)
		(stroke
			(width 0.2)
			(type default)
		)
		(layer "In1.Cu")
	)
	(gr_line
		(start 11.99134 -52.9844)
		(end 11.99134 -52.578)
		(stroke
			(width 0.2)
			(type default)
		)
		(layer "In1.Cu")
	)
	(gr_arc
		(start 11.99134 -52.578)
		(mid 11.975717 -52.540283)
		(end 11.938 -52.52466)
		(stroke
			(width 0.2)
			(type default)
		)
		(layer "In1.Cu")
	)
	(gr_line
		(start 12.04214 -51.943)
		(end 12.04214 -51.5366)
		(stroke
			(width 0.2)
			(type default)
		)
		(layer "In1.Cu")
	)
	(gr_arc
		(start 12.04214 -51.5366)
		(mid 12.026517 -51.498883)
		(end 11.9888 -51.48326)
		(stroke
			(width 0.2)
			(type default)
		)
		(layer "In1.Cu")
	)
	(gr_line
		(start 12.04214 -50.6984)
		(end 12.04214 -50.292)
		(stroke
			(width 0.2)
			(type default)
		)
		(layer "In1.Cu")
	)
	(gr_arc
		(start 12.04214 -50.292)
		(mid 12.026517 -50.254283)
		(end 11.9888 -50.23866)
		(stroke
			(width 0.2)
			(type default)
		)
		(layer "In1.Cu")
	)
	(gr_arc
		(start 12.29106 -54.229)
		(mid 12.306683 -54.266717)
		(end 12.3444 -54.28234)
		(stroke
			(width 0.2)
			(type default)
		)
		(layer "In1.Cu")
	)
	(gr_line
		(start 12.29106 -53.8226)
		(end 12.29106 -54.229)
		(stroke
			(width 0.2)
			(type default)
		)
		(layer "In1.Cu")
	)
	(gr_arc
		(start 12.29106 -52.9844)
		(mid 12.306683 -53.022117)
		(end 12.3444 -53.03774)
		(stroke
			(width 0.2)
			(type default)
		)
		(layer "In1.Cu")
	)
	(gr_line
		(start 12.29106 -52.578)
		(end 12.29106 -52.9844)
		(stroke
			(width 0.2)
			(type default)
		)
		(layer "In1.Cu")
	)
	(gr_line
		(start 12.3444 -54.28234)
		(end 12.7 -54.28234)
		(stroke
			(width 0.2)
			(type default)
		)
		(layer "In1.Cu")
	)
	(gr_arc
		(start 12.3444 -53.76926)
		(mid 12.306683 -53.784883)
		(end 12.29106 -53.8226)
		(stroke
			(width 0.2)
			(type default)
		)
		(layer "In1.Cu")
	)
	(gr_line
		(start 12.3444 -53.03774)
		(end 12.7 -53.03774)
		(stroke
			(width 0.2)
			(type default)
		)
		(layer "In1.Cu")
	)
	(gr_arc
		(start 12.3444 -52.52466)
		(mid 12.306683 -52.540283)
		(end 12.29106 -52.578)
		(stroke
			(width 0.2)
			(type default)
		)
		(layer "In1.Cu")
	)
	(gr_arc
		(start 12.7 -54.28234)
		(mid 12.737717 -54.266717)
		(end 12.75334 -54.229)
		(stroke
			(width 0.2)
			(type default)
		)
		(layer "In1.Cu")
	)
	(gr_line
		(start 12.7 -53.76926)
		(end 12.3444 -53.76926)
		(stroke
			(width 0.2)
			(type default)
		)
		(layer "In1.Cu")
	)
	(gr_arc
		(start 12.7 -53.03774)
		(mid 12.737717 -53.022117)
		(end 12.75334 -52.9844)
		(stroke
			(width 0.2)
			(type default)
		)
		(layer "In1.Cu")
	)
	(gr_line
		(start 12.7 -52.52466)
		(end 12.3444 -52.52466)
		(stroke
			(width 0.2)
			(type default)
		)
		(layer "In1.Cu")
	)
	(gr_line
		(start 12.75334 -54.229)
		(end 12.75334 -53.8226)
		(stroke
			(width 0.2)
			(type default)
		)
		(layer "In1.Cu")
	)
	(gr_arc
		(start 12.75334 -53.8226)
		(mid 12.737717 -53.784883)
		(end 12.7 -53.76926)
		(stroke
			(width 0.2)
			(type default)
		)
		(layer "In1.Cu")
	)
	(gr_line
		(start 12.75334 -52.9844)
		(end 12.75334 -52.578)
		(stroke
			(width 0.2)
			(type default)
		)
		(layer "In1.Cu")
	)
	(gr_arc
		(start 12.75334 -52.578)
		(mid 12.737717 -52.540283)
		(end 12.7 -52.52466)
		(stroke
			(width 0.2)
			(type default)
		)
		(layer "In1.Cu")
	)
	(gr_arc
		(start 12.7889 -48.617886)
		(mid 13.172313 -49.00168)
		(end 13.55598 -48.61814)
		(stroke
			(width 0.2)
			(type default)
		)
		(layer "In1.Cu")
	)
	(gr_line
		(start 12.7889 -47.66056)
		(end 12.7889 -48.617886)
		(stroke
			(width 0.2)
			(type default)
		)
		(layer "In1.Cu")
	)
	(gr_line
		(start 13.55598 -48.61814)
		(end 13.55598 -47.66056)
		(stroke
			(width 0.2)
			(type default)
		)
		(layer "In1.Cu")
	)
	(gr_arc
		(start 13.55598 -47.66056)
		(mid 13.17244 -47.27702)
		(end 12.7889 -47.66056)
		(stroke
			(width 0.2)
			(type default)
		)
		(layer "In1.Cu")
	)
	(gr_line
		(start 14.15288 -47.21606)
		(end 15.082266 -47.21606)
		(stroke
			(width 0.2)
			(type default)
		)
		(layer "In1.Cu")
	)
	(gr_arc
		(start 14.153134 -46.44898)
		(mid 13.76934 -46.832393)
		(end 14.15288 -47.21606)
		(stroke
			(width 0.2)
			(type default)
		)
		(layer "In1.Cu")
	)
	(gr_arc
		(start 15.082266 -47.21606)
		(mid 15.465806 -46.83252)
		(end 15.082266 -46.44898)
		(stroke
			(width 0.2)
			(type default)
		)
		(layer "In1.Cu")
	)
	(gr_line
		(start 15.082266 -46.44898)
		(end 14.153134 -46.44898)
		(stroke
			(width 0.2)
			(type default)
		)
		(layer "In1.Cu")
	)
	(gr_rect
		(start 18.991834 -4.097528)
		(end 19.708114 -8.293608)
		(stroke
			(width 0)
			(type default)
		)
		(fill no)
		(layer "In1.Cu")
	)
	(gr_line
		(start 19.408394 -10.634218)
		(end 20.327874 -10.634218)
		(stroke
			(width 0.2)
			(type default)
		)
		(layer "In1.Cu")
	)
	(gr_arc
		(start 19.408648 -9.867138)
		(mid 19.024854 -10.250551)
		(end 19.408394 -10.634218)
		(stroke
			(width 0.2)
			(type default)
		)
		(layer "In1.Cu")
	)
	(gr_rect
		(start 19.991832 -4.097528)
		(end 20.708112 -8.293608)
		(stroke
			(width 0)
			(type default)
		)
		(fill no)
		(layer "In1.Cu")
	)
	(gr_line
		(start 20.09521 -15.872206)
		(end 21.052536 -15.872206)
		(stroke
			(width 0.2)
			(type default)
		)
		(layer "In1.Cu")
	)
	(gr_arc
		(start 20.09521 -15.105126)
		(mid 19.71167 -15.488666)
		(end 20.09521 -15.872206)
		(stroke
			(width 0.2)
			(type default)
		)
		(layer "In1.Cu")
	)
	(gr_arc
		(start 20.327874 -10.634218)
		(mid 20.711414 -10.250678)
		(end 20.327874 -9.867138)
		(stroke
			(width 0.2)
			(type default)
		)
		(layer "In1.Cu")
	)
	(gr_line
		(start 20.327874 -9.867138)
		(end 19.408648 -9.867138)
		(stroke
			(width 0.2)
			(type default)
		)
		(layer "In1.Cu")
	)
	(gr_arc
		(start 21.052536 -15.872206)
		(mid 21.43633 -15.488793)
		(end 21.05279 -15.105126)
		(stroke
			(width 0.2)
			(type default)
		)
		(layer "In1.Cu")
	)
	(gr_line
		(start 21.05279 -15.105126)
		(end 20.09521 -15.105126)
		(stroke
			(width 0.2)
			(type default)
		)
		(layer "In1.Cu")
	)
	(gr_line
		(start 21.6662 -14.20114)
		(end 22.5298 -14.20114)
		(stroke
			(width 0.2)
			(type default)
		)
		(layer "In1.Cu")
	)
	(gr_arc
		(start 21.666454 -13.43406)
		(mid 21.28266 -13.817473)
		(end 21.6662 -14.20114)
		(stroke
			(width 0.2)
			(type default)
		)
		(layer "In1.Cu")
	)
	(gr_arc
		(start 22.5298 -14.20114)
		(mid 22.91334 -13.8176)
		(end 22.5298 -13.43406)
		(stroke
			(width 0.2)
			(type default)
		)
		(layer "In1.Cu")
	)
	(gr_line
		(start 22.5298 -13.43406)
		(end 21.666454 -13.43406)
		(stroke
			(width 0.2)
			(type default)
		)
		(layer "In1.Cu")
	)
	(gr_rect
		(start 22.991826 -4.097528)
		(end 23.708106 -8.293608)
		(stroke
			(width 0)
			(type default)
		)
		(fill no)
		(layer "In1.Cu")
	)
	(gr_line
		(start 23.408386 -10.634218)
		(end 24.327866 -10.634218)
		(stroke
			(width 0.2)
			(type default)
		)
		(layer "In1.Cu")
	)
	(gr_arc
		(start 23.40864 -9.867138)
		(mid 23.024846 -10.250551)
		(end 23.408386 -10.634218)
		(stroke
			(width 0.2)
			(type default)
		)
		(layer "In1.Cu")
	)
	(gr_rect
		(start 23.991824 -4.097528)
		(end 24.708104 -8.293608)
		(stroke
			(width 0)
			(type default)
		)
		(fill no)
		(layer "In1.Cu")
	)
	(gr_arc
		(start 24.327866 -10.634218)
		(mid 24.711406 -10.250678)
		(end 24.327866 -9.867138)
		(stroke
			(width 0.2)
			(type default)
		)
		(layer "In1.Cu")
	)
	(gr_line
		(start 24.327866 -9.867138)
		(end 23.40864 -9.867138)
		(stroke
			(width 0.2)
			(type default)
		)
		(layer "In1.Cu")
	)
	(gr_line
		(start 25.4127 -14.20114)
		(end 26.276046 -14.20114)
		(stroke
			(width 0.2)
			(type default)
		)
		(layer "In1.Cu")
	)
	(gr_arc
		(start 25.4127 -13.43406)
		(mid 25.02916 -13.8176)
		(end 25.4127 -14.20114)
		(stroke
			(width 0.2)
			(type default)
		)
		(layer "In1.Cu")
	)
	(gr_arc
		(start 26.276046 -14.20114)
		(mid 26.65984 -13.817727)
		(end 26.2763 -13.43406)
		(stroke
			(width 0.2)
			(type default)
		)
		(layer "In1.Cu")
	)
	(gr_line
		(start 26.2763 -13.43406)
		(end 25.4127 -13.43406)
		(stroke
			(width 0.2)
			(type default)
		)
		(layer "In1.Cu")
	)
	(gr_rect
		(start 26.991818 -4.097528)
		(end 27.708098 -8.293608)
		(stroke
			(width 0)
			(type default)
		)
		(fill no)
		(layer "In1.Cu")
	)
	(gr_line
		(start 27.408378 -10.634218)
		(end 28.327604 -10.634218)
		(stroke
			(width 0.2)
			(type default)
		)
		(layer "In1.Cu")
	)
	(gr_arc
		(start 27.408378 -9.867138)
		(mid 27.024838 -10.250678)
		(end 27.408378 -10.634218)
		(stroke
			(width 0.2)
			(type default)
		)
		(layer "In1.Cu")
	)
	(gr_rect
		(start 27.991816 -4.097528)
		(end 28.708096 -8.293608)
		(stroke
			(width 0)
			(type default)
		)
		(fill no)
		(layer "In1.Cu")
	)
	(gr_arc
		(start 28.327604 -10.634218)
		(mid 28.711398 -10.250805)
		(end 28.327858 -9.867138)
		(stroke
			(width 0.2)
			(type default)
		)
		(layer "In1.Cu")
	)
	(gr_line
		(start 28.327858 -9.867138)
		(end 27.408378 -9.867138)
		(stroke
			(width 0.2)
			(type default)
		)
		(layer "In1.Cu")
	)
	(gr_line
		(start 29.4132 -14.96314)
		(end 30.276546 -14.96314)
		(stroke
			(width 0.2)
			(type default)
		)
		(layer "In1.Cu")
	)
	(gr_arc
		(start 29.4132 -14.19606)
		(mid 29.02966 -14.5796)
		(end 29.4132 -14.96314)
		(stroke
			(width 0.2)
			(type default)
		)
		(layer "In1.Cu")
	)
	(gr_arc
		(start 30.276546 -14.96314)
		(mid 30.66034 -14.579727)
		(end 30.2768 -14.19606)
		(stroke
			(width 0.2)
			(type default)
		)
		(layer "In1.Cu")
	)
	(gr_line
		(start 30.2768 -14.19606)
		(end 29.4132 -14.19606)
		(stroke
			(width 0.2)
			(type default)
		)
		(layer "In1.Cu")
	)
	(gr_rect
		(start 30.99181 -4.097528)
		(end 31.70809 -8.293608)
		(stroke
			(width 0)
			(type default)
		)
		(fill no)
		(layer "In1.Cu")
	)
	(gr_line
		(start 31.40837 -10.634218)
		(end 32.327596 -10.634218)
		(stroke
			(width 0.2)
			(type default)
		)
		(layer "In1.Cu")
	)
	(gr_arc
		(start 31.40837 -9.867138)
		(mid 31.02483 -10.250678)
		(end 31.40837 -10.634218)
		(stroke
			(width 0.2)
			(type default)
		)
		(layer "In1.Cu")
	)
	(gr_rect
		(start 31.991808 -4.097528)
		(end 32.708088 -8.293608)
		(stroke
			(width 0)
			(type default)
		)
		(fill no)
		(layer "In1.Cu")
	)
	(gr_arc
		(start 32.327596 -10.634218)
		(mid 32.71139 -10.250805)
		(end 32.32785 -9.867138)
		(stroke
			(width 0.2)
			(type default)
		)
		(layer "In1.Cu")
	)
	(gr_line
		(start 32.32785 -9.867138)
		(end 31.40837 -9.867138)
		(stroke
			(width 0.2)
			(type default)
		)
		(layer "In1.Cu")
	)
	(gr_line
		(start 33.4264 -14.96314)
		(end 34.289746 -14.96314)
		(stroke
			(width 0.2)
			(type default)
		)
		(layer "In1.Cu")
	)
	(gr_arc
		(start 33.4264 -14.19606)
		(mid 33.04286 -14.5796)
		(end 33.4264 -14.96314)
		(stroke
			(width 0.2)
			(type default)
		)
		(layer "In1.Cu")
	)
	(gr_arc
		(start 34.289746 -14.96314)
		(mid 34.67354 -14.579727)
		(end 34.29 -14.19606)
		(stroke
			(width 0.2)
			(type default)
		)
		(layer "In1.Cu")
	)
	(gr_line
		(start 34.29 -14.19606)
		(end 33.4264 -14.19606)
		(stroke
			(width 0.2)
			(type default)
		)
		(layer "In1.Cu")
	)
	(gr_rect
		(start 34.991802 -4.097528)
		(end 35.708082 -8.293608)
		(stroke
			(width 0)
			(type default)
		)
		(fill no)
		(layer "In1.Cu")
	)
	(gr_line
		(start 35.408362 -10.634218)
		(end 36.327588 -10.634218)
		(stroke
			(width 0.2)
			(type default)
		)
		(layer "In1.Cu")
	)
	(gr_arc
		(start 35.408362 -9.867138)
		(mid 35.024822 -10.250678)
		(end 35.408362 -10.634218)
		(stroke
			(width 0.2)
			(type default)
		)
		(layer "In1.Cu")
	)
	(gr_rect
		(start 35.9918 -4.097528)
		(end 36.70808 -8.293608)
		(stroke
			(width 0)
			(type default)
		)
		(fill no)
		(layer "In1.Cu")
	)
	(gr_arc
		(start 36.327588 -10.634218)
		(mid 36.711382 -10.250805)
		(end 36.327842 -9.867138)
		(stroke
			(width 0.2)
			(type default)
		)
		(layer "In1.Cu")
	)
	(gr_line
		(start 36.327842 -9.867138)
		(end 35.408362 -9.867138)
		(stroke
			(width 0.2)
			(type default)
		)
		(layer "In1.Cu")
	)
	(gr_line
		(start 37.41801 -14.20114)
		(end 38.281356 -14.20114)
		(stroke
			(width 0.2)
			(type default)
		)
		(layer "In1.Cu")
	)
	(gr_arc
		(start 37.41801 -13.43406)
		(mid 37.03447 -13.8176)
		(end 37.41801 -14.20114)
		(stroke
			(width 0.2)
			(type default)
		)
		(layer "In1.Cu")
	)
	(gr_arc
		(start 37.88664 -30.2006)
		(mid 38.27018 -30.58414)
		(end 38.65372 -30.2006)
		(stroke
			(width 0.2)
			(type default)
		)
		(layer "In1.Cu")
	)
	(gr_line
		(start 37.88664 -29.337)
		(end 37.88664 -30.2006)
		(stroke
			(width 0.2)
			(type default)
		)
		(layer "In1.Cu")
	)
	(gr_arc
		(start 38.281356 -14.20114)
		(mid 38.66515 -13.817727)
		(end 38.28161 -13.43406)
		(stroke
			(width 0.2)
			(type default)
		)
		(layer "In1.Cu")
	)
	(gr_line
		(start 38.28161 -13.43406)
		(end 37.41801 -13.43406)
		(stroke
			(width 0.2)
			(type default)
		)
		(layer "In1.Cu")
	)
	(gr_line
		(start 38.65372 -30.2006)
		(end 38.65372 -29.337254)
		(stroke
			(width 0.2)
			(type default)
		)
		(layer "In1.Cu")
	)
	(gr_arc
		(start 38.65372 -29.337254)
		(mid 38.270307 -28.95346)
		(end 37.88664 -29.337)
		(stroke
			(width 0.2)
			(type default)
		)
		(layer "In1.Cu")
	)
	(gr_rect
		(start 38.991794 -4.097528)
		(end 39.708074 -8.293608)
		(stroke
			(width 0)
			(type default)
		)
		(fill no)
		(layer "In1.Cu")
	)
	(gr_line
		(start 39.408354 -10.634218)
		(end 40.327834 -10.634218)
		(stroke
			(width 0.2)
			(type default)
		)
		(layer "In1.Cu")
	)
	(gr_arc
		(start 39.408608 -9.867138)
		(mid 39.024814 -10.250551)
		(end 39.408354 -10.634218)
		(stroke
			(width 0.2)
			(type default)
		)
		(layer "In1.Cu")
	)
	(gr_line
		(start 39.44366 -12.73048)
		(end 40.40124 -12.73048)
		(stroke
			(width 0.2)
			(type default)
		)
		(layer "In1.Cu")
	)
	(gr_arc
		(start 39.443914 -11.9634)
		(mid 39.06012 -12.346813)
		(end 39.44366 -12.73048)
		(stroke
			(width 0.2)
			(type default)
		)
		(layer "In1.Cu")
	)
	(gr_rect
		(start 39.991792 -4.097528)
		(end 40.708072 -8.293608)
		(stroke
			(width 0)
			(type default)
		)
		(fill no)
		(layer "In1.Cu")
	)
	(gr_arc
		(start 40.327834 -10.634218)
		(mid 40.711374 -10.250678)
		(end 40.327834 -9.867138)
		(stroke
			(width 0.2)
			(type default)
		)
		(layer "In1.Cu")
	)
	(gr_line
		(start 40.327834 -9.867138)
		(end 39.408608 -9.867138)
		(stroke
			(width 0.2)
			(type default)
		)
		(layer "In1.Cu")
	)
	(gr_arc
		(start 40.40124 -12.73048)
		(mid 40.78478 -12.34694)
		(end 40.40124 -11.9634)
		(stroke
			(width 0.2)
			(type default)
		)
		(layer "In1.Cu")
	)
	(gr_line
		(start 40.40124 -11.9634)
		(end 39.443914 -11.9634)
		(stroke
			(width 0.2)
			(type default)
		)
		(layer "In1.Cu")
	)
	(gr_line
		(start 41.418002 -14.20114)
		(end 42.281348 -14.20114)
		(stroke
			(width 0.2)
			(type default)
		)
		(layer "In1.Cu")
	)
	(gr_arc
		(start 41.418002 -13.43406)
		(mid 41.034462 -13.8176)
		(end 41.418002 -14.20114)
		(stroke
			(width 0.2)
			(type default)
		)
		(layer "In1.Cu")
	)
	(gr_arc
		(start 42.281348 -14.20114)
		(mid 42.665142 -13.817727)
		(end 42.281602 -13.43406)
		(stroke
			(width 0.2)
			(type default)
		)
		(layer "In1.Cu")
	)
	(gr_line
		(start 42.281602 -13.43406)
		(end 41.418002 -13.43406)
		(stroke
			(width 0.2)
			(type default)
		)
		(layer "In1.Cu")
	)
	(gr_line
		(start 42.45356 -44.5389)
		(end 43.41114 -44.5389)
		(stroke
			(width 0.2)
			(type default)
		)
		(layer "In1.Cu")
	)
	(gr_arc
		(start 42.453814 -43.77182)
		(mid 42.07002 -44.155233)
		(end 42.45356 -44.5389)
		(stroke
			(width 0.2)
			(type default)
		)
		(layer "In1.Cu")
	)
	(gr_rect
		(start 42.991786 -4.097528)
		(end 43.708066 -8.293608)
		(stroke
			(width 0)
			(type default)
		)
		(fill no)
		(layer "In1.Cu")
	)
	(gr_line
		(start 43.25366 -12.98194)
		(end 44.210986 -12.98194)
		(stroke
			(width 0.2)
			(type default)
		)
		(layer "In1.Cu")
	)
	(gr_arc
		(start 43.25366 -12.21486)
		(mid 42.87012 -12.5984)
		(end 43.25366 -12.98194)
		(stroke
			(width 0.2)
			(type default)
		)
		(layer "In1.Cu")
	)
	(gr_line
		(start 43.408346 -10.634218)
		(end 44.327826 -10.634218)
		(stroke
			(width 0.2)
			(type default)
		)
		(layer "In1.Cu")
	)
	(gr_arc
		(start 43.4086 -9.867138)
		(mid 43.024806 -10.250551)
		(end 43.408346 -10.634218)
		(stroke
			(width 0.2)
			(type default)
		)
		(layer "In1.Cu")
	)
	(gr_arc
		(start 43.41114 -44.5389)
		(mid 43.79468 -44.15536)
		(end 43.41114 -43.77182)
		(stroke
			(width 0.2)
			(type default)
		)
		(layer "In1.Cu")
	)
	(gr_line
		(start 43.41114 -43.77182)
		(end 42.453814 -43.77182)
		(stroke
			(width 0.2)
			(type default)
		)
		(layer "In1.Cu")
	)
	(gr_rect
		(start 43.991784 -4.097528)
		(end 44.708064 -8.293608)
		(stroke
			(width 0)
			(type default)
		)
		(fill no)
		(layer "In1.Cu")
	)
	(gr_arc
		(start 44.210986 -12.98194)
		(mid 44.59478 -12.598527)
		(end 44.21124 -12.21486)
		(stroke
			(width 0.2)
			(type default)
		)
		(layer "In1.Cu")
	)
	(gr_line
		(start 44.21124 -12.21486)
		(end 43.25366 -12.21486)
		(stroke
			(width 0.2)
			(type default)
		)
		(layer "In1.Cu")
	)
	(gr_arc
		(start 44.327826 -10.634218)
		(mid 44.711366 -10.250678)
		(end 44.327826 -9.867138)
		(stroke
			(width 0.2)
			(type default)
		)
		(layer "In1.Cu")
	)
	(gr_line
		(start 44.327826 -9.867138)
		(end 43.4086 -9.867138)
		(stroke
			(width 0.2)
			(type default)
		)
		(layer "In1.Cu")
	)
	(gr_line
		(start 44.98975 -44.30014)
		(end 45.947838 -44.32173)
		(stroke
			(width 0.2)
			(type default)
		)
		(layer "In1.Cu")
	)
	(gr_arc
		(start 45.007276 -43.53306)
		(mid 44.615103 -43.907837)
		(end 44.98975 -44.30014)
		(stroke
			(width 0.2)
			(type default)
		)
		(layer "In1.Cu")
	)
	(gr_line
		(start 45.466 -14.1986)
		(end 46.176946 -14.1986)
		(stroke
			(width 0.2)
			(type default)
		)
		(layer "In1.Cu")
	)
	(gr_arc
		(start 45.466 -13.4366)
		(mid 45.085 -13.8176)
		(end 45.466 -14.1986)
		(stroke
			(width 0.2)
			(type default)
		)
		(layer "In1.Cu")
	)
	(gr_arc
		(start 45.947838 -44.32173)
		(mid 46.340014 -43.946826)
		(end 45.96511 -43.55465)
		(stroke
			(width 0.2)
			(type default)
		)
		(layer "In1.Cu")
	)
	(gr_line
		(start 45.96511 -43.55465)
		(end 45.007276 -43.53306)
		(stroke
			(width 0.2)
			(type default)
		)
		(layer "In1.Cu")
	)
	(gr_arc
		(start 46.176946 -14.1986)
		(mid 46.5582 -13.817727)
		(end 46.1772 -13.4366)
		(stroke
			(width 0.2)
			(type default)
		)
		(layer "In1.Cu")
	)
	(gr_line
		(start 46.1772 -13.4366)
		(end 45.466 -13.4366)
		(stroke
			(width 0.2)
			(type default)
		)
		(layer "In1.Cu")
	)
	(gr_rect
		(start 46.991778 -4.097528)
		(end 47.708058 -8.293608)
		(stroke
			(width 0)
			(type default)
		)
		(fill no)
		(layer "In1.Cu")
	)
	(gr_line
		(start 47.408338 -10.634218)
		(end 48.327818 -10.634218)
		(stroke
			(width 0.2)
			(type default)
		)
		(layer "In1.Cu")
	)
	(gr_arc
		(start 47.408592 -9.867138)
		(mid 47.024798 -10.250551)
		(end 47.408338 -10.634218)
		(stroke
			(width 0.2)
			(type default)
		)
		(layer "In1.Cu")
	)
	(gr_line
		(start 47.46371 -14.1732)
		(end 48.183546 -14.1732)
		(stroke
			(width 0.2)
			(type default)
		)
		(layer "In1.Cu")
	)
	(gr_arc
		(start 47.46371 -13.4112)
		(mid 47.08271 -13.7922)
		(end 47.46371 -14.1732)
		(stroke
			(width 0.2)
			(type default)
		)
		(layer "In1.Cu")
	)
	(gr_rect
		(start 47.991776 -4.097528)
		(end 48.708056 -8.293608)
		(stroke
			(width 0)
			(type default)
		)
		(fill no)
		(layer "In1.Cu")
	)
	(gr_arc
		(start 48.183546 -14.1732)
		(mid 48.5648 -13.792327)
		(end 48.1838 -13.4112)
		(stroke
			(width 0.2)
			(type default)
		)
		(layer "In1.Cu")
	)
	(gr_line
		(start 48.1838 -13.4112)
		(end 47.46371 -13.4112)
		(stroke
			(width 0.2)
			(type default)
		)
		(layer "In1.Cu")
	)
	(gr_arc
		(start 48.327818 -10.634218)
		(mid 48.711358 -10.250678)
		(end 48.327818 -9.867138)
		(stroke
			(width 0.2)
			(type default)
		)
		(layer "In1.Cu")
	)
	(gr_line
		(start 48.327818 -9.867138)
		(end 47.408592 -9.867138)
		(stroke
			(width 0.2)
			(type default)
		)
		(layer "In1.Cu")
	)
	(gr_line
		(start 49.176432 -38.313614)
		(end 49.81321 -38.892226)
		(stroke
			(width 0.2)
			(type default)
		)
		(layer "In1.Cu")
	)
	(gr_arc
		(start 49.19726 -13.2588)
		(mid 49.212883 -13.296517)
		(end 49.2506 -13.31214)
		(stroke
			(width 0.2)
			(type default)
		)
		(layer "In1.Cu")
	)
	(gr_line
		(start 49.19726 -12.9032)
		(end 49.19726 -13.2588)
		(stroke
			(width 0.2)
			(type default)
		)
		(layer "In1.Cu")
	)
	(gr_arc
		(start 49.19726 -12.4968)
		(mid 49.212883 -12.534517)
		(end 49.2506 -12.55014)
		(stroke
			(width 0.2)
			(type default)
		)
		(layer "In1.Cu")
	)
	(gr_line
		(start 49.19726 -12.1412)
		(end 49.19726 -12.4968)
		(stroke
			(width 0.2)
			(type default)
		)
		(layer "In1.Cu")
	)
	(gr_line
		(start 49.2506 -13.31214)
		(end 49.657 -13.31214)
		(stroke
			(width 0.2)
			(type default)
		)
		(layer "In1.Cu")
	)
	(gr_arc
		(start 49.2506 -12.84986)
		(mid 49.212883 -12.865483)
		(end 49.19726 -12.9032)
		(stroke
			(width 0.2)
			(type default)
		)
		(layer "In1.Cu")
	)
	(gr_line
		(start 49.2506 -12.55014)
		(end 49.657 -12.55014)
		(stroke
			(width 0.2)
			(type default)
		)
		(layer "In1.Cu")
	)
	(gr_arc
		(start 49.2506 -12.08786)
		(mid 49.212883 -12.103483)
		(end 49.19726 -12.1412)
		(stroke
			(width 0.2)
			(type default)
		)
		(layer "In1.Cu")
	)
	(gr_line
		(start 49.29505 -20.79498)
		(end 50.25263 -20.79498)
		(stroke
			(width 0.2)
			(type default)
		)
		(layer "In1.Cu")
	)
	(gr_arc
		(start 49.295304 -20.0279)
		(mid 48.91151 -20.411313)
		(end 49.29505 -20.79498)
		(stroke
			(width 0.2)
			(type default)
		)
		(layer "In1.Cu")
	)
	(gr_line
		(start 49.38903 -10.64387)
		(end 50.310542 -10.64387)
		(stroke
			(width 0.2)
			(type default)
		)
		(layer "In1.Cu")
	)
	(gr_arc
		(start 49.389284 -9.87679)
		(mid 49.00549 -10.260203)
		(end 49.38903 -10.64387)
		(stroke
			(width 0.2)
			(type default)
		)
		(layer "In1.Cu")
	)
	(gr_line
		(start 49.4538 -14.1986)
		(end 50.2158 -14.1986)
		(stroke
			(width 0.2)
			(type default)
		)
		(layer "In1.Cu")
	)
	(gr_arc
		(start 49.454054 -13.4366)
		(mid 49.0728 -13.817473)
		(end 49.4538 -14.1986)
		(stroke
			(width 0.2)
			(type default)
		)
		(layer "In1.Cu")
	)
	(gr_arc
		(start 49.657 -13.31214)
		(mid 49.694717 -13.296517)
		(end 49.71034 -13.2588)
		(stroke
			(width 0.2)
			(type default)
		)
		(layer "In1.Cu")
	)
	(gr_line
		(start 49.657 -12.84986)
		(end 49.2506 -12.84986)
		(stroke
			(width 0.2)
			(type default)
		)
		(layer "In1.Cu")
	)
	(gr_arc
		(start 49.657 -12.55014)
		(mid 49.694717 -12.534517)
		(end 49.71034 -12.4968)
		(stroke
			(width 0.2)
			(type default)
		)
		(layer "In1.Cu")
	)
	(gr_line
		(start 49.657 -12.08786)
		(end 49.2506 -12.08786)
		(stroke
			(width 0.2)
			(type default)
		)
		(layer "In1.Cu")
	)
	(gr_arc
		(start 49.692052 -37.74567)
		(mid 49.15027 -37.771832)
		(end 49.176432 -38.313614)
		(stroke
			(width 0.2)
			(type default)
		)
		(layer "In1.Cu")
	)
	(gr_line
		(start 49.71034 -13.2588)
		(end 49.71034 -12.9032)
		(stroke
			(width 0.2)
			(type default)
		)
		(layer "In1.Cu")
	)
	(gr_arc
		(start 49.71034 -12.9032)
		(mid 49.694717 -12.865483)
		(end 49.657 -12.84986)
		(stroke
			(width 0.2)
			(type default)
		)
		(layer "In1.Cu")
	)
	(gr_line
		(start 49.71034 -12.4968)
		(end 49.71034 -12.1412)
		(stroke
			(width 0.2)
			(type default)
		)
		(layer "In1.Cu")
	)
	(gr_arc
		(start 49.71034 -12.1412)
		(mid 49.694717 -12.103483)
		(end 49.657 -12.08786)
		(stroke
			(width 0.2)
			(type default)
		)
		(layer "In1.Cu")
	)
	(gr_arc
		(start 49.81321 -38.892226)
		(mid 50.356403 -38.869633)
		(end 50.33137 -38.326568)
		(stroke
			(width 0.2)
			(type default)
		)
		(layer "In1.Cu")
	)
	(gr_arc
		(start 49.95926 -13.2588)
		(mid 49.974883 -13.296517)
		(end 50.0126 -13.31214)
		(stroke
			(width 0.2)
			(type default)
		)
		(layer "In1.Cu")
	)
	(gr_line
		(start 49.95926 -12.9032)
		(end 49.95926 -13.2588)
		(stroke
			(width 0.2)
			(type default)
		)
		(layer "In1.Cu")
	)
	(gr_arc
		(start 49.95926 -12.4968)
		(mid 49.974883 -12.534517)
		(end 50.0126 -12.55014)
		(stroke
			(width 0.2)
			(type default)
		)
		(layer "In1.Cu")
	)
	(gr_line
		(start 49.95926 -12.1412)
		(end 49.95926 -12.4968)
		(stroke
			(width 0.2)
			(type default)
		)
		(layer "In1.Cu")
	)
	(gr_line
		(start 50.0126 -13.31214)
		(end 50.419 -13.31214)
		(stroke
			(width 0.2)
			(type default)
		)
		(layer "In1.Cu")
	)
	(gr_arc
		(start 50.0126 -12.84986)
		(mid 49.974883 -12.865483)
		(end 49.95926 -12.9032)
		(stroke
			(width 0.2)
			(type default)
		)
		(layer "In1.Cu")
	)
	(gr_line
		(start 50.0126 -12.55014)
		(end 50.419 -12.55014)
		(stroke
			(width 0.2)
			(type default)
		)
		(layer "In1.Cu")
	)
	(gr_arc
		(start 50.0126 -12.08786)
		(mid 49.974883 -12.103483)
		(end 49.95926 -12.1412)
		(stroke
			(width 0.2)
			(type default)
		)
		(layer "In1.Cu")
	)
	(gr_arc
		(start 50.2158 -14.1986)
		(mid 50.5968 -13.8176)
		(end 50.2158 -13.4366)
		(stroke
			(width 0.2)
			(type default)
		)
		(layer "In1.Cu")
	)
	(gr_line
		(start 50.2158 -13.4366)
		(end 49.454054 -13.4366)
		(stroke
			(width 0.2)
			(type default)
		)
		(layer "In1.Cu")
	)
	(gr_arc
		(start 50.25263 -20.79498)
		(mid 50.63617 -20.41144)
		(end 50.25263 -20.0279)
		(stroke
			(width 0.2)
			(type default)
		)
		(layer "In1.Cu")
	)
	(gr_line
		(start 50.25263 -20.0279)
		(end 49.295304 -20.0279)
		(stroke
			(width 0.2)
			(type default)
		)
		(layer "In1.Cu")
	)
	(gr_arc
		(start 50.262028 -48.49495)
		(mid 50.63998 -48.884078)
		(end 51.029108 -48.506126)
		(stroke
			(width 0.2)
			(type default)
		)
		(layer "In1.Cu")
	)
	(gr_line
		(start 50.274474 -47.63135)
		(end 50.262028 -48.49495)
		(stroke
			(width 0.2)
			(type default)
		)
		(layer "In1.Cu")
	)
	(gr_arc
		(start 50.310542 -10.64387)
		(mid 50.694082 -10.26033)
		(end 50.310542 -9.87679)
		(stroke
			(width 0.2)
			(type default)
		)
		(layer "In1.Cu")
	)
	(gr_line
		(start 50.310542 -9.87679)
		(end 49.389284 -9.87679)
		(stroke
			(width 0.2)
			(type default)
		)
		(layer "In1.Cu")
	)
	(gr_line
		(start 50.33137 -38.326568)
		(end 49.692052 -37.74567)
		(stroke
			(width 0.2)
			(type default)
		)
		(layer "In1.Cu")
	)
	(gr_arc
		(start 50.419 -13.31214)
		(mid 50.456717 -13.296517)
		(end 50.47234 -13.2588)
		(stroke
			(width 0.2)
			(type default)
		)
		(layer "In1.Cu")
	)
	(gr_line
		(start 50.419 -12.84986)
		(end 50.0126 -12.84986)
		(stroke
			(width 0.2)
			(type default)
		)
		(layer "In1.Cu")
	)
	(gr_arc
		(start 50.419 -12.55014)
		(mid 50.456717 -12.534517)
		(end 50.47234 -12.4968)
		(stroke
			(width 0.2)
			(type default)
		)
		(layer "In1.Cu")
	)
	(gr_line
		(start 50.419 -12.08786)
		(end 50.0126 -12.08786)
		(stroke
			(width 0.2)
			(type default)
		)
		(layer "In1.Cu")
	)
	(gr_line
		(start 50.47234 -13.2588)
		(end 50.47234 -12.9032)
		(stroke
			(width 0.2)
			(type default)
		)
		(layer "In1.Cu")
	)
	(gr_arc
		(start 50.47234 -12.9032)
		(mid 50.456717 -12.865483)
		(end 50.419 -12.84986)
		(stroke
			(width 0.2)
			(type default)
		)
		(layer "In1.Cu")
	)
	(gr_line
		(start 50.47234 -12.4968)
		(end 50.47234 -12.1412)
		(stroke
			(width 0.2)
			(type default)
		)
		(layer "In1.Cu")
	)
	(gr_arc
		(start 50.47234 -12.1412)
		(mid 50.456717 -12.103483)
		(end 50.419 -12.08786)
		(stroke
			(width 0.2)
			(type default)
		)
		(layer "In1.Cu")
	)
	(gr_rect
		(start 50.99177 -4.097528)
		(end 51.70805 -8.293608)
		(stroke
			(width 0)
			(type default)
		)
		(fill no)
		(layer "In1.Cu")
	)
	(gr_line
		(start 51.029108 -48.506126)
		(end 51.041554 -47.64278)
		(stroke
			(width 0.2)
			(type default)
		)
		(layer "In1.Cu")
	)
	(gr_arc
		(start 51.041554 -47.64278)
		(mid 50.663729 -47.253654)
		(end 50.274474 -47.63135)
		(stroke
			(width 0.2)
			(type default)
		)
		(layer "In1.Cu")
	)
	(gr_line
		(start 51.282346 -34.47034)
		(end 52.16652 -34.47034)
		(stroke
			(width 0.2)
			(type default)
		)
		(layer "In1.Cu")
	)
	(gr_arc
		(start 51.2826 -33.70326)
		(mid 50.898806 -34.086673)
		(end 51.282346 -34.47034)
		(stroke
			(width 0.2)
			(type default)
		)
		(layer "In1.Cu")
	)
	(gr_arc
		(start 51.96586 -13.3858)
		(mid 51.981483 -13.423517)
		(end 52.0192 -13.43914)
		(stroke
			(width 0.2)
			(type default)
		)
		(layer "In1.Cu")
	)
	(gr_line
		(start 51.96586 -13.0302)
		(end 51.96586 -13.3858)
		(stroke
			(width 0.2)
			(type default)
		)
		(layer "In1.Cu")
	)
	(gr_arc
		(start 51.96586 -12.6238)
		(mid 51.981483 -12.661517)
		(end 52.0192 -12.67714)
		(stroke
			(width 0.2)
			(type default)
		)
		(layer "In1.Cu")
	)
	(gr_line
		(start 51.96586 -12.2682)
		(end 51.96586 -12.6238)
		(stroke
			(width 0.2)
			(type default)
		)
		(layer "In1.Cu")
	)
	(gr_rect
		(start 51.991768 -4.097528)
		(end 52.708048 -8.293608)
		(stroke
			(width 0)
			(type default)
		)
		(fill no)
		(layer "In1.Cu")
	)
	(gr_line
		(start 52.0192 -13.43914)
		(end 52.4256 -13.43914)
		(stroke
			(width 0.2)
			(type default)
		)
		(layer "In1.Cu")
	)
	(gr_arc
		(start 52.0192 -12.97686)
		(mid 51.981483 -12.992483)
		(end 51.96586 -13.0302)
		(stroke
			(width 0.2)
			(type default)
		)
		(layer "In1.Cu")
	)
	(gr_line
		(start 52.0192 -12.67714)
		(end 52.4256 -12.67714)
		(stroke
			(width 0.2)
			(type default)
		)
		(layer "In1.Cu")
	)
	(gr_arc
		(start 52.0192 -12.21486)
		(mid 51.981483 -12.230483)
		(end 51.96586 -12.2682)
		(stroke
			(width 0.2)
			(type default)
		)
		(layer "In1.Cu")
	)
	(gr_line
		(start 52.1462 -14.32814)
		(end 53.009546 -14.32814)
		(stroke
			(width 0.2)
			(type default)
		)
		(layer "In1.Cu")
	)
	(gr_arc
		(start 52.1462 -13.56106)
		(mid 51.76266 -13.9446)
		(end 52.1462 -14.32814)
		(stroke
			(width 0.2)
			(type default)
		)
		(layer "In1.Cu")
	)
	(gr_arc
		(start 52.16652 -34.47034)
		(mid 52.55006 -34.0868)
		(end 52.16652 -33.70326)
		(stroke
			(width 0.2)
			(type default)
		)
		(layer "In1.Cu")
	)
	(gr_line
		(start 52.16652 -33.70326)
		(end 51.2826 -33.70326)
		(stroke
			(width 0.2)
			(type default)
		)
		(layer "In1.Cu")
	)
	(gr_arc
		(start 52.4256 -13.43914)
		(mid 52.463317 -13.423517)
		(end 52.47894 -13.3858)
		(stroke
			(width 0.2)
			(type default)
		)
		(layer "In1.Cu")
	)
	(gr_line
		(start 52.4256 -12.97686)
		(end 52.0192 -12.97686)
		(stroke
			(width 0.2)
			(type default)
		)
		(layer "In1.Cu")
	)
	(gr_arc
		(start 52.4256 -12.67714)
		(mid 52.463317 -12.661517)
		(end 52.47894 -12.6238)
		(stroke
			(width 0.2)
			(type default)
		)
		(layer "In1.Cu")
	)
	(gr_line
		(start 52.4256 -12.21486)
		(end 52.0192 -12.21486)
		(stroke
			(width 0.2)
			(type default)
		)
		(layer "In1.Cu")
	)
	(gr_line
		(start 52.47894 -13.3858)
		(end 52.47894 -13.0302)
		(stroke
			(width 0.2)
			(type default)
		)
		(layer "In1.Cu")
	)
	(gr_arc
		(start 52.47894 -13.0302)
		(mid 52.463317 -12.992483)
		(end 52.4256 -12.97686)
		(stroke
			(width 0.2)
			(type default)
		)
		(layer "In1.Cu")
	)
	(gr_line
		(start 52.47894 -12.6238)
		(end 52.47894 -12.2682)
		(stroke
			(width 0.2)
			(type default)
		)
		(layer "In1.Cu")
	)
	(gr_arc
		(start 52.47894 -12.2682)
		(mid 52.463317 -12.230483)
		(end 52.4256 -12.21486)
		(stroke
			(width 0.2)
			(type default)
		)
		(layer "In1.Cu")
	)
	(gr_arc
		(start 52.52339 -34.93262)
		(mid 52.14112 -35.31743)
		(end 52.52593 -35.6997)
		(stroke
			(width 0.2)
			(type default)
		)
		(layer "In1.Cu")
	)
	(gr_line
		(start 52.52593 -35.6997)
		(end 53.479954 -35.696652)
		(stroke
			(width 0.2)
			(type default)
		)
		(layer "In1.Cu")
	)
	(gr_arc
		(start 52.72786 -13.3858)
		(mid 52.743483 -13.423517)
		(end 52.7812 -13.43914)
		(stroke
			(width 0.2)
			(type default)
		)
		(layer "In1.Cu")
	)
	(gr_line
		(start 52.72786 -13.0302)
		(end 52.72786 -13.3858)
		(stroke
			(width 0.2)
			(type default)
		)
		(layer "In1.Cu")
	)
	(gr_arc
		(start 52.72786 -12.6238)
		(mid 52.743483 -12.661517)
		(end 52.7812 -12.67714)
		(stroke
			(width 0.2)
			(type default)
		)
		(layer "In1.Cu")
	)
	(gr_line
		(start 52.72786 -12.2682)
		(end 52.72786 -12.6238)
		(stroke
			(width 0.2)
			(type default)
		)
		(layer "In1.Cu")
	)
	(gr_arc
		(start 52.768246 -29.826966)
		(mid 53.151659 -30.21076)
		(end 53.535326 -29.82722)
		(stroke
			(width 0.2)
			(type default)
		)
		(layer "In1.Cu")
	)
	(gr_line
		(start 52.768246 -28.897834)
		(end 52.768246 -29.826966)
		(stroke
			(width 0.2)
			(type default)
		)
		(layer "In1.Cu")
	)
	(gr_line
		(start 52.7812 -13.43914)
		(end 53.1876 -13.43914)
		(stroke
			(width 0.2)
			(type default)
		)
		(layer "In1.Cu")
	)
	(gr_arc
		(start 52.7812 -12.97686)
		(mid 52.743483 -12.992483)
		(end 52.72786 -13.0302)
		(stroke
			(width 0.2)
			(type default)
		)
		(layer "In1.Cu")
	)
	(gr_line
		(start 52.7812 -12.67714)
		(end 53.1876 -12.67714)
		(stroke
			(width 0.2)
			(type default)
		)
		(layer "In1.Cu")
	)
	(gr_arc
		(start 52.7812 -12.21486)
		(mid 52.743483 -12.230483)
		(end 52.72786 -12.2682)
		(stroke
			(width 0.2)
			(type default)
		)
		(layer "In1.Cu")
	)
	(gr_arc
		(start 53.009546 -14.32814)
		(mid 53.39334 -13.944727)
		(end 53.0098 -13.56106)
		(stroke
			(width 0.2)
			(type default)
		)
		(layer "In1.Cu")
	)
	(gr_line
		(start 53.0098 -13.56106)
		(end 52.1462 -13.56106)
		(stroke
			(width 0.2)
			(type default)
		)
		(layer "In1.Cu")
	)
	(gr_arc
		(start 53.1876 -13.43914)
		(mid 53.225317 -13.423517)
		(end 53.24094 -13.3858)
		(stroke
			(width 0.2)
			(type default)
		)
		(layer "In1.Cu")
	)
	(gr_line
		(start 53.1876 -12.97686)
		(end 52.7812 -12.97686)
		(stroke
			(width 0.2)
			(type default)
		)
		(layer "In1.Cu")
	)
	(gr_arc
		(start 53.1876 -12.67714)
		(mid 53.225317 -12.661517)
		(end 53.24094 -12.6238)
		(stroke
			(width 0.2)
			(type default)
		)
		(layer "In1.Cu")
	)
	(gr_line
		(start 53.1876 -12.21486)
		(end 52.7812 -12.21486)
		(stroke
			(width 0.2)
			(type default)
		)
		(layer "In1.Cu")
	)
	(gr_line
		(start 53.24094 -13.3858)
		(end 53.24094 -13.0302)
		(stroke
			(width 0.2)
			(type default)
		)
		(layer "In1.Cu")
	)
	(gr_arc
		(start 53.24094 -13.0302)
		(mid 53.225317 -12.992483)
		(end 53.1876 -12.97686)
		(stroke
			(width 0.2)
			(type default)
		)
		(layer "In1.Cu")
	)
	(gr_line
		(start 53.24094 -12.6238)
		(end 53.24094 -12.2682)
		(stroke
			(width 0.2)
			(type default)
		)
		(layer "In1.Cu")
	)
	(gr_arc
		(start 53.24094 -12.2682)
		(mid 53.225317 -12.230483)
		(end 53.1876 -12.21486)
		(stroke
			(width 0.2)
			(type default)
		)
		(layer "In1.Cu")
	)
	(gr_line
		(start 53.477668 -34.929572)
		(end 52.52339 -34.93262)
		(stroke
			(width 0.2)
			(type default)
		)
		(layer "In1.Cu")
	)
	(gr_arc
		(start 53.479954 -35.696652)
		(mid 53.862478 -35.311969)
		(end 53.477668 -34.929572)
		(stroke
			(width 0.2)
			(type default)
		)
		(layer "In1.Cu")
	)
	(gr_line
		(start 53.535326 -29.82722)
		(end 53.535326 -28.897834)
		(stroke
			(width 0.2)
			(type default)
		)
		(layer "In1.Cu")
	)
	(gr_arc
		(start 53.535326 -28.897834)
		(mid 53.151786 -28.514294)
		(end 52.768246 -28.897834)
		(stroke
			(width 0.2)
			(type default)
		)
		(layer "In1.Cu")
	)
	(gr_rect
		(start 58.991754 -4.097528)
		(end 59.708034 -8.293608)
		(stroke
			(width 0)
			(type default)
		)
		(fill no)
		(layer "In1.Cu")
	)
	(gr_line
		(start 59.078114 -11.320018)
		(end 59.997594 -11.320018)
		(stroke
			(width 0.2)
			(type default)
		)
		(layer "In1.Cu")
	)
	(gr_arc
		(start 59.078368 -10.552938)
		(mid 58.694574 -10.936351)
		(end 59.078114 -11.320018)
		(stroke
			(width 0.2)
			(type default)
		)
		(layer "In1.Cu")
	)
	(gr_arc
		(start 59.27471 -36.33724)
		(mid 59.65825 -36.72078)
		(end 60.04179 -36.33724)
		(stroke
			(width 0.2)
			(type default)
		)
		(layer "In1.Cu")
	)
	(gr_line
		(start 59.27471 -35.37966)
		(end 59.27471 -36.33724)
		(stroke
			(width 0.2)
			(type default)
		)
		(layer "In1.Cu")
	)
	(gr_rect
		(start 59.991752 -4.097528)
		(end 60.708032 -8.293608)
		(stroke
			(width 0)
			(type default)
		)
		(fill no)
		(layer "In1.Cu")
	)
	(gr_arc
		(start 59.997594 -11.320018)
		(mid 60.381134 -10.936478)
		(end 59.997594 -10.552938)
		(stroke
			(width 0.2)
			(type default)
		)
		(layer "In1.Cu")
	)
	(gr_line
		(start 59.997594 -10.552938)
		(end 59.078368 -10.552938)
		(stroke
			(width 0.2)
			(type default)
		)
		(layer "In1.Cu")
	)
	(gr_line
		(start 60.04179 -36.33724)
		(end 60.04179 -35.379914)
		(stroke
			(width 0.2)
			(type default)
		)
		(layer "In1.Cu")
	)
	(gr_arc
		(start 60.04179 -35.379914)
		(mid 59.658377 -34.99612)
		(end 59.27471 -35.37966)
		(stroke
			(width 0.2)
			(type default)
		)
		(layer "In1.Cu")
	)
	(gr_line
		(start 60.551822 -45.897038)
		(end 60.607448 -46.75886)
		(stroke
			(width 0.2)
			(type default)
		)
		(layer "In1.Cu")
	)
	(gr_arc
		(start 60.607448 -46.75886)
		(mid 61.014864 -47.117)
		(end 61.373004 -46.709584)
		(stroke
			(width 0.2)
			(type default)
		)
		(layer "In1.Cu")
	)
	(gr_arc
		(start 61.317378 -45.848016)
		(mid 60.910088 -45.489868)
		(end 60.551822 -45.897038)
		(stroke
			(width 0.2)
			(type default)
		)
		(layer "In1.Cu")
	)
	(gr_line
		(start 61.373004 -46.709584)
		(end 61.317378 -45.848016)
		(stroke
			(width 0.2)
			(type default)
		)
		(layer "In1.Cu")
	)
	(gr_line
		(start 61.40831 -10.634218)
		(end 62.327536 -10.634218)
		(stroke
			(width 0.2)
			(type default)
		)
		(layer "In1.Cu")
	)
	(gr_arc
		(start 61.40831 -9.867138)
		(mid 61.02477 -10.250678)
		(end 61.40831 -10.634218)
		(stroke
			(width 0.2)
			(type default)
		)
		(layer "In1.Cu")
	)
	(gr_arc
		(start 62.327536 -10.634218)
		(mid 62.71133 -10.250805)
		(end 62.32779 -9.867138)
		(stroke
			(width 0.2)
			(type default)
		)
		(layer "In1.Cu")
	)
	(gr_line
		(start 62.32779 -9.867138)
		(end 61.40831 -9.867138)
		(stroke
			(width 0.2)
			(type default)
		)
		(layer "In1.Cu")
	)
	(gr_rect
		(start 62.991746 -4.097528)
		(end 63.708026 -8.293608)
		(stroke
			(width 0)
			(type default)
		)
		(fill no)
		(layer "In1.Cu")
	)
	(gr_arc
		(start 63.37046 -14.1478)
		(mid 63.386083 -14.185517)
		(end 63.4238 -14.20114)
		(stroke
			(width 0.2)
			(type default)
		)
		(layer "In1.Cu")
	)
	(gr_line
		(start 63.37046 -13.7922)
		(end 63.37046 -14.1478)
		(stroke
			(width 0.2)
			(type default)
		)
		(layer "In1.Cu")
	)
	(gr_arc
		(start 63.37046 -13.3858)
		(mid 63.386083 -13.423517)
		(end 63.4238 -13.43914)
		(stroke
			(width 0.2)
			(type default)
		)
		(layer "In1.Cu")
	)
	(gr_line
		(start 63.37046 -13.0302)
		(end 63.37046 -13.3858)
		(stroke
			(width 0.2)
			(type default)
		)
		(layer "In1.Cu")
	)
	(gr_line
		(start 63.4238 -14.20114)
		(end 63.8302 -14.20114)
		(stroke
			(width 0.2)
			(type default)
		)
		(layer "In1.Cu")
	)
	(gr_arc
		(start 63.4238 -13.73886)
		(mid 63.386083 -13.754483)
		(end 63.37046 -13.7922)
		(stroke
			(width 0.2)
			(type default)
		)
		(layer "In1.Cu")
	)
	(gr_line
		(start 63.4238 -13.43914)
		(end 63.8302 -13.43914)
		(stroke
			(width 0.2)
			(type default)
		)
		(layer "In1.Cu")
	)
	(gr_arc
		(start 63.4238 -12.97686)
		(mid 63.386083 -12.992483)
		(end 63.37046 -13.0302)
		(stroke
			(width 0.2)
			(type default)
		)
		(layer "In1.Cu")
	)
	(gr_line
		(start 63.627 -15.0876)
		(end 64.389 -15.0876)
		(stroke
			(width 0.2)
			(type default)
		)
		(layer "In1.Cu")
	)
	(gr_arc
		(start 63.627254 -14.3256)
		(mid 63.246 -14.706473)
		(end 63.627 -15.0876)
		(stroke
			(width 0.2)
			(type default)
		)
		(layer "In1.Cu")
	)
	(gr_arc
		(start 63.8302 -14.20114)
		(mid 63.867917 -14.185517)
		(end 63.88354 -14.1478)
		(stroke
			(width 0.2)
			(type default)
		)
		(layer "In1.Cu")
	)
	(gr_line
		(start 63.8302 -13.73886)
		(end 63.4238 -13.73886)
		(stroke
			(width 0.2)
			(type default)
		)
		(layer "In1.Cu")
	)
	(gr_arc
		(start 63.8302 -13.43914)
		(mid 63.867917 -13.423517)
		(end 63.88354 -13.3858)
		(stroke
			(width 0.2)
			(type default)
		)
		(layer "In1.Cu")
	)
	(gr_line
		(start 63.8302 -12.97686)
		(end 63.4238 -12.97686)
		(stroke
			(width 0.2)
			(type default)
		)
		(layer "In1.Cu")
	)
	(gr_line
		(start 63.88354 -14.1478)
		(end 63.88354 -13.7922)
		(stroke
			(width 0.2)
			(type default)
		)
		(layer "In1.Cu")
	)
	(gr_arc
		(start 63.88354 -13.7922)
		(mid 63.867917 -13.754483)
		(end 63.8302 -13.73886)
		(stroke
			(width 0.2)
			(type default)
		)
		(layer "In1.Cu")
	)
	(gr_line
		(start 63.88354 -13.3858)
		(end 63.88354 -13.0302)
		(stroke
			(width 0.2)
			(type default)
		)
		(layer "In1.Cu")
	)
	(gr_arc
		(start 63.88354 -13.0302)
		(mid 63.867917 -12.992483)
		(end 63.8302 -12.97686)
		(stroke
			(width 0.2)
			(type default)
		)
		(layer "In1.Cu")
	)
	(gr_rect
		(start 63.991744 -4.097528)
		(end 64.708024 -8.293608)
		(stroke
			(width 0)
			(type default)
		)
		(fill no)
		(layer "In1.Cu")
	)
	(gr_arc
		(start 64.13246 -14.1478)
		(mid 64.148083 -14.185517)
		(end 64.1858 -14.20114)
		(stroke
			(width 0.2)
			(type default)
		)
		(layer "In1.Cu")
	)
	(gr_line
		(start 64.13246 -13.7922)
		(end 64.13246 -14.1478)
		(stroke
			(width 0.2)
			(type default)
		)
		(layer "In1.Cu")
	)
	(gr_arc
		(start 64.13246 -13.3858)
		(mid 64.148083 -13.423517)
		(end 64.1858 -13.43914)
		(stroke
			(width 0.2)
			(type default)
		)
		(layer "In1.Cu")
	)
	(gr_line
		(start 64.13246 -13.0302)
		(end 64.13246 -13.3858)
		(stroke
			(width 0.2)
			(type default)
		)
		(layer "In1.Cu")
	)
	(gr_line
		(start 64.1858 -14.20114)
		(end 64.5922 -14.20114)
		(stroke
			(width 0.2)
			(type default)
		)
		(layer "In1.Cu")
	)
	(gr_arc
		(start 64.1858 -13.73886)
		(mid 64.148083 -13.754483)
		(end 64.13246 -13.7922)
		(stroke
			(width 0.2)
			(type default)
		)
		(layer "In1.Cu")
	)
	(gr_line
		(start 64.1858 -13.43914)
		(end 64.5922 -13.43914)
		(stroke
			(width 0.2)
			(type default)
		)
		(layer "In1.Cu")
	)
	(gr_arc
		(start 64.1858 -12.97686)
		(mid 64.148083 -12.992483)
		(end 64.13246 -13.0302)
		(stroke
			(width 0.2)
			(type default)
		)
		(layer "In1.Cu")
	)
	(gr_arc
		(start 64.389 -15.0876)
		(mid 64.77 -14.7066)
		(end 64.389 -14.3256)
		(stroke
			(width 0.2)
			(type default)
		)
		(layer "In1.Cu")
	)
	(gr_line
		(start 64.389 -14.3256)
		(end 63.627254 -14.3256)
		(stroke
			(width 0.2)
			(type default)
		)
		(layer "In1.Cu")
	)
	(gr_arc
		(start 64.5922 -14.20114)
		(mid 64.629917 -14.185517)
		(end 64.64554 -14.1478)
		(stroke
			(width 0.2)
			(type default)
		)
		(layer "In1.Cu")
	)
	(gr_line
		(start 64.5922 -13.73886)
		(end 64.1858 -13.73886)
		(stroke
			(width 0.2)
			(type default)
		)
		(layer "In1.Cu")
	)
	(gr_arc
		(start 64.5922 -13.43914)
		(mid 64.629917 -13.423517)
		(end 64.64554 -13.3858)
		(stroke
			(width 0.2)
			(type default)
		)
		(layer "In1.Cu")
	)
	(gr_line
		(start 64.5922 -12.97686)
		(end 64.1858 -12.97686)
		(stroke
			(width 0.2)
			(type default)
		)
		(layer "In1.Cu")
	)
	(gr_line
		(start 64.64554 -14.1478)
		(end 64.64554 -13.7922)
		(stroke
			(width 0.2)
			(type default)
		)
		(layer "In1.Cu")
	)
	(gr_arc
		(start 64.64554 -13.7922)
		(mid 64.629917 -13.754483)
		(end 64.5922 -13.73886)
		(stroke
			(width 0.2)
			(type default)
		)
		(layer "In1.Cu")
	)
	(gr_line
		(start 64.64554 -13.3858)
		(end 64.64554 -13.0302)
		(stroke
			(width 0.2)
			(type default)
		)
		(layer "In1.Cu")
	)
	(gr_arc
		(start 64.64554 -13.0302)
		(mid 64.629917 -12.992483)
		(end 64.5922 -12.97686)
		(stroke
			(width 0.2)
			(type default)
		)
		(layer "In1.Cu")
	)
	(gr_line
		(start 65.786 -15.0622)
		(end 66.547746 -15.0622)
		(stroke
			(width 0.2)
			(type default)
		)
		(layer "In1.Cu")
	)
	(gr_arc
		(start 65.786 -14.3002)
		(mid 65.405 -14.6812)
		(end 65.786 -15.0622)
		(stroke
			(width 0.2)
			(type default)
		)
		(layer "In1.Cu")
	)
	(gr_arc
		(start 66.547746 -15.0622)
		(mid 66.929 -14.681327)
		(end 66.548 -14.3002)
		(stroke
			(width 0.2)
			(type default)
		)
		(layer "In1.Cu")
	)
	(gr_line
		(start 66.548 -14.3002)
		(end 65.786 -14.3002)
		(stroke
			(width 0.2)
			(type default)
		)
		(layer "In1.Cu")
	)
	(gr_rect
		(start 66.991738 -4.097528)
		(end 67.708018 -8.293608)
		(stroke
			(width 0)
			(type default)
		)
		(fill no)
		(layer "In1.Cu")
	)
	(gr_line
		(start 67.34556 -10.668)
		(end 68.302886 -10.668)
		(stroke
			(width 0.2)
			(type default)
		)
		(layer "In1.Cu")
	)
	(gr_arc
		(start 67.34556 -9.90092)
		(mid 66.96202 -10.28446)
		(end 67.34556 -10.668)
		(stroke
			(width 0.2)
			(type default)
		)
		(layer "In1.Cu")
	)
	(gr_rect
		(start 67.991736 -4.097528)
		(end 68.708016 -8.293608)
		(stroke
			(width 0)
			(type default)
		)
		(fill no)
		(layer "In1.Cu")
	)
	(gr_line
		(start 68.072 -14.98854)
		(end 68.834 -14.98854)
		(stroke
			(width 0.2)
			(type default)
		)
		(layer "In1.Cu")
	)
	(gr_arc
		(start 68.072254 -14.22146)
		(mid 67.68846 -14.604873)
		(end 68.072 -14.98854)
		(stroke
			(width 0.2)
			(type default)
		)
		(layer "In1.Cu")
	)
	(gr_arc
		(start 68.302886 -10.668)
		(mid 68.68668 -10.284587)
		(end 68.30314 -9.90092)
		(stroke
			(width 0.2)
			(type default)
		)
		(layer "In1.Cu")
	)
	(gr_line
		(start 68.30314 -9.90092)
		(end 67.34556 -9.90092)
		(stroke
			(width 0.2)
			(type default)
		)
		(layer "In1.Cu")
	)
	(gr_arc
		(start 68.75145 -28.403296)
		(mid 69.133212 -28.788614)
		(end 69.51853 -28.406852)
		(stroke
			(width 0.2)
			(type default)
		)
		(layer "In1.Cu")
	)
	(gr_line
		(start 68.75526 -27.51963)
		(end 68.75145 -28.403296)
		(stroke
			(width 0.2)
			(type default)
		)
		(layer "In1.Cu")
	)
	(gr_arc
		(start 68.834 -14.98854)
		(mid 69.21754 -14.605)
		(end 68.834 -14.22146)
		(stroke
			(width 0.2)
			(type default)
		)
		(layer "In1.Cu")
	)
	(gr_line
		(start 68.834 -14.22146)
		(end 68.072254 -14.22146)
		(stroke
			(width 0.2)
			(type default)
		)
		(layer "In1.Cu")
	)
	(gr_line
		(start 69.51853 -28.406852)
		(end 69.52234 -27.52344)
		(stroke
			(width 0.2)
			(type default)
		)
		(layer "In1.Cu")
	)
	(gr_arc
		(start 69.52234 -27.52344)
		(mid 69.140705 -27.138123)
		(end 68.75526 -27.51963)
		(stroke
			(width 0.2)
			(type default)
		)
		(layer "In1.Cu")
	)
	(gr_rect
		(start 70.99173 -4.097528)
		(end 71.70801 -8.293608)
		(stroke
			(width 0)
			(type default)
		)
		(fill no)
		(layer "In1.Cu")
	)
	(gr_line
		(start 71.370952 -10.668)
		(end 72.328532 -10.668)
		(stroke
			(width 0.2)
			(type default)
		)
		(layer "In1.Cu")
	)
	(gr_arc
		(start 71.371206 -9.90092)
		(mid 70.987412 -10.284333)
		(end 71.370952 -10.668)
		(stroke
			(width 0.2)
			(type default)
		)
		(layer "In1.Cu")
	)
	(gr_rect
		(start 71.991728 -4.097528)
		(end 72.708008 -8.293608)
		(stroke
			(width 0)
			(type default)
		)
		(fill no)
		(layer "In1.Cu")
	)
	(gr_arc
		(start 72.328532 -10.668)
		(mid 72.712072 -10.28446)
		(end 72.328532 -9.90092)
		(stroke
			(width 0.2)
			(type default)
		)
		(layer "In1.Cu")
	)
	(gr_line
		(start 72.328532 -9.90092)
		(end 71.371206 -9.90092)
		(stroke
			(width 0.2)
			(type default)
		)
		(layer "In1.Cu")
	)
	(gr_line
		(start 72.8472 -15.09014)
		(end 73.7108 -15.09014)
		(stroke
			(width 0.2)
			(type default)
		)
		(layer "In1.Cu")
	)
	(gr_arc
		(start 72.847454 -14.32306)
		(mid 72.46366 -14.706473)
		(end 72.8472 -15.09014)
		(stroke
			(width 0.2)
			(type default)
		)
		(layer "In1.Cu")
	)
	(gr_arc
		(start 73.7108 -15.09014)
		(mid 74.09434 -14.7066)
		(end 73.7108 -14.32306)
		(stroke
			(width 0.2)
			(type default)
		)
		(layer "In1.Cu")
	)
	(gr_line
		(start 73.7108 -14.32306)
		(end 72.847454 -14.32306)
		(stroke
			(width 0.2)
			(type default)
		)
		(layer "In1.Cu")
	)
	(gr_rect
		(start 74.991722 -4.097528)
		(end 75.708002 -8.293608)
		(stroke
			(width 0)
			(type default)
		)
		(fill no)
		(layer "In1.Cu")
	)
	(gr_line
		(start 75.370944 -10.668)
		(end 76.328524 -10.668)
		(stroke
			(width 0.2)
			(type default)
		)
		(layer "In1.Cu")
	)
	(gr_arc
		(start 75.371198 -9.90092)
		(mid 74.987404 -10.284333)
		(end 75.370944 -10.668)
		(stroke
			(width 0.2)
			(type default)
		)
		(layer "In1.Cu")
	)
	(gr_rect
		(start 75.99172 -4.097528)
		(end 76.708 -8.293608)
		(stroke
			(width 0)
			(type default)
		)
		(fill no)
		(layer "In1.Cu")
	)
	(gr_arc
		(start 76.328524 -10.668)
		(mid 76.712064 -10.28446)
		(end 76.328524 -9.90092)
		(stroke
			(width 0.2)
			(type default)
		)
		(layer "In1.Cu")
	)
	(gr_line
		(start 76.328524 -9.90092)
		(end 75.371198 -9.90092)
		(stroke
			(width 0.2)
			(type default)
		)
		(layer "In1.Cu")
	)
	(gr_line
		(start 77.4192 -14.96314)
		(end 78.2828 -14.96314)
		(stroke
			(width 0.2)
			(type default)
		)
		(layer "In1.Cu")
	)
	(gr_arc
		(start 77.419454 -14.19606)
		(mid 77.03566 -14.579473)
		(end 77.4192 -14.96314)
		(stroke
			(width 0.2)
			(type default)
		)
		(layer "In1.Cu")
	)
	(gr_arc
		(start 77.972666 -29.55925)
		(mid 77.633576 -29.90596)
		(end 77.980286 -30.24505)
		(stroke
			(width 0.2)
			(type default)
		)
		(layer "In1.Cu")
	)
	(gr_line
		(start 77.980286 -30.24505)
		(end 78.538832 -30.2387)
		(stroke
			(width 0.2)
			(type default)
		)
		(layer "In1.Cu")
	)
	(gr_line
		(start 78.090014 -31.508446)
		(end 78.648814 -31.53283)
		(stroke
			(width 0.2)
			(type default)
		)
		(layer "In1.Cu")
	)
	(gr_arc
		(start 78.12024 -30.823154)
		(mid 77.762614 -31.150687)
		(end 78.090014 -31.508446)
		(stroke
			(width 0.2)
			(type default)
		)
		(layer "In1.Cu")
	)
	(gr_arc
		(start 78.2828 -14.96314)
		(mid 78.66634 -14.5796)
		(end 78.2828 -14.19606)
		(stroke
			(width 0.2)
			(type default)
		)
		(layer "In1.Cu")
	)
	(gr_line
		(start 78.2828 -14.19606)
		(end 77.419454 -14.19606)
		(stroke
			(width 0.2)
			(type default)
		)
		(layer "In1.Cu")
	)
	(gr_line
		(start 78.531466 -29.5529)
		(end 77.972666 -29.55925)
		(stroke
			(width 0.2)
			(type default)
		)
		(layer "In1.Cu")
	)
	(gr_arc
		(start 78.538832 -30.2387)
		(mid 78.878175 -29.892117)
		(end 78.531466 -29.5529)
		(stroke
			(width 0.2)
			(type default)
		)
		(layer "In1.Cu")
	)
	(gr_arc
		(start 78.648814 -31.53283)
		(mid 79.006446 -31.20517)
		(end 78.678786 -30.847538)
		(stroke
			(width 0.2)
			(type default)
		)
		(layer "In1.Cu")
	)
	(gr_line
		(start 78.678786 -30.847538)
		(end 78.12024 -30.823154)
		(stroke
			(width 0.2)
			(type default)
		)
		(layer "In1.Cu")
	)
	(gr_rect
		(start 78.991714 -4.097528)
		(end 79.707994 -8.293608)
		(stroke
			(width 0)
			(type default)
		)
		(fill no)
		(layer "In1.Cu")
	)
	(gr_line
		(start 79.370936 -10.7188)
		(end 80.328516 -10.7188)
		(stroke
			(width 0.2)
			(type default)
		)
		(layer "In1.Cu")
	)
	(gr_arc
		(start 79.37119 -9.95172)
		(mid 78.987396 -10.335133)
		(end 79.370936 -10.7188)
		(stroke
			(width 0.2)
			(type default)
		)
		(layer "In1.Cu")
	)
	(gr_rect
		(start 79.991712 -4.097528)
		(end 80.707992 -8.293608)
		(stroke
			(width 0)
			(type default)
		)
		(fill no)
		(layer "In1.Cu")
	)
	(gr_line
		(start 80.2132 -14.96314)
		(end 81.076546 -14.96314)
		(stroke
			(width 0.2)
			(type default)
		)
		(layer "In1.Cu")
	)
	(gr_arc
		(start 80.2132 -14.19606)
		(mid 79.82966 -14.5796)
		(end 80.2132 -14.96314)
		(stroke
			(width 0.2)
			(type default)
		)
		(layer "In1.Cu")
	)
	(gr_arc
		(start 80.2259 -54.685946)
		(mid 80.568673 -55.0291)
		(end 80.9117 -54.6862)
		(stroke
			(width 0.2)
			(type default)
		)
		(layer "In1.Cu")
	)
	(gr_line
		(start 80.2259 -54.1274)
		(end 80.2259 -54.685946)
		(stroke
			(width 0.2)
			(type default)
		)
		(layer "In1.Cu")
	)
	(gr_line
		(start 80.264 -60.7187)
		(end 81.0514 -60.7187)
		(stroke
			(width 0.2)
			(type default)
		)
		(layer "In1.Cu")
	)
	(gr_arc
		(start 80.264254 -60.0329)
		(mid 79.9211 -60.375673)
		(end 80.264 -60.7187)
		(stroke
			(width 0.2)
			(type default)
		)
		(layer "In1.Cu")
	)
	(gr_arc
		(start 80.328516 -10.7188)
		(mid 80.712056 -10.33526)
		(end 80.328516 -9.95172)
		(stroke
			(width 0.2)
			(type default)
		)
		(layer "In1.Cu")
	)
	(gr_line
		(start 80.328516 -9.95172)
		(end 79.37119 -9.95172)
		(stroke
			(width 0.2)
			(type default)
		)
		(layer "In1.Cu")
	)
	(gr_line
		(start 80.9117 -54.6862)
		(end 80.9117 -54.1274)
		(stroke
			(width 0.2)
			(type default)
		)
		(layer "In1.Cu")
	)
	(gr_arc
		(start 80.9117 -54.1274)
		(mid 80.5688 -53.7845)
		(end 80.2259 -54.1274)
		(stroke
			(width 0.2)
			(type default)
		)
		(layer "In1.Cu")
	)
	(gr_arc
		(start 81.0514 -60.7187)
		(mid 81.3943 -60.3758)
		(end 81.0514 -60.0329)
		(stroke
			(width 0.2)
			(type default)
		)
		(layer "In1.Cu")
	)
	(gr_line
		(start 81.0514 -60.0329)
		(end 80.264254 -60.0329)
		(stroke
			(width 0.2)
			(type default)
		)
		(layer "In1.Cu")
	)
	(gr_arc
		(start 81.076546 -14.96314)
		(mid 81.46034 -14.579727)
		(end 81.0768 -14.19606)
		(stroke
			(width 0.2)
			(type default)
		)
		(layer "In1.Cu")
	)
	(gr_line
		(start 81.0768 -14.19606)
		(end 80.2132 -14.19606)
		(stroke
			(width 0.2)
			(type default)
		)
		(layer "In1.Cu")
	)
	(gr_arc
		(start 81.3435 -53.593746)
		(mid 81.686273 -53.9369)
		(end 82.0293 -53.594)
		(stroke
			(width 0.2)
			(type default)
		)
		(layer "In1.Cu")
	)
	(gr_line
		(start 81.3435 -53.0098)
		(end 81.3435 -53.593746)
		(stroke
			(width 0.2)
			(type default)
		)
		(layer "In1.Cu")
	)
	(gr_line
		(start 82.0293 -53.594)
		(end 82.0293 -53.0098)
		(stroke
			(width 0.2)
			(type default)
		)
		(layer "In1.Cu")
	)
	(gr_arc
		(start 82.0293 -53.0098)
		(mid 81.6864 -52.6669)
		(end 81.3435 -53.0098)
		(stroke
			(width 0.2)
			(type default)
		)
		(layer "In1.Cu")
	)
	(gr_line
		(start 82.296 -14.32814)
		(end 83.1596 -14.32814)
		(stroke
			(width 0.2)
			(type default)
		)
		(layer "In1.Cu")
	)
	(gr_arc
		(start 82.296254 -13.56106)
		(mid 81.91246 -13.944473)
		(end 82.296 -14.32814)
		(stroke
			(width 0.2)
			(type default)
		)
		(layer "In1.Cu")
	)
	(gr_arc
		(start 82.803746 -55.65902)
		(mid 82.83702 -56.146446)
		(end 83.324446 -56.113172)
		(stroke
			(width 0.2)
			(type default)
		)
		(layer "In1.Cu")
	)
	(gr_rect
		(start 82.991706 -4.097528)
		(end 83.707986 -8.293608)
		(stroke
			(width 0)
			(type default)
		)
		(fill no)
		(layer "In1.Cu")
	)
	(gr_arc
		(start 83.1596 -14.32814)
		(mid 83.54314 -13.9446)
		(end 83.1596 -13.56106)
		(stroke
			(width 0.2)
			(type default)
		)
		(layer "In1.Cu")
	)
	(gr_line
		(start 83.1596 -13.56106)
		(end 82.296254 -13.56106)
		(stroke
			(width 0.2)
			(type default)
		)
		(layer "In1.Cu")
	)
	(gr_line
		(start 83.18119 -55.226204)
		(end 82.803746 -55.65902)
		(stroke
			(width 0.2)
			(type default)
		)
		(layer "In1.Cu")
	)
	(gr_arc
		(start 83.309968 -59.661806)
		(mid 83.308952 -60.146946)
		(end 83.794092 -60.147962)
		(stroke
			(width 0.2)
			(type default)
		)
		(layer "In1.Cu")
	)
	(gr_line
		(start 83.324446 -56.113172)
		(end 83.701636 -55.68061)
		(stroke
			(width 0.2)
			(type default)
		)
		(layer "In1.Cu")
	)
	(gr_line
		(start 83.388962 -10.79627)
		(end 84.310474 -10.79627)
		(stroke
			(width 0.2)
			(type default)
		)
		(layer "In1.Cu")
	)
	(gr_arc
		(start 83.389216 -10.02919)
		(mid 83.005422 -10.412603)
		(end 83.388962 -10.79627)
		(stroke
			(width 0.2)
			(type default)
		)
		(layer "In1.Cu")
	)
	(gr_arc
		(start 83.701636 -55.68061)
		(mid 83.668625 -55.193446)
		(end 83.18119 -55.226204)
		(stroke
			(width 0.2)
			(type default)
		)
		(layer "In1.Cu")
	)
	(gr_line
		(start 83.794092 -60.147962)
		(end 84.348828 -59.595258)
		(stroke
			(width 0.2)
			(type default)
		)
		(layer "In1.Cu")
	)
	(gr_line
		(start 83.868006 -59.106054)
		(end 83.309968 -59.661806)
		(stroke
			(width 0.2)
			(type default)
		)
		(layer "In1.Cu")
	)
	(gr_arc
		(start 83.885024 -54.567836)
		(mid 84.22386 -54.91988)
		(end 84.575904 -54.581044)
		(stroke
			(width 0.2)
			(type default)
		)
		(layer "In1.Cu")
	)
	(gr_line
		(start 83.895692 -54.009036)
		(end 83.885024 -54.567836)
		(stroke
			(width 0.2)
			(type default)
		)
		(layer "In1.Cu")
	)
	(gr_rect
		(start 83.991704 -4.097528)
		(end 84.707984 -8.293608)
		(stroke
			(width 0)
			(type default)
		)
		(fill no)
		(layer "In1.Cu")
	)
	(gr_arc
		(start 84.310474 -10.79627)
		(mid 84.694014 -10.41273)
		(end 84.310474 -10.02919)
		(stroke
			(width 0.2)
			(type default)
		)
		(layer "In1.Cu")
	)
	(gr_line
		(start 84.310474 -10.02919)
		(end 83.389216 -10.02919)
		(stroke
			(width 0.2)
			(type default)
		)
		(layer "In1.Cu")
	)
	(gr_arc
		(start 84.348828 -59.595258)
		(mid 84.354625 -59.108766)
		(end 83.868006 -59.106054)
		(stroke
			(width 0.2)
			(type default)
		)
		(layer "In1.Cu")
	)
	(gr_line
		(start 84.575904 -54.581044)
		(end 84.586572 -54.022498)
		(stroke
			(width 0.2)
			(type default)
		)
		(layer "In1.Cu")
	)
	(gr_arc
		(start 84.586572 -54.022498)
		(mid 84.247863 -53.670456)
		(end 83.895692 -54.009036)
		(stroke
			(width 0.2)
			(type default)
		)
		(layer "In1.Cu")
	)
	(gr_arc
		(start 85.330538 -55.356506)
		(mid 85.670517 -55.707536)
		(end 86.021418 -55.367428)
		(stroke
			(width 0.2)
			(type default)
		)
		(layer "In1.Cu")
	)
	(gr_line
		(start 85.339174 -54.79034)
		(end 85.330538 -55.356506)
		(stroke
			(width 0.2)
			(type default)
		)
		(layer "In1.Cu")
	)
	(gr_arc
		(start 85.741764 -53.758592)
		(mid 86.080727 -54.110638)
		(end 86.432644 -53.771546)
		(stroke
			(width 0.2)
			(type default)
		)
		(layer "In1.Cu")
	)
	(gr_line
		(start 85.752178 -53.19522)
		(end 85.741764 -53.758592)
		(stroke
			(width 0.2)
			(type default)
		)
		(layer "In1.Cu")
	)
	(gr_line
		(start 86.021418 -55.367428)
		(end 86.030054 -54.801008)
		(stroke
			(width 0.2)
			(type default)
		)
		(layer "In1.Cu")
	)
	(gr_arc
		(start 86.030054 -54.801008)
		(mid 85.689948 -54.450234)
		(end 85.339174 -54.79034)
		(stroke
			(width 0.2)
			(type default)
		)
		(layer "In1.Cu")
	)
	(gr_line
		(start 86.432644 -53.771546)
		(end 86.443058 -53.20792)
		(stroke
			(width 0.2)
			(type default)
		)
		(layer "In1.Cu")
	)
	(gr_arc
		(start 86.443058 -53.20792)
		(mid 86.103968 -52.85613)
		(end 85.752178 -53.19522)
		(stroke
			(width 0.2)
			(type default)
		)
		(layer "In1.Cu")
	)
	(gr_arc
		(start 86.826852 -54.834028)
		(mid 87.165307 -55.186583)
		(end 87.517732 -54.847998)
		(stroke
			(width 0.2)
			(type default)
		)
		(layer "In1.Cu")
	)
	(gr_line
		(start 86.838028 -54.270402)
		(end 86.826852 -54.834028)
		(stroke
			(width 0.2)
			(type default)
		)
		(layer "In1.Cu")
	)
	(gr_line
		(start 87.517732 -54.847998)
		(end 87.528908 -54.284118)
		(stroke
			(width 0.2)
			(type default)
		)
		(layer "In1.Cu")
	)
	(gr_arc
		(start 87.528908 -54.284118)
		(mid 87.190326 -53.93182)
		(end 86.838028 -54.270402)
		(stroke
			(width 0.2)
			(type default)
		)
		(layer "In1.Cu")
	)
	(gr_line
		(start 87.940896 -53.421534)
		(end 87.95893 -53.98008)
		(stroke
			(width 0.2)
			(type default)
		)
		(layer "In1.Cu")
	)
	(gr_line
		(start 87.943436 -53.421534)
		(end 87.940896 -53.421534)
		(stroke
			(width 0.2)
			(type default)
		)
		(layer "In1.Cu")
	)
	(gr_line
		(start 87.95893 -53.98008)
		(end 87.96147 -53.98008)
		(stroke
			(width 0.2)
			(type default)
		)
		(layer "In1.Cu")
	)
	(gr_arc
		(start 87.96147 -53.98008)
		(mid 88.317832 -54.31409)
		(end 88.651842 -53.957728)
		(stroke
			(width 0.2)
			(type default)
		)
		(layer "In1.Cu")
	)
	(gr_arc
		(start 88.633808 -53.399182)
		(mid 88.277446 -53.065172)
		(end 87.943436 -53.421534)
		(stroke
			(width 0.2)
			(type default)
		)
		(layer "In1.Cu")
	)
	(gr_line
		(start 88.636094 -53.399182)
		(end 88.633808 -53.399182)
		(stroke
			(width 0.2)
			(type default)
		)
		(layer "In1.Cu")
	)
	(gr_line
		(start 88.636348 -53.399436)
		(end 88.636094 -53.399182)
		(stroke
			(width 0.2)
			(type default)
		)
		(layer "In1.Cu")
	)
	(gr_line
		(start 88.651842 -53.957728)
		(end 88.654382 -53.957728)
		(stroke
			(width 0.2)
			(type default)
		)
		(layer "In1.Cu")
	)
	(gr_line
		(start 88.654382 -53.957728)
		(end 88.636348 -53.399436)
		(stroke
			(width 0.2)
			(type default)
		)
		(layer "In1.Cu")
	)
	(gr_arc
		(start 89.415874 -54.043326)
		(mid 89.727024 -54.420008)
		(end 90.103706 -54.108858)
		(stroke
			(width 0.2)
			(type default)
		)
		(layer "In1.Cu")
	)
	(gr_line
		(start 89.46896 -53.486812)
		(end 89.415874 -54.043326)
		(stroke
			(width 0.2)
			(type default)
		)
		(layer "In1.Cu")
	)
	(gr_line
		(start 90.103706 -54.108858)
		(end 90.156792 -53.552598)
		(stroke
			(width 0.2)
			(type default)
		)
		(layer "In1.Cu")
	)
	(gr_arc
		(start 90.156792 -53.552598)
		(mid 89.845768 -53.175928)
		(end 89.46896 -53.486812)
		(stroke
			(width 0.2)
			(type default)
		)
		(layer "In1.Cu")
	)
	(gr_line
		(start 90.681556 -53.93817)
		(end 90.684096 -53.938424)
		(stroke
			(width 0.2)
			(type default)
		)
		(layer "In1.Cu")
	)
	(gr_arc
		(start 90.684096 -53.938424)
		(mid 91.010994 -54.30139)
		(end 91.37396 -53.974492)
		(stroke
			(width 0.2)
			(type default)
		)
		(layer "In1.Cu")
	)
	(gr_line
		(start 90.71102 -53.377592)
		(end 90.681556 -53.93817)
		(stroke
			(width 0.2)
			(type default)
		)
		(layer "In1.Cu")
	)
	(gr_line
		(start 90.71356 -53.377846)
		(end 90.71102 -53.377592)
		(stroke
			(width 0.2)
			(type default)
		)
		(layer "In1.Cu")
	)
	(gr_line
		(start 90.73769 -54.954932)
		(end 90.73896 -54.956964)
		(stroke
			(width 0.2)
			(type default)
		)
		(layer "In1.Cu")
	)
	(gr_line
		(start 90.73769 -54.954678)
		(end 90.73769 -54.954932)
		(stroke
			(width 0.2)
			(type default)
		)
		(layer "In1.Cu")
	)
	(gr_arc
		(start 90.73896 -54.956964)
		(mid 90.631264 -55.433468)
		(end 91.107768 -55.541164)
		(stroke
			(width 0.2)
			(type default)
		)
		(layer "In1.Cu")
	)
	(gr_line
		(start 91.107768 -55.541164)
		(end 91.109038 -55.543196)
		(stroke
			(width 0.2)
			(type default)
		)
		(layer "In1.Cu")
	)
	(gr_line
		(start 91.109038 -55.543196)
		(end 91.581732 -55.244746)
		(stroke
			(width 0.2)
			(type default)
		)
		(layer "In1.Cu")
	)
	(gr_line
		(start 91.210384 -54.656482)
		(end 90.73769 -54.954678)
		(stroke
			(width 0.2)
			(type default)
		)
		(layer "In1.Cu")
	)
	(gr_line
		(start 91.211654 -54.658514)
		(end 91.210384 -54.656482)
		(stroke
			(width 0.2)
			(type default)
		)
		(layer "In1.Cu")
	)
	(gr_line
		(start 91.37396 -53.974492)
		(end 91.403424 -53.414168)
		(stroke
			(width 0.2)
			(type default)
		)
		(layer "In1.Cu")
	)
	(gr_arc
		(start 91.403424 -53.414168)
		(mid 91.076653 -53.050941)
		(end 90.71356 -53.377846)
		(stroke
			(width 0.2)
			(type default)
		)
		(layer "In1.Cu")
	)
	(gr_arc
		(start 91.580462 -55.242714)
		(mid 91.688158 -54.76621)
		(end 91.211654 -54.658514)
		(stroke
			(width 0.2)
			(type default)
		)
		(layer "In1.Cu")
	)
	(gr_line
		(start 91.581732 -55.244746)
		(end 91.580462 -55.242714)
		(stroke
			(width 0.2)
			(type default)
		)
		(layer "In1.Cu")
	)
	(gr_line
		(start 98.552 -49.53)
		(end 98.552 -46.609)
		(stroke
			(width 0.381)
			(type default)
		)
		(layer "In1.Cu")
	)
	(gr_line
		(start 98.552 -46.609)
		(end 100.076 -45.085)
		(stroke
			(width 0.381)
			(type default)
		)
		(layer "In1.Cu")
	)
	(gr_line
		(start 98.552 -32.004)
		(end 98.806 -32.258)
		(stroke
			(width 0.381)
			(type default)
		)
		(layer "In1.Cu")
	)
	(gr_line
		(start 98.552 -31.242)
		(end 98.552 -32.004)
		(stroke
			(width 0.381)
			(type default)
		)
		(layer "In1.Cu")
	)
	(gr_line
		(start 98.806 -32.258)
		(end 99.187 -32.258)
		(stroke
			(width 0.381)
			(type default)
		)
		(layer "In1.Cu")
	)
	(gr_line
		(start 98.933 -49.911)
		(end 98.552 -49.53)
		(stroke
			(width 0.381)
			(type default)
		)
		(layer "In1.Cu")
	)
	(gr_line
		(start 99.06 -30.734)
		(end 98.552 -31.242)
		(stroke
			(width 0.381)
			(type default)
		)
		(layer "In1.Cu")
	)
	(gr_line
		(start 99.06 -28.829)
		(end 99.06 -30.734)
		(stroke
			(width 0.381)
			(type default)
		)
		(layer "In1.Cu")
	)
	(gr_line
		(start 99.187 -32.258)
		(end 99.695 -32.766)
		(stroke
			(width 0.381)
			(type default)
		)
		(layer "In1.Cu")
	)
	(gr_line
		(start 99.24542 -60.922154)
		(end 99.86518 -61.523372)
		(stroke
			(width 0.2)
			(type default)
		)
		(layer "In1.Cu")
	)
	(gr_line
		(start 99.247198 -60.920376)
		(end 99.24542 -60.922154)
		(stroke
			(width 0.2)
			(type default)
		)
		(layer "In1.Cu")
	)
	(gr_line
		(start 99.695 -32.766)
		(end 100.33 -32.766)
		(stroke
			(width 0.381)
			(type default)
		)
		(layer "In1.Cu")
	)
	(gr_arc
		(start 99.781106 -60.369704)
		(mid 99.238816 -60.378086)
		(end 99.247198 -60.920376)
		(stroke
			(width 0.2)
			(type default)
		)
		(layer "In1.Cu")
	)
	(gr_line
		(start 99.782884 -60.367926)
		(end 99.781106 -60.369704)
		(stroke
			(width 0.2)
			(type default)
		)
		(layer "In1.Cu")
	)
	(gr_line
		(start 99.822 -28.067)
		(end 99.06 -28.829)
		(stroke
			(width 0.381)
			(type default)
		)
		(layer "In1.Cu")
	)
	(gr_line
		(start 99.86518 -61.523372)
		(end 99.865434 -61.523372)
		(stroke
			(width 0.2)
			(type default)
		)
		(layer "In1.Cu")
	)
	(gr_line
		(start 99.865434 -61.523372)
		(end 99.866958 -61.521848)
		(stroke
			(width 0.2)
			(type default)
		)
		(layer "In1.Cu")
	)
	(gr_arc
		(start 99.866958 -61.521848)
		(mid 100.409565 -61.513655)
		(end 100.40112 -60.971176)
		(stroke
			(width 0.2)
			(type default)
		)
		(layer "In1.Cu")
	)
	(gr_line
		(start 100.076 -45.085)
		(end 101.092 -45.085)
		(stroke
			(width 0.381)
			(type default)
		)
		(layer "In1.Cu")
	)
	(gr_line
		(start 100.33 -32.766)
		(end 100.584 -33.02)
		(stroke
			(width 0.381)
			(type default)
		)
		(layer "In1.Cu")
	)
	(gr_line
		(start 100.40112 -60.971176)
		(end 100.402898 -60.969398)
		(stroke
			(width 0.2)
			(type default)
		)
		(layer "In1.Cu")
	)
	(gr_line
		(start 100.402898 -60.969398)
		(end 99.782884 -60.367926)
		(stroke
			(width 0.2)
			(type default)
		)
		(layer "In1.Cu")
	)
	(gr_line
		(start 100.584 -33.02)
		(end 101.473 -33.02)
		(stroke
			(width 0.381)
			(type default)
		)
		(layer "In1.Cu")
	)
	(gr_line
		(start 101.092 -45.085)
		(end 103.124 -45.085)
		(stroke
			(width 0.381)
			(type default)
		)
		(layer "In1.Cu")
	)
	(gr_line
		(start 101.185472 -62.20587)
		(end 101.795072 -62.817756)
		(stroke
			(width 0.2)
			(type default)
		)
		(layer "In1.Cu")
	)
	(gr_line
		(start 101.473 -33.02)
		(end 103.251 -33.02)
		(stroke
			(width 0.381)
			(type default)
		)
		(layer "In1.Cu")
	)
	(gr_arc
		(start 101.734366 -61.66993)
		(mid 101.189299 -61.660676)
		(end 101.185472 -62.20587)
		(stroke
			(width 0.2)
			(type default)
		)
		(layer "In1.Cu")
	)
	(gr_arc
		(start 101.795072 -62.817756)
		(mid 102.337616 -62.818772)
		(end 102.338632 -62.276228)
		(stroke
			(width 0.2)
			(type default)
		)
		(layer "In1.Cu")
	)
	(gr_line
		(start 102.338632 -62.276228)
		(end 101.734366 -61.66993)
		(stroke
			(width 0.2)
			(type default)
		)
		(layer "In1.Cu")
	)
	(gr_line
		(start 103.124 -45.085)
		(end 103.378 -45.339)
		(stroke
			(width 0.381)
			(type default)
		)
		(layer "In1.Cu")
	)
	(gr_line
		(start 103.251 -33.02)
		(end 104.013 -32.258)
		(stroke
			(width 0.381)
			(type default)
		)
		(layer "In1.Cu")
	)
	(gr_line
		(start 103.378 -45.72)
		(end 104.14 -46.482)
		(stroke
			(width 0.381)
			(type default)
		)
		(layer "In1.Cu")
	)
	(gr_line
		(start 103.378 -45.339)
		(end 103.378 -45.72)
		(stroke
			(width 0.381)
			(type default)
		)
		(layer "In1.Cu")
	)
	(gr_line
		(start 104.013 -49.911)
		(end 98.933 -49.911)
		(stroke
			(width 0.381)
			(type default)
		)
		(layer "In1.Cu")
	)
	(gr_line
		(start 104.013 -32.258)
		(end 104.013 -30.988)
		(stroke
			(width 0.381)
			(type default)
		)
		(layer "In1.Cu")
	)
	(gr_line
		(start 104.013 -30.988)
		(end 105.029 -29.972)
		(stroke
			(width 0.381)
			(type default)
		)
		(layer "In1.Cu")
	)
	(gr_line
		(start 104.013 -28.067)
		(end 99.822 -28.067)
		(stroke
			(width 0.381)
			(type default)
		)
		(layer "In1.Cu")
	)
	(gr_line
		(start 104.14 -46.482)
		(end 105.41 -46.482)
		(stroke
			(width 0.381)
			(type default)
		)
		(layer "In1.Cu")
	)
	(gr_line
		(start 104.267 -28.321)
		(end 104.013 -28.067)
		(stroke
			(width 0.381)
			(type default)
		)
		(layer "In1.Cu")
	)
	(gr_line
		(start 104.394 -49.53)
		(end 104.013 -49.911)
		(stroke
			(width 0.381)
			(type default)
		)
		(layer "In1.Cu")
	)
	(gr_line
		(start 105.029 -29.972)
		(end 105.664 -29.972)
		(stroke
			(width 0.381)
			(type default)
		)
		(layer "In1.Cu")
	)
	(gr_line
		(start 105.156 -49.53)
		(end 104.394 -49.53)
		(stroke
			(width 0.381)
			(type default)
		)
		(layer "In1.Cu")
	)
	(gr_line
		(start 105.41 -51.054)
		(end 105.41 -49.784)
		(stroke
			(width 0.381)
			(type default)
		)
		(layer "In1.Cu")
	)
	(gr_line
		(start 105.41 -49.784)
		(end 105.156 -49.53)
		(stroke
			(width 0.381)
			(type default)
		)
		(layer "In1.Cu")
	)
	(gr_line
		(start 105.41 -46.482)
		(end 105.791 -46.101)
		(stroke
			(width 0.381)
			(type default)
		)
		(layer "In1.Cu")
	)
	(gr_line
		(start 105.664 -51.308)
		(end 105.41 -51.054)
		(stroke
			(width 0.381)
			(type default)
		)
		(layer "In1.Cu")
	)
	(gr_line
		(start 105.664 -29.972)
		(end 105.791 -30.099)
		(stroke
			(width 0.381)
			(type default)
		)
		(layer "In1.Cu")
	)
	(gr_line
		(start 105.791 -46.101)
		(end 106.807 -46.101)
		(stroke
			(width 0.381)
			(type default)
		)
		(layer "In1.Cu")
	)
	(gr_line
		(start 105.791 -30.988)
		(end 106.553 -31.75)
		(stroke
			(width 0.381)
			(type default)
		)
		(layer "In1.Cu")
	)
	(gr_line
		(start 105.791 -30.099)
		(end 105.791 -30.988)
		(stroke
			(width 0.381)
			(type default)
		)
		(layer "In1.Cu")
	)
	(gr_line
		(start 106.299 -51.308)
		(end 105.664 -51.308)
		(stroke
			(width 0.381)
			(type default)
		)
		(layer "In1.Cu")
	)
	(gr_line
		(start 106.553 -31.75)
		(end 107.95 -31.75)
		(stroke
			(width 0.381)
			(type default)
		)
		(layer "In1.Cu")
	)
	(gr_line
		(start 106.68 -53.594)
		(end 106.68 -53.34)
		(stroke
			(width 0.381)
			(type default)
		)
		(layer "In1.Cu")
	)
	(gr_line
		(start 106.68 -53.34)
		(end 106.934 -53.086)
		(stroke
			(width 0.381)
			(type default)
		)
		(layer "In1.Cu")
	)
	(gr_line
		(start 106.807 -46.101)
		(end 107.188 -46.482)
		(stroke
			(width 0.381)
			(type default)
		)
		(layer "In1.Cu")
	)
	(gr_line
		(start 106.934 -53.848)
		(end 106.68 -53.594)
		(stroke
			(width 0.381)
			(type default)
		)
		(layer "In1.Cu")
	)
	(gr_line
		(start 106.934 -53.086)
		(end 106.934 -51.943)
		(stroke
			(width 0.381)
			(type default)
		)
		(layer "In1.Cu")
	)
	(gr_line
		(start 106.934 -51.943)
		(end 106.299 -51.308)
		(stroke
			(width 0.381)
			(type default)
		)
		(layer "In1.Cu")
	)
	(gr_line
		(start 107.188 -46.482)
		(end 108.966 -46.482)
		(stroke
			(width 0.381)
			(type default)
		)
		(layer "In1.Cu")
	)
	(gr_line
		(start 107.188 -28.321)
		(end 104.267 -28.321)
		(stroke
			(width 0.381)
			(type default)
		)
		(layer "In1.Cu")
	)
	(gr_line
		(start 107.315 -53.848)
		(end 106.934 -53.848)
		(stroke
			(width 0.381)
			(type default)
		)
		(layer "In1.Cu")
	)
	(gr_line
		(start 107.696 -53.467)
		(end 107.315 -53.848)
		(stroke
			(width 0.381)
			(type default)
		)
		(layer "In1.Cu")
	)
	(gr_line
		(start 107.696 -52.832)
		(end 107.696 -53.467)
		(stroke
			(width 0.381)
			(type default)
		)
		(layer "In1.Cu")
	)
	(gr_line
		(start 107.696 -27.813)
		(end 107.188 -28.321)
		(stroke
			(width 0.381)
			(type default)
		)
		(layer "In1.Cu")
	)
	(gr_line
		(start 107.696 -26.924)
		(end 107.696 -27.813)
		(stroke
			(width 0.381)
			(type default)
		)
		(layer "In1.Cu")
	)
	(gr_line
		(start 107.95 -31.75)
		(end 108.712 -32.512)
		(stroke
			(width 0.381)
			(type default)
		)
		(layer "In1.Cu")
	)
	(gr_line
		(start 108.077 -52.451)
		(end 107.696 -52.832)
		(stroke
			(width 0.381)
			(type default)
		)
		(layer "In1.Cu")
	)
	(gr_line
		(start 108.331 -26.289)
		(end 107.696 -26.924)
		(stroke
			(width 0.381)
			(type default)
		)
		(layer "In1.Cu")
	)
	(gr_line
		(start 108.712 -32.512)
		(end 109.093 -32.512)
		(stroke
			(width 0.381)
			(type default)
		)
		(layer "In1.Cu")
	)
	(gr_line
		(start 108.839 -52.451)
		(end 108.077 -52.451)
		(stroke
			(width 0.381)
			(type default)
		)
		(layer "In1.Cu")
	)
	(gr_line
		(start 108.966 -46.482)
		(end 110.998 -48.514)
		(stroke
			(width 0.381)
			(type default)
		)
		(layer "In1.Cu")
	)
	(gr_line
		(start 109.093 -32.512)
		(end 109.347 -32.258)
		(stroke
			(width 0.381)
			(type default)
		)
		(layer "In1.Cu")
	)
	(gr_line
		(start 109.347 -32.258)
		(end 110.236 -32.258)
		(stroke
			(width 0.381)
			(type default)
		)
		(layer "In1.Cu")
	)
	(gr_line
		(start 109.474 -26.289)
		(end 108.331 -26.289)
		(stroke
			(width 0.381)
			(type default)
		)
		(layer "In1.Cu")
	)
	(gr_line
		(start 109.601 -27.686)
		(end 109.601 -26.416)
		(stroke
			(width 0.381)
			(type default)
		)
		(layer "In1.Cu")
	)
	(gr_line
		(start 109.601 -26.416)
		(end 109.474 -26.289)
		(stroke
			(width 0.381)
			(type default)
		)
		(layer "In1.Cu")
	)
	(gr_line
		(start 110.109 -28.194)
		(end 109.601 -27.686)
		(stroke
			(width 0.381)
			(type default)
		)
		(layer "In1.Cu")
	)
	(gr_line
		(start 110.236 -32.258)
		(end 110.998 -33.02)
		(stroke
			(width 0.381)
			(type default)
		)
		(layer "In1.Cu")
	)
	(gr_line
		(start 110.617 -50.673)
		(end 108.839 -52.451)
		(stroke
			(width 0.381)
			(type default)
		)
		(layer "In1.Cu")
	)
	(gr_line
		(start 110.998 -48.514)
		(end 111.506 -48.514)
		(stroke
			(width 0.381)
			(type default)
		)
		(layer "In1.Cu")
	)
	(gr_line
		(start 110.998 -33.02)
		(end 111.379 -33.02)
		(stroke
			(width 0.381)
			(type default)
		)
		(layer "In1.Cu")
	)
	(gr_line
		(start 111.379 -33.02)
		(end 111.76 -32.639)
		(stroke
			(width 0.381)
			(type default)
		)
		(layer "In1.Cu")
	)
	(gr_line
		(start 111.506 -48.514)
		(end 112.014 -49.022)
		(stroke
			(width 0.381)
			(type default)
		)
		(layer "In1.Cu")
	)
	(gr_line
		(start 111.633 -28.194)
		(end 110.109 -28.194)
		(stroke
			(width 0.381)
			(type default)
		)
		(layer "In1.Cu")
	)
	(gr_line
		(start 111.76 -50.673)
		(end 110.617 -50.673)
		(stroke
			(width 0.381)
			(type default)
		)
		(layer "In1.Cu")
	)
	(gr_line
		(start 111.76 -32.639)
		(end 112.395 -32.639)
		(stroke
			(width 0.381)
			(type default)
		)
		(layer "In1.Cu")
	)
	(gr_line
		(start 112.014 -50.419)
		(end 111.76 -50.673)
		(stroke
			(width 0.381)
			(type default)
		)
		(layer "In1.Cu")
	)
	(gr_line
		(start 112.014 -49.022)
		(end 112.014 -50.419)
		(stroke
			(width 0.381)
			(type default)
		)
		(layer "In1.Cu")
	)
	(gr_line
		(start 112.395 -32.639)
		(end 113.284 -31.75)
		(stroke
			(width 0.381)
			(type default)
		)
		(layer "In1.Cu")
	)
	(gr_line
		(start 113.284 -31.75)
		(end 113.284 -29.845)
		(stroke
			(width 0.381)
			(type default)
		)
		(layer "In1.Cu")
	)
	(gr_line
		(start 113.284 -29.845)
		(end 111.633 -28.194)
		(stroke
			(width 0.381)
			(type default)
		)
		(layer "In1.Cu")
	)
	(gr_line
		(start 147.828 -61.214)
		(end 147.828 -59.182)
		(stroke
			(width 0.381)
			(type default)
		)
		(layer "In1.Cu")
	)
	(gr_line
		(start 147.828 -59.182)
		(end 148.082 -58.928)
		(stroke
			(width 0.381)
			(type default)
		)
		(layer "In1.Cu")
	)
	(gr_line
		(start 148.082 -58.928)
		(end 149.987 -58.928)
		(stroke
			(width 0.381)
			(type default)
		)
		(layer "In1.Cu")
	)
	(gr_line
		(start 148.463 -71.501)
		(end 148.463 -61.849)
		(stroke
			(width 0.381)
			(type default)
		)
		(layer "In1.Cu")
	)
	(gr_line
		(start 148.463 -61.849)
		(end 147.828 -61.214)
		(stroke
			(width 0.381)
			(type default)
		)
		(layer "In1.Cu")
	)
	(gr_line
		(start 148.717 -71.755)
		(end 148.463 -71.501)
		(stroke
			(width 0.381)
			(type default)
		)
		(layer "In1.Cu")
	)
	(gr_line
		(start 149.987 -58.928)
		(end 151.003 -59.944)
		(stroke
			(width 0.381)
			(type default)
		)
		(layer "In1.Cu")
	)
	(gr_line
		(start 151.003 -59.944)
		(end 160.147 -59.944)
		(stroke
			(width 0.381)
			(type default)
		)
		(layer "In1.Cu")
	)
	(gr_line
		(start 155.702 -10.287)
		(end 156.21 -10.795)
		(stroke
			(width 0.381)
			(type default)
		)
		(layer "In1.Cu")
	)
	(gr_line
		(start 155.702 -0.635)
		(end 155.702 -10.287)
		(stroke
			(width 0.381)
			(type default)
		)
		(layer "In1.Cu")
	)
	(gr_line
		(start 156.21 -12.446)
		(end 156.591 -12.827)
		(stroke
			(width 0.381)
			(type default)
		)
		(layer "In1.Cu")
	)
	(gr_line
		(start 156.21 -10.795)
		(end 156.21 -12.446)
		(stroke
			(width 0.381)
			(type default)
		)
		(layer "In1.Cu")
	)
	(gr_line
		(start 156.591 -12.827)
		(end 167.259 -12.827)
		(stroke
			(width 0.381)
			(type default)
		)
		(layer "In1.Cu")
	)
	(gr_line
		(start 160.147 -59.944)
		(end 162.814 -62.611)
		(stroke
			(width 0.381)
			(type default)
		)
		(layer "In1.Cu")
	)
	(gr_line
		(start 162.56 -71.755)
		(end 148.717 -71.755)
		(stroke
			(width 0.381)
			(type default)
		)
		(layer "In1.Cu")
	)
	(gr_line
		(start 162.814 -71.501)
		(end 162.56 -71.755)
		(stroke
			(width 0.381)
			(type default)
		)
		(layer "In1.Cu")
	)
	(gr_line
		(start 162.814 -62.611)
		(end 162.814 -71.501)
		(stroke
			(width 0.381)
			(type default)
		)
		(layer "In1.Cu")
	)
	(gr_line
		(start 167.259 -12.827)
		(end 170.053 -10.033)
		(stroke
			(width 0.381)
			(type default)
		)
		(layer "In1.Cu")
	)
	(gr_line
		(start 169.799 -3.683)
		(end 169.799 -0.635)
		(stroke
			(width 0.381)
			(type default)
		)
		(layer "In1.Cu")
	)
	(gr_line
		(start 170.053 -10.033)
		(end 170.053 -5.461)
		(stroke
			(width 0.381)
			(type default)
		)
		(layer "In1.Cu")
	)
	(gr_line
		(start 170.053 -5.461)
		(end 170.561 -4.953)
		(stroke
			(width 0.381)
			(type default)
		)
		(layer "In1.Cu")
	)
	(gr_line
		(start 170.561 -4.953)
		(end 170.561 -4.445)
		(stroke
			(width 0.381)
			(type default)
		)
		(layer "In1.Cu")
	)
	(gr_line
		(start 170.561 -4.445)
		(end 169.799 -3.683)
		(stroke
			(width 0.381)
			(type default)
		)
		(layer "In1.Cu")
	)
	(gr_line
		(start 20.09521 -15.488666)
		(end 20.338796 -15.732252)
		(stroke
			(width 0.05715)
			(type default)
		)
		(layer "In2.Cu")
	)
	(gr_line
		(start 20.809204 -15.732252)
		(end 21.05279 -15.488666)
		(stroke
			(width 0.05715)
			(type default)
		)
		(layer "In2.Cu")
	)
	(gr_line
		(start 21.053552 -16.999458)
		(end 21.126958 -17.072864)
		(stroke
			(width 0.05715)
			(type default)
		)
		(layer "In2.Cu")
	)
	(gr_line
		(start 21.05533 -16.530574)
		(end 21.353526 -16.530574)
		(stroke
			(width 0.05715)
			(type default)
		)
		(layer "In2.Cu")
	)
	(gr_line
		(start 21.353526 -16.530574)
		(end 21.595842 -16.77289)
		(stroke
			(width 0.05715)
			(type default)
		)
		(layer "In2.Cu")
	)
	(gr_line
		(start 21.595842 -16.77289)
		(end 21.595842 -17.071086)
		(stroke
			(width 0.05715)
			(type default)
		)
		(layer "In2.Cu")
	)
	(gr_line
		(start 21.6662 -13.8176)
		(end 21.862796 -14.014196)
		(stroke
			(width 0.05715)
			(type default)
		)
		(layer "In2.Cu")
	)
	(gr_line
		(start 22.333204 -14.014196)
		(end 22.5298 -13.8176)
		(stroke
			(width 0.05715)
			(type default)
		)
		(layer "In2.Cu")
	)
	(gr_line
		(start 25.4127 -13.8176)
		(end 25.609296 -14.014196)
		(stroke
			(width 0.05715)
			(type default)
		)
		(layer "In2.Cu")
	)
	(gr_line
		(start 26.079704 -14.014196)
		(end 26.2763 -13.8176)
		(stroke
			(width 0.05715)
			(type default)
		)
		(layer "In2.Cu")
	)
	(gr_line
		(start 26.381964 -16.48587)
		(end 26.45537 -16.559276)
		(stroke
			(width 0.05715)
			(type default)
		)
		(layer "In2.Cu")
	)
	(gr_line
		(start 26.383742 -16.016986)
		(end 26.681938 -16.016986)
		(stroke
			(width 0.05715)
			(type default)
		)
		(layer "In2.Cu")
	)
	(gr_line
		(start 26.681938 -16.016986)
		(end 26.924254 -16.259302)
		(stroke
			(width 0.05715)
			(type default)
		)
		(layer "In2.Cu")
	)
	(gr_line
		(start 26.924254 -16.259302)
		(end 26.924254 -16.557498)
		(stroke
			(width 0.05715)
			(type default)
		)
		(layer "In2.Cu")
	)
	(gr_line
		(start 27.168602 -17.272508)
		(end 27.242008 -17.345914)
		(stroke
			(width 0.05715)
			(type default)
		)
		(layer "In2.Cu")
	)
	(gr_line
		(start 27.17038 -16.803624)
		(end 27.468576 -16.803624)
		(stroke
			(width 0.05715)
			(type default)
		)
		(layer "In2.Cu")
	)
	(gr_line
		(start 27.468576 -16.803624)
		(end 27.710892 -17.04594)
		(stroke
			(width 0.05715)
			(type default)
		)
		(layer "In2.Cu")
	)
	(gr_line
		(start 27.710892 -17.04594)
		(end 27.710892 -17.344136)
		(stroke
			(width 0.05715)
			(type default)
		)
		(layer "In2.Cu")
	)
	(gr_line
		(start 27.95524 -18.059146)
		(end 28.028646 -18.132552)
		(stroke
			(width 0.05715)
			(type default)
		)
		(layer "In2.Cu")
	)
	(gr_line
		(start 27.957018 -17.590262)
		(end 28.255214 -17.590262)
		(stroke
			(width 0.05715)
			(type default)
		)
		(layer "In2.Cu")
	)
	(gr_line
		(start 28.255214 -17.590262)
		(end 28.49753 -17.832578)
		(stroke
			(width 0.05715)
			(type default)
		)
		(layer "In2.Cu")
	)
	(gr_line
		(start 28.49753 -17.832578)
		(end 28.49753 -18.130774)
		(stroke
			(width 0.05715)
			(type default)
		)
		(layer "In2.Cu")
	)
	(gr_line
		(start 29.4132 -14.5796)
		(end 29.609796 -14.776196)
		(stroke
			(width 0.05715)
			(type default)
		)
		(layer "In2.Cu")
	)
	(gr_line
		(start 30.080204 -14.776196)
		(end 30.2768 -14.5796)
		(stroke
			(width 0.05715)
			(type default)
		)
		(layer "In2.Cu")
	)
	(gr_line
		(start 31.69793 -23.62962)
		(end 31.771336 -23.703026)
		(stroke
			(width 0.05715)
			(type default)
		)
		(layer "In2.Cu")
	)
	(gr_line
		(start 31.699708 -23.160736)
		(end 31.99765 -23.160736)
		(stroke
			(width 0.05715)
			(type default)
		)
		(layer "In2.Cu")
	)
	(gr_line
		(start 31.99765 -23.160736)
		(end 32.24022 -23.403052)
		(stroke
			(width 0.05715)
			(type default)
		)
		(layer "In2.Cu")
	)
	(gr_line
		(start 32.24022 -23.403052)
		(end 32.24022 -23.701248)
		(stroke
			(width 0.05715)
			(type default)
		)
		(layer "In2.Cu")
	)
	(gr_line
		(start 32.484568 -24.416258)
		(end 32.557974 -24.489664)
		(stroke
			(width 0.05715)
			(type default)
		)
		(layer "In2.Cu")
	)
	(gr_line
		(start 32.486346 -23.947374)
		(end 32.784542 -23.947374)
		(stroke
			(width 0.05715)
			(type default)
		)
		(layer "In2.Cu")
	)
	(gr_line
		(start 32.784542 -23.947374)
		(end 33.026858 -24.18969)
		(stroke
			(width 0.05715)
			(type default)
		)
		(layer "In2.Cu")
	)
	(gr_line
		(start 33.026858 -24.18969)
		(end 33.026858 -24.487886)
		(stroke
			(width 0.05715)
			(type default)
		)
		(layer "In2.Cu")
	)
	(gr_line
		(start 33.4264 -14.5796)
		(end 33.622996 -14.776196)
		(stroke
			(width 0.05715)
			(type default)
		)
		(layer "In2.Cu")
	)
	(gr_line
		(start 34.093404 -14.776196)
		(end 34.29 -14.5796)
		(stroke
			(width 0.05715)
			(type default)
		)
		(layer "In2.Cu")
	)
	(gr_line
		(start 34.229548 -18.125948)
		(end 34.302954 -18.199354)
		(stroke
			(width 0.05715)
			(type default)
		)
		(layer "In2.Cu")
	)
	(gr_line
		(start 34.231326 -17.657064)
		(end 34.529522 -17.657064)
		(stroke
			(width 0.05715)
			(type default)
		)
		(layer "In2.Cu")
	)
	(gr_line
		(start 34.529522 -17.657064)
		(end 34.771838 -17.89938)
		(stroke
			(width 0.05715)
			(type default)
		)
		(layer "In2.Cu")
	)
	(gr_line
		(start 34.771838 -17.89938)
		(end 34.771838 -18.197576)
		(stroke
			(width 0.05715)
			(type default)
		)
		(layer "In2.Cu")
	)
	(gr_line
		(start 35.016186 -18.912586)
		(end 35.089592 -18.985992)
		(stroke
			(width 0.05715)
			(type default)
		)
		(layer "In2.Cu")
	)
	(gr_line
		(start 35.017964 -18.443702)
		(end 35.31616 -18.443702)
		(stroke
			(width 0.05715)
			(type default)
		)
		(layer "In2.Cu")
	)
	(gr_line
		(start 35.268408 -30.401514)
		(end 35.341814 -30.47492)
		(stroke
			(width 0.05715)
			(type default)
		)
		(layer "In2.Cu")
	)
	(gr_line
		(start 35.270186 -29.93263)
		(end 35.568382 -29.93263)
		(stroke
			(width 0.05715)
			(type default)
		)
		(layer "In2.Cu")
	)
	(gr_line
		(start 35.31616 -18.443702)
		(end 35.558476 -18.686018)
		(stroke
			(width 0.05715)
			(type default)
		)
		(layer "In2.Cu")
	)
	(gr_line
		(start 35.558476 -18.686018)
		(end 35.558476 -18.984214)
		(stroke
			(width 0.05715)
			(type default)
		)
		(layer "In2.Cu")
	)
	(gr_line
		(start 35.568382 -29.93263)
		(end 35.810698 -30.174946)
		(stroke
			(width 0.05715)
			(type default)
		)
		(layer "In2.Cu")
	)
	(gr_line
		(start 35.754564 -21.478748)
		(end 35.82797 -21.552154)
		(stroke
			(width 0.05715)
			(type default)
		)
		(layer "In2.Cu")
	)
	(gr_line
		(start 35.756342 -21.009864)
		(end 36.054538 -21.009864)
		(stroke
			(width 0.05715)
			(type default)
		)
		(layer "In2.Cu")
	)
	(gr_line
		(start 35.802824 -19.699224)
		(end 35.87623 -19.77263)
		(stroke
			(width 0.05715)
			(type default)
		)
		(layer "In2.Cu")
	)
	(gr_line
		(start 35.804602 -19.23034)
		(end 36.102798 -19.23034)
		(stroke
			(width 0.05715)
			(type default)
		)
		(layer "In2.Cu")
	)
	(gr_line
		(start 35.810698 -30.174946)
		(end 35.810698 -30.473142)
		(stroke
			(width 0.05715)
			(type default)
		)
		(layer "In2.Cu")
	)
	(gr_line
		(start 36.054538 -21.009864)
		(end 36.296854 -21.25218)
		(stroke
			(width 0.05715)
			(type default)
		)
		(layer "In2.Cu")
	)
	(gr_line
		(start 36.055046 -31.188152)
		(end 36.128452 -31.261558)
		(stroke
			(width 0.05715)
			(type default)
		)
		(layer "In2.Cu")
	)
	(gr_line
		(start 36.056824 -30.719268)
		(end 36.35502 -30.719268)
		(stroke
			(width 0.05715)
			(type default)
		)
		(layer "In2.Cu")
	)
	(gr_line
		(start 36.102798 -19.23034)
		(end 36.345114 -19.472656)
		(stroke
			(width 0.05715)
			(type default)
		)
		(layer "In2.Cu")
	)
	(gr_line
		(start 36.296854 -21.25218)
		(end 36.296854 -21.550376)
		(stroke
			(width 0.05715)
			(type default)
		)
		(layer "In2.Cu")
	)
	(gr_line
		(start 36.345114 -19.472656)
		(end 36.345114 -19.770852)
		(stroke
			(width 0.05715)
			(type default)
		)
		(layer "In2.Cu")
	)
	(gr_line
		(start 36.35502 -30.719268)
		(end 36.597336 -30.961584)
		(stroke
			(width 0.05715)
			(type default)
		)
		(layer "In2.Cu")
	)
	(gr_line
		(start 36.541202 -22.265386)
		(end 36.614608 -22.338792)
		(stroke
			(width 0.05715)
			(type default)
		)
		(layer "In2.Cu")
	)
	(gr_line
		(start 36.54298 -21.796502)
		(end 36.841176 -21.796502)
		(stroke
			(width 0.05715)
			(type default)
		)
		(layer "In2.Cu")
	)
	(gr_line
		(start 36.597336 -30.961584)
		(end 36.597336 -31.25978)
		(stroke
			(width 0.05715)
			(type default)
		)
		(layer "In2.Cu")
	)
	(gr_line
		(start 36.841176 -21.796502)
		(end 37.083492 -22.038818)
		(stroke
			(width 0.05715)
			(type default)
		)
		(layer "In2.Cu")
	)
	(gr_line
		(start 37.083492 -22.038818)
		(end 37.083492 -22.337014)
		(stroke
			(width 0.05715)
			(type default)
		)
		(layer "In2.Cu")
	)
	(gr_line
		(start 37.32784 -23.052024)
		(end 37.401246 -23.12543)
		(stroke
			(width 0.05715)
			(type default)
		)
		(layer "In2.Cu")
	)
	(gr_line
		(start 37.329618 -22.58314)
		(end 37.627814 -22.58314)
		(stroke
			(width 0.05715)
			(type default)
		)
		(layer "In2.Cu")
	)
	(gr_line
		(start 37.41801 -13.8176)
		(end 37.614606 -14.014196)
		(stroke
			(width 0.05715)
			(type default)
		)
		(layer "In2.Cu")
	)
	(gr_line
		(start 37.627814 -22.58314)
		(end 37.87013 -22.825456)
		(stroke
			(width 0.05715)
			(type default)
		)
		(layer "In2.Cu")
	)
	(gr_line
		(start 37.87013 -22.825456)
		(end 37.87013 -23.123652)
		(stroke
			(width 0.05715)
			(type default)
		)
		(layer "In2.Cu")
	)
	(gr_line
		(start 38.085014 -14.014196)
		(end 38.28161 -13.8176)
		(stroke
			(width 0.05715)
			(type default)
		)
		(layer "In2.Cu")
	)
	(gr_line
		(start 38.786308 -22.682708)
		(end 38.859714 -22.756114)
		(stroke
			(width 0.05715)
			(type default)
		)
		(layer "In2.Cu")
	)
	(gr_line
		(start 38.788086 -22.213824)
		(end 39.086282 -22.213824)
		(stroke
			(width 0.05715)
			(type default)
		)
		(layer "In2.Cu")
	)
	(gr_line
		(start 39.086282 -22.213824)
		(end 39.328598 -22.45614)
		(stroke
			(width 0.05715)
			(type default)
		)
		(layer "In2.Cu")
	)
	(gr_line
		(start 39.328598 -22.45614)
		(end 39.328598 -22.754336)
		(stroke
			(width 0.05715)
			(type default)
		)
		(layer "In2.Cu")
	)
	(gr_line
		(start 39.367206 -33.230312)
		(end 39.440612 -33.303718)
		(stroke
			(width 0.05715)
			(type default)
		)
		(layer "In2.Cu")
	)
	(gr_line
		(start 39.368984 -32.761428)
		(end 39.66718 -32.761428)
		(stroke
			(width 0.05715)
			(type default)
		)
		(layer "In2.Cu")
	)
	(gr_line
		(start 39.44366 -12.34694)
		(end 39.687246 -12.103354)
		(stroke
			(width 0.05715)
			(type default)
		)
		(layer "In2.Cu")
	)
	(gr_line
		(start 39.572946 -23.469346)
		(end 39.646352 -23.542752)
		(stroke
			(width 0.05715)
			(type default)
		)
		(layer "In2.Cu")
	)
	(gr_line
		(start 39.574724 -23.000462)
		(end 39.87292 -23.000462)
		(stroke
			(width 0.05715)
			(type default)
		)
		(layer "In2.Cu")
	)
	(gr_line
		(start 39.66718 -32.761428)
		(end 39.909496 -33.003744)
		(stroke
			(width 0.05715)
			(type default)
		)
		(layer "In2.Cu")
	)
	(gr_line
		(start 39.87292 -23.000462)
		(end 40.115236 -23.242778)
		(stroke
			(width 0.05715)
			(type default)
		)
		(layer "In2.Cu")
	)
	(gr_line
		(start 39.909496 -33.003744)
		(end 39.909496 -33.30194)
		(stroke
			(width 0.05715)
			(type default)
		)
		(layer "In2.Cu")
	)
	(gr_line
		(start 40.115236 -23.242778)
		(end 40.115236 -23.540974)
		(stroke
			(width 0.05715)
			(type default)
		)
		(layer "In2.Cu")
	)
	(gr_line
		(start 40.157654 -12.103354)
		(end 40.40124 -12.34694)
		(stroke
			(width 0.05715)
			(type default)
		)
		(layer "In2.Cu")
	)
	(gr_line
		(start 40.338248 -26.062432)
		(end 40.411654 -26.135838)
		(stroke
			(width 0.05715)
			(type default)
		)
		(layer "In2.Cu")
	)
	(gr_line
		(start 40.340026 -25.593548)
		(end 40.638222 -25.593548)
		(stroke
			(width 0.05715)
			(type default)
		)
		(layer "In2.Cu")
	)
	(gr_line
		(start 40.40632 -34.269426)
		(end 40.479726 -34.342832)
		(stroke
			(width 0.05715)
			(type default)
		)
		(layer "In2.Cu")
	)
	(gr_line
		(start 40.408098 -33.800542)
		(end 40.706294 -33.800542)
		(stroke
			(width 0.05715)
			(type default)
		)
		(layer "In2.Cu")
	)
	(gr_line
		(start 40.54094 -32.653478)
		(end 40.6146 -32.727138)
		(stroke
			(width 0.05715)
			(type default)
		)
		(layer "In2.Cu")
	)
	(gr_line
		(start 40.542718 -32.184594)
		(end 40.840914 -32.184594)
		(stroke
			(width 0.05715)
			(type default)
		)
		(layer "In2.Cu")
	)
	(gr_line
		(start 40.638222 -25.593548)
		(end 40.880538 -25.835864)
		(stroke
			(width 0.05715)
			(type default)
		)
		(layer "In2.Cu")
	)
	(gr_line
		(start 40.706294 -33.800542)
		(end 40.94861 -34.042858)
		(stroke
			(width 0.05715)
			(type default)
		)
		(layer "In2.Cu")
	)
	(gr_line
		(start 40.792908 -29.278072)
		(end 40.792908 -29.382212)
		(stroke
			(width 0.05715)
			(type default)
		)
		(layer "In2.Cu")
	)
	(gr_line
		(start 40.792908 -28.165552)
		(end 40.792908 -28.269692)
		(stroke
			(width 0.05715)
			(type default)
		)
		(layer "In2.Cu")
	)
	(gr_line
		(start 40.840914 -32.184594)
		(end 41.083484 -32.427164)
		(stroke
			(width 0.05715)
			(type default)
		)
		(layer "In2.Cu")
	)
	(gr_line
		(start 40.880538 -25.835864)
		(end 40.880538 -26.13406)
		(stroke
			(width 0.05715)
			(type default)
		)
		(layer "In2.Cu")
	)
	(gr_line
		(start 40.94861 -34.042858)
		(end 40.94861 -34.341054)
		(stroke
			(width 0.05715)
			(type default)
		)
		(layer "In2.Cu")
	)
	(gr_line
		(start 41.083484 -32.427164)
		(end 41.083484 -32.72536)
		(stroke
			(width 0.05715)
			(type default)
		)
		(layer "In2.Cu")
	)
	(gr_line
		(start 41.125648 -29.712412)
		(end 41.336468 -29.501592)
		(stroke
			(width 0.05715)
			(type default)
		)
		(layer "In2.Cu")
	)
	(gr_line
		(start 41.125648 -28.947872)
		(end 41.336468 -29.158692)
		(stroke
			(width 0.05715)
			(type default)
		)
		(layer "In2.Cu")
	)
	(gr_line
		(start 41.125648 -28.599892)
		(end 41.336468 -28.389072)
		(stroke
			(width 0.05715)
			(type default)
		)
		(layer "In2.Cu")
	)
	(gr_line
		(start 41.125648 -27.835352)
		(end 41.336468 -28.046172)
		(stroke
			(width 0.05715)
			(type default)
		)
		(layer "In2.Cu")
	)
	(gr_line
		(start 41.327578 -33.440116)
		(end 41.401238 -33.513776)
		(stroke
			(width 0.05715)
			(type default)
		)
		(layer "In2.Cu")
	)
	(gr_line
		(start 41.329356 -32.971232)
		(end 41.627552 -32.971232)
		(stroke
			(width 0.05715)
			(type default)
		)
		(layer "In2.Cu")
	)
	(gr_line
		(start 41.336468 -29.158692)
		(end 41.336468 -29.501592)
		(stroke
			(width 0.05715)
			(type default)
		)
		(layer "In2.Cu")
	)
	(gr_line
		(start 41.336468 -28.046172)
		(end 41.336468 -28.389072)
		(stroke
			(width 0.05715)
			(type default)
		)
		(layer "In2.Cu")
	)
	(gr_line
		(start 41.418002 -13.8176)
		(end 41.614598 -14.014196)
		(stroke
			(width 0.05715)
			(type default)
		)
		(layer "In2.Cu")
	)
	(gr_line
		(start 41.627552 -32.971232)
		(end 41.870122 -33.213802)
		(stroke
			(width 0.05715)
			(type default)
		)
		(layer "In2.Cu")
	)
	(gr_line
		(start 41.684702 -25.451308)
		(end 41.758108 -25.524714)
		(stroke
			(width 0.05715)
			(type default)
		)
		(layer "In2.Cu")
	)
	(gr_line
		(start 41.68648 -24.982424)
		(end 41.984676 -24.982424)
		(stroke
			(width 0.05715)
			(type default)
		)
		(layer "In2.Cu")
	)
	(gr_line
		(start 41.800272 -31.66237)
		(end 41.873678 -31.735776)
		(stroke
			(width 0.05715)
			(type default)
		)
		(layer "In2.Cu")
	)
	(gr_line
		(start 41.80205 -31.193486)
		(end 42.100246 -31.193486)
		(stroke
			(width 0.05715)
			(type default)
		)
		(layer "In2.Cu")
	)
	(gr_line
		(start 41.870122 -33.213802)
		(end 41.870122 -33.511998)
		(stroke
			(width 0.05715)
			(type default)
		)
		(layer "In2.Cu")
	)
	(gr_line
		(start 41.984676 -24.982424)
		(end 42.226992 -25.22474)
		(stroke
			(width 0.05715)
			(type default)
		)
		(layer "In2.Cu")
	)
	(gr_line
		(start 42.02049 -35.883596)
		(end 42.093896 -35.957002)
		(stroke
			(width 0.05715)
			(type default)
		)
		(layer "In2.Cu")
	)
	(gr_line
		(start 42.022268 -35.414712)
		(end 42.32021 -35.414712)
		(stroke
			(width 0.05715)
			(type default)
		)
		(layer "In2.Cu")
	)
	(gr_line
		(start 42.085006 -14.014196)
		(end 42.281602 -13.8176)
		(stroke
			(width 0.05715)
			(type default)
		)
		(layer "In2.Cu")
	)
	(gr_line
		(start 42.100246 -31.193486)
		(end 42.342562 -31.435802)
		(stroke
			(width 0.05715)
			(type default)
		)
		(layer "In2.Cu")
	)
	(gr_line
		(start 42.114216 -34.226754)
		(end 42.187876 -34.300414)
		(stroke
			(width 0.05715)
			(type default)
		)
		(layer "In2.Cu")
	)
	(gr_line
		(start 42.115994 -33.75787)
		(end 42.41419 -33.75787)
		(stroke
			(width 0.05715)
			(type default)
		)
		(layer "In2.Cu")
	)
	(gr_line
		(start 42.226992 -25.22474)
		(end 42.226992 -25.522936)
		(stroke
			(width 0.05715)
			(type default)
		)
		(layer "In2.Cu")
	)
	(gr_line
		(start 42.32021 -35.414712)
		(end 42.56278 -35.657028)
		(stroke
			(width 0.05715)
			(type default)
		)
		(layer "In2.Cu")
	)
	(gr_line
		(start 42.342562 -31.435802)
		(end 42.342562 -31.733998)
		(stroke
			(width 0.05715)
			(type default)
		)
		(layer "In2.Cu")
	)
	(gr_line
		(start 42.41419 -33.75787)
		(end 42.65676 -34.00044)
		(stroke
			(width 0.05715)
			(type default)
		)
		(layer "In2.Cu")
	)
	(gr_line
		(start 42.47134 -26.237946)
		(end 42.544746 -26.311352)
		(stroke
			(width 0.05715)
			(type default)
		)
		(layer "In2.Cu")
	)
	(gr_line
		(start 42.473118 -25.769062)
		(end 42.771314 -25.769062)
		(stroke
			(width 0.05715)
			(type default)
		)
		(layer "In2.Cu")
	)
	(gr_line
		(start 42.56278 -35.657028)
		(end 42.56278 -35.955224)
		(stroke
			(width 0.05715)
			(type default)
		)
		(layer "In2.Cu")
	)
	(gr_line
		(start 42.58691 -32.449008)
		(end 42.660316 -32.522414)
		(stroke
			(width 0.05715)
			(type default)
		)
		(layer "In2.Cu")
	)
	(gr_line
		(start 42.588688 -31.980124)
		(end 42.886884 -31.980124)
		(stroke
			(width 0.05715)
			(type default)
		)
		(layer "In2.Cu")
	)
	(gr_line
		(start 42.65676 -34.00044)
		(end 42.65676 -34.298636)
		(stroke
			(width 0.05715)
			(type default)
		)
		(layer "In2.Cu")
	)
	(gr_line
		(start 42.771314 -25.769062)
		(end 43.01363 -26.011378)
		(stroke
			(width 0.05715)
			(type default)
		)
		(layer "In2.Cu")
	)
	(gr_line
		(start 42.886884 -31.980124)
		(end 43.1292 -32.22244)
		(stroke
			(width 0.05715)
			(type default)
		)
		(layer "In2.Cu")
	)
	(gr_line
		(start 43.01363 -26.011378)
		(end 43.01363 -26.309574)
		(stroke
			(width 0.05715)
			(type default)
		)
		(layer "In2.Cu")
	)
	(gr_line
		(start 43.1292 -32.22244)
		(end 43.1292 -32.520636)
		(stroke
			(width 0.05715)
			(type default)
		)
		(layer "In2.Cu")
	)
	(gr_line
		(start 43.25366 -12.5984)
		(end 43.497246 -12.354814)
		(stroke
			(width 0.05715)
			(type default)
		)
		(layer "In2.Cu")
	)
	(gr_line
		(start 43.373548 -33.235646)
		(end 43.446954 -33.309052)
		(stroke
			(width 0.05715)
			(type default)
		)
		(layer "In2.Cu")
	)
	(gr_line
		(start 43.375326 -32.766762)
		(end 43.673522 -32.766762)
		(stroke
			(width 0.05715)
			(type default)
		)
		(layer "In2.Cu")
	)
	(gr_line
		(start 43.673522 -32.766762)
		(end 43.915838 -33.009078)
		(stroke
			(width 0.05715)
			(type default)
		)
		(layer "In2.Cu")
	)
	(gr_line
		(start 43.740324 -33.602422)
		(end 43.740324 -33.64103)
		(stroke
			(width 0.05715)
			(type default)
		)
		(layer "In2.Cu")
	)
	(gr_line
		(start 43.915838 -33.272222)
		(end 43.915838 -33.31083)
		(stroke
			(width 0.05715)
			(type default)
		)
		(layer "In2.Cu")
	)
	(gr_line
		(start 43.915838 -33.009078)
		(end 43.915838 -33.269682)
		(stroke
			(width 0.05715)
			(type default)
		)
		(layer "In2.Cu")
	)
	(gr_line
		(start 43.967654 -12.354814)
		(end 44.21124 -12.5984)
		(stroke
			(width 0.05715)
			(type default)
		)
		(layer "In2.Cu")
	)
	(gr_line
		(start 44.161964 -29.802328)
		(end 44.235624 -29.875988)
		(stroke
			(width 0.05715)
			(type default)
		)
		(layer "In2.Cu")
	)
	(gr_line
		(start 44.163742 -29.333444)
		(end 44.461938 -29.333444)
		(stroke
			(width 0.05715)
			(type default)
		)
		(layer "In2.Cu")
	)
	(gr_line
		(start 44.461938 -29.333444)
		(end 44.704508 -29.576014)
		(stroke
			(width 0.05715)
			(type default)
		)
		(layer "In2.Cu")
	)
	(gr_line
		(start 44.704508 -29.576014)
		(end 44.704508 -29.87421)
		(stroke
			(width 0.05715)
			(type default)
		)
		(layer "In2.Cu")
	)
	(gr_line
		(start 44.948602 -30.588966)
		(end 45.022262 -30.662626)
		(stroke
			(width 0.05715)
			(type default)
		)
		(layer "In2.Cu")
	)
	(gr_line
		(start 44.95038 -30.120082)
		(end 45.248576 -30.120082)
		(stroke
			(width 0.05715)
			(type default)
		)
		(layer "In2.Cu")
	)
	(gr_line
		(start 45.248576 -30.120082)
		(end 45.491146 -30.362652)
		(stroke
			(width 0.05715)
			(type default)
		)
		(layer "In2.Cu")
	)
	(gr_line
		(start 45.397166 -15.7734)
		(end 45.50156 -15.7734)
		(stroke
			(width 0.05715)
			(type default)
		)
		(layer "In2.Cu")
	)
	(gr_line
		(start 45.466 -13.8176)
		(end 45.586396 -13.937996)
		(stroke
			(width 0.05715)
			(type default)
		)
		(layer "In2.Cu")
	)
	(gr_line
		(start 45.491146 -30.362652)
		(end 45.491146 -30.660848)
		(stroke
			(width 0.05715)
			(type default)
		)
		(layer "In2.Cu")
	)
	(gr_line
		(start 45.727366 -16.0147)
		(end 45.83176 -16.0147)
		(stroke
			(width 0.05715)
			(type default)
		)
		(layer "In2.Cu")
	)
	(gr_line
		(start 45.735494 -31.375858)
		(end 45.8089 -31.449264)
		(stroke
			(width 0.05715)
			(type default)
		)
		(layer "In2.Cu")
	)
	(gr_line
		(start 45.737272 -30.906974)
		(end 46.035468 -30.906974)
		(stroke
			(width 0.05715)
			(type default)
		)
		(layer "In2.Cu")
	)
	(gr_line
		(start 46.035468 -30.906974)
		(end 46.277784 -31.14929)
		(stroke
			(width 0.05715)
			(type default)
		)
		(layer "In2.Cu")
	)
	(gr_line
		(start 46.056804 -13.937996)
		(end 46.1772 -13.8176)
		(stroke
			(width 0.05715)
			(type default)
		)
		(layer "In2.Cu")
	)
	(gr_line
		(start 46.277784 -31.14929)
		(end 46.277784 -31.447486)
		(stroke
			(width 0.05715)
			(type default)
		)
		(layer "In2.Cu")
	)
	(gr_line
		(start 46.30801 -37.12591)
		(end 46.381416 -37.199316)
		(stroke
			(width 0.05715)
			(type default)
		)
		(layer "In2.Cu")
	)
	(gr_line
		(start 46.309788 -36.657026)
		(end 46.607984 -36.657026)
		(stroke
			(width 0.05715)
			(type default)
		)
		(layer "In2.Cu")
	)
	(gr_line
		(start 46.607984 -36.657026)
		(end 46.8503 -36.899596)
		(stroke
			(width 0.05715)
			(type default)
		)
		(layer "In2.Cu")
	)
	(gr_line
		(start 46.8503 -36.899596)
		(end 46.8503 -37.197538)
		(stroke
			(width 0.05715)
			(type default)
		)
		(layer "In2.Cu")
	)
	(gr_line
		(start 46.957996 -19.227546)
		(end 47.031402 -19.300952)
		(stroke
			(width 0.05715)
			(type default)
		)
		(layer "In2.Cu")
	)
	(gr_line
		(start 46.959774 -18.758662)
		(end 47.25797 -18.758662)
		(stroke
			(width 0.05715)
			(type default)
		)
		(layer "In2.Cu")
	)
	(gr_line
		(start 47.25797 -18.758662)
		(end 47.500286 -19.000978)
		(stroke
			(width 0.05715)
			(type default)
		)
		(layer "In2.Cu")
	)
	(gr_line
		(start 47.46371 -13.7922)
		(end 47.588424 -13.667486)
		(stroke
			(width 0.05715)
			(type default)
		)
		(layer "In2.Cu")
	)
	(gr_line
		(start 47.500286 -19.000978)
		(end 47.500286 -19.299174)
		(stroke
			(width 0.05715)
			(type default)
		)
		(layer "In2.Cu")
	)
	(gr_line
		(start 48.059086 -13.667486)
		(end 48.1838 -13.7922)
		(stroke
			(width 0.05715)
			(type default)
		)
		(layer "In2.Cu")
	)
	(gr_line
		(start 48.618394 -34.258758)
		(end 48.6918 -34.332164)
		(stroke
			(width 0.05715)
			(type default)
		)
		(layer "In2.Cu")
	)
	(gr_line
		(start 48.620172 -33.789874)
		(end 48.918368 -33.789874)
		(stroke
			(width 0.05715)
			(type default)
		)
		(layer "In2.Cu")
	)
	(gr_line
		(start 48.918368 -33.789874)
		(end 49.160684 -34.03219)
		(stroke
			(width 0.05715)
			(type default)
		)
		(layer "In2.Cu")
	)
	(gr_line
		(start 49.160684 -34.03219)
		(end 49.160684 -34.330386)
		(stroke
			(width 0.05715)
			(type default)
		)
		(layer "In2.Cu")
	)
	(gr_line
		(start 49.29505 -20.41144)
		(end 49.538636 -20.655026)
		(stroke
			(width 0.05715)
			(type default)
		)
		(layer "In2.Cu")
	)
	(gr_line
		(start 49.60874 -22.266402)
		(end 49.60874 -22.370542)
		(stroke
			(width 0.05715)
			(type default)
		)
		(layer "In2.Cu")
	)
	(gr_line
		(start 49.94148 -22.700742)
		(end 50.1523 -22.489922)
		(stroke
			(width 0.05715)
			(type default)
		)
		(layer "In2.Cu")
	)
	(gr_line
		(start 49.94148 -21.936202)
		(end 50.1523 -22.147022)
		(stroke
			(width 0.05715)
			(type default)
		)
		(layer "In2.Cu")
	)
	(gr_line
		(start 50.009044 -20.655026)
		(end 50.25263 -20.41144)
		(stroke
			(width 0.05715)
			(type default)
		)
		(layer "In2.Cu")
	)
	(gr_line
		(start 50.1523 -22.147022)
		(end 50.1523 -22.489922)
		(stroke
			(width 0.05715)
			(type default)
		)
		(layer "In2.Cu")
	)
	(gr_line
		(start 50.324258 -32.658558)
		(end 50.324258 -32.762698)
		(stroke
			(width 0.05715)
			(type default)
		)
		(layer "In2.Cu")
	)
	(gr_line
		(start 50.324258 -31.546038)
		(end 50.324258 -31.650178)
		(stroke
			(width 0.05715)
			(type default)
		)
		(layer "In2.Cu")
	)
	(gr_line
		(start 50.324258 -30.433518)
		(end 50.324258 -30.537658)
		(stroke
			(width 0.05715)
			(type default)
		)
		(layer "In2.Cu")
	)
	(gr_line
		(start 50.324258 -29.320998)
		(end 50.324258 -29.425138)
		(stroke
			(width 0.05715)
			(type default)
		)
		(layer "In2.Cu")
	)
	(gr_line
		(start 50.324258 -26.808938)
		(end 50.324258 -26.913078)
		(stroke
			(width 0.05715)
			(type default)
		)
		(layer "In2.Cu")
	)
	(gr_line
		(start 50.324258 -25.696418)
		(end 50.324258 -25.800558)
		(stroke
			(width 0.05715)
			(type default)
		)
		(layer "In2.Cu")
	)
	(gr_line
		(start 50.324258 -24.583898)
		(end 50.324258 -24.688038)
		(stroke
			(width 0.05715)
			(type default)
		)
		(layer "In2.Cu")
	)
	(gr_line
		(start 50.656998 -33.092898)
		(end 50.867818 -32.882078)
		(stroke
			(width 0.05715)
			(type default)
		)
		(layer "In2.Cu")
	)
	(gr_line
		(start 50.656998 -32.328358)
		(end 50.867818 -32.539178)
		(stroke
			(width 0.05715)
			(type default)
		)
		(layer "In2.Cu")
	)
	(gr_line
		(start 50.656998 -31.980378)
		(end 50.867818 -31.769558)
		(stroke
			(width 0.05715)
			(type default)
		)
		(layer "In2.Cu")
	)
	(gr_line
		(start 50.656998 -31.215838)
		(end 50.867818 -31.426658)
		(stroke
			(width 0.05715)
			(type default)
		)
		(layer "In2.Cu")
	)
	(gr_line
		(start 50.656998 -30.867858)
		(end 50.867818 -30.657038)
		(stroke
			(width 0.05715)
			(type default)
		)
		(layer "In2.Cu")
	)
	(gr_line
		(start 50.656998 -30.103318)
		(end 50.867818 -30.314138)
		(stroke
			(width 0.05715)
			(type default)
		)
		(layer "In2.Cu")
	)
	(gr_line
		(start 50.656998 -29.755338)
		(end 50.867818 -29.544518)
		(stroke
			(width 0.05715)
			(type default)
		)
		(layer "In2.Cu")
	)
	(gr_line
		(start 50.656998 -28.990798)
		(end 50.867818 -29.201618)
		(stroke
			(width 0.05715)
			(type default)
		)
		(layer "In2.Cu")
	)
	(gr_line
		(start 50.656998 -27.243278)
		(end 50.867818 -27.032458)
		(stroke
			(width 0.05715)
			(type default)
		)
		(layer "In2.Cu")
	)
	(gr_line
		(start 50.656998 -26.478738)
		(end 50.867818 -26.689558)
		(stroke
			(width 0.05715)
			(type default)
		)
		(layer "In2.Cu")
	)
	(gr_line
		(start 50.656998 -26.130758)
		(end 50.867818 -25.919938)
		(stroke
			(width 0.05715)
			(type default)
		)
		(layer "In2.Cu")
	)
	(gr_line
		(start 50.656998 -25.366218)
		(end 50.867818 -25.577038)
		(stroke
			(width 0.05715)
			(type default)
		)
		(layer "In2.Cu")
	)
	(gr_line
		(start 50.656998 -25.018238)
		(end 50.867818 -24.807418)
		(stroke
			(width 0.05715)
			(type default)
		)
		(layer "In2.Cu")
	)
	(gr_line
		(start 50.656998 -24.253698)
		(end 50.867818 -24.464518)
		(stroke
			(width 0.05715)
			(type default)
		)
		(layer "In2.Cu")
	)
	(gr_line
		(start 50.867818 -32.539178)
		(end 50.867818 -32.882078)
		(stroke
			(width 0.05715)
			(type default)
		)
		(layer "In2.Cu")
	)
	(gr_line
		(start 50.867818 -31.426658)
		(end 50.867818 -31.769558)
		(stroke
			(width 0.05715)
			(type default)
		)
		(layer "In2.Cu")
	)
	(gr_line
		(start 50.867818 -30.314138)
		(end 50.867818 -30.657038)
		(stroke
			(width 0.05715)
			(type default)
		)
		(layer "In2.Cu")
	)
	(gr_line
		(start 50.867818 -29.201618)
		(end 50.867818 -29.544518)
		(stroke
			(width 0.05715)
			(type default)
		)
		(layer "In2.Cu")
	)
	(gr_line
		(start 50.867818 -26.689558)
		(end 50.867818 -27.032458)
		(stroke
			(width 0.05715)
			(type default)
		)
		(layer "In2.Cu")
	)
	(gr_line
		(start 50.867818 -25.577038)
		(end 50.867818 -25.919938)
		(stroke
			(width 0.05715)
			(type default)
		)
		(layer "In2.Cu")
	)
	(gr_line
		(start 50.867818 -24.464518)
		(end 50.867818 -24.807418)
		(stroke
			(width 0.05715)
			(type default)
		)
		(layer "In2.Cu")
	)
	(gr_line
		(start 51.50104 -19.656806)
		(end 51.574446 -19.730212)
		(stroke
			(width 0.05715)
			(type default)
		)
		(layer "In2.Cu")
	)
	(gr_line
		(start 51.502818 -19.187922)
		(end 51.801014 -19.187922)
		(stroke
			(width 0.05715)
			(type default)
		)
		(layer "In2.Cu")
	)
	(gr_line
		(start 51.518058 -35.929062)
		(end 51.728878 -35.718242)
		(stroke
			(width 0.05715)
			(type default)
		)
		(layer "In2.Cu")
	)
	(gr_line
		(start 51.728878 -35.718242)
		(end 52.071778 -35.718242)
		(stroke
			(width 0.05715)
			(type default)
		)
		(layer "In2.Cu")
	)
	(gr_line
		(start 51.801014 -19.187922)
		(end 52.04333 -19.430238)
		(stroke
			(width 0.05715)
			(type default)
		)
		(layer "In2.Cu")
	)
	(gr_line
		(start 51.848258 -36.261802)
		(end 51.952398 -36.261802)
		(stroke
			(width 0.05715)
			(type default)
		)
		(layer "In2.Cu")
	)
	(gr_line
		(start 52.04333 -19.430238)
		(end 52.04333 -19.728434)
		(stroke
			(width 0.05715)
			(type default)
		)
		(layer "In2.Cu")
	)
	(gr_line
		(start 52.071778 -35.718242)
		(end 52.282598 -35.929062)
		(stroke
			(width 0.05715)
			(type default)
		)
		(layer "In2.Cu")
	)
	(gr_line
		(start 52.124864 -40.90797)
		(end 52.198524 -40.98163)
		(stroke
			(width 0.05715)
			(type default)
		)
		(layer "In2.Cu")
	)
	(gr_line
		(start 52.126642 -40.439086)
		(end 52.424838 -40.439086)
		(stroke
			(width 0.05715)
			(type default)
		)
		(layer "In2.Cu")
	)
	(gr_line
		(start 52.424838 -40.439086)
		(end 52.667408 -40.681656)
		(stroke
			(width 0.05715)
			(type default)
		)
		(layer "In2.Cu")
	)
	(gr_line
		(start 52.52466 -35.31616)
		(end 52.764944 -35.556444)
		(stroke
			(width 0.05715)
			(type default)
		)
		(layer "In2.Cu")
	)
	(gr_line
		(start 52.667408 -40.681656)
		(end 52.667408 -40.979852)
		(stroke
			(width 0.05715)
			(type default)
		)
		(layer "In2.Cu")
	)
	(gr_line
		(start 52.8701 -23.793704)
		(end 52.8701 -23.897844)
		(stroke
			(width 0.05715)
			(type default)
		)
		(layer "In2.Cu")
	)
	(gr_line
		(start 52.8701 -22.681184)
		(end 52.8701 -22.785324)
		(stroke
			(width 0.05715)
			(type default)
		)
		(layer "In2.Cu")
	)
	(gr_line
		(start 52.8701 -21.568664)
		(end 52.8701 -21.672804)
		(stroke
			(width 0.05715)
			(type default)
		)
		(layer "In2.Cu")
	)
	(gr_line
		(start 52.911502 -41.694608)
		(end 52.985162 -41.768268)
		(stroke
			(width 0.05715)
			(type default)
		)
		(layer "In2.Cu")
	)
	(gr_line
		(start 52.91328 -41.225724)
		(end 53.211476 -41.225724)
		(stroke
			(width 0.05715)
			(type default)
		)
		(layer "In2.Cu")
	)
	(gr_line
		(start 53.20284 -24.228044)
		(end 53.41366 -24.017224)
		(stroke
			(width 0.05715)
			(type default)
		)
		(layer "In2.Cu")
	)
	(gr_line
		(start 53.20284 -23.463504)
		(end 53.41366 -23.674324)
		(stroke
			(width 0.05715)
			(type default)
		)
		(layer "In2.Cu")
	)
	(gr_line
		(start 53.20284 -23.115524)
		(end 53.41366 -22.904704)
		(stroke
			(width 0.05715)
			(type default)
		)
		(layer "In2.Cu")
	)
	(gr_line
		(start 53.20284 -22.350984)
		(end 53.41366 -22.561804)
		(stroke
			(width 0.05715)
			(type default)
		)
		(layer "In2.Cu")
	)
	(gr_line
		(start 53.20284 -22.003004)
		(end 53.41366 -21.792184)
		(stroke
			(width 0.05715)
			(type default)
		)
		(layer "In2.Cu")
	)
	(gr_line
		(start 53.20284 -21.238464)
		(end 53.41366 -21.449284)
		(stroke
			(width 0.05715)
			(type default)
		)
		(layer "In2.Cu")
	)
	(gr_line
		(start 53.211476 -41.225724)
		(end 53.454046 -41.468294)
		(stroke
			(width 0.05715)
			(type default)
		)
		(layer "In2.Cu")
	)
	(gr_line
		(start 53.235606 -35.556444)
		(end 53.478938 -35.313112)
		(stroke
			(width 0.05715)
			(type default)
		)
		(layer "In2.Cu")
	)
	(gr_line
		(start 53.41366 -23.674324)
		(end 53.41366 -24.017224)
		(stroke
			(width 0.05715)
			(type default)
		)
		(layer "In2.Cu")
	)
	(gr_line
		(start 53.41366 -22.561804)
		(end 53.41366 -22.904704)
		(stroke
			(width 0.05715)
			(type default)
		)
		(layer "In2.Cu")
	)
	(gr_line
		(start 53.41366 -21.449284)
		(end 53.41366 -21.792184)
		(stroke
			(width 0.05715)
			(type default)
		)
		(layer "In2.Cu")
	)
	(gr_line
		(start 53.454046 -41.468294)
		(end 53.454046 -41.76649)
		(stroke
			(width 0.05715)
			(type default)
		)
		(layer "In2.Cu")
	)
	(gr_line
		(start 53.955188 -25.996646)
		(end 54.028848 -26.070306)
		(stroke
			(width 0.05715)
			(type default)
		)
		(layer "In2.Cu")
	)
	(gr_line
		(start 53.956966 -25.527762)
		(end 54.255162 -25.527762)
		(stroke
			(width 0.05715)
			(type default)
		)
		(layer "In2.Cu")
	)
	(gr_line
		(start 54.01183 -8.69696)
		(end 54.22265 -8.48614)
		(stroke
			(width 0.05715)
			(type default)
		)
		(layer "In2.Cu")
	)
	(gr_line
		(start 54.22265 -8.48614)
		(end 54.56555 -8.48614)
		(stroke
			(width 0.05715)
			(type default)
		)
		(layer "In2.Cu")
	)
	(gr_line
		(start 54.255162 -25.527762)
		(end 54.497732 -25.770332)
		(stroke
			(width 0.05715)
			(type default)
		)
		(layer "In2.Cu")
	)
	(gr_line
		(start 54.34203 -9.0297)
		(end 54.44617 -9.0297)
		(stroke
			(width 0.05715)
			(type default)
		)
		(layer "In2.Cu")
	)
	(gr_line
		(start 54.497732 -25.770332)
		(end 54.497732 -26.068528)
		(stroke
			(width 0.05715)
			(type default)
		)
		(layer "In2.Cu")
	)
	(gr_line
		(start 54.56555 -8.48614)
		(end 54.77637 -8.69696)
		(stroke
			(width 0.05715)
			(type default)
		)
		(layer "In2.Cu")
	)
	(gr_line
		(start 54.741826 -26.783284)
		(end 54.815486 -26.856944)
		(stroke
			(width 0.05715)
			(type default)
		)
		(layer "In2.Cu")
	)
	(gr_line
		(start 54.743604 -26.3144)
		(end 55.0418 -26.3144)
		(stroke
			(width 0.05715)
			(type default)
		)
		(layer "In2.Cu")
	)
	(gr_line
		(start 55.0418 -26.3144)
		(end 55.28437 -26.55697)
		(stroke
			(width 0.05715)
			(type default)
		)
		(layer "In2.Cu")
	)
	(gr_line
		(start 55.095902 -27.13736)
		(end 55.095902 -27.188922)
		(stroke
			(width 0.05715)
			(type default)
		)
		(layer "In2.Cu")
	)
	(gr_line
		(start 55.12435 -8.69696)
		(end 55.33517 -8.48614)
		(stroke
			(width 0.05715)
			(type default)
		)
		(layer "In2.Cu")
	)
	(gr_line
		(start 55.28437 -26.80716)
		(end 55.28437 -26.858722)
		(stroke
			(width 0.05715)
			(type default)
		)
		(layer "In2.Cu")
	)
	(gr_line
		(start 55.28437 -26.55697)
		(end 55.28437 -26.80462)
		(stroke
			(width 0.05715)
			(type default)
		)
		(layer "In2.Cu")
	)
	(gr_line
		(start 55.33517 -8.48614)
		(end 55.67807 -8.48614)
		(stroke
			(width 0.05715)
			(type default)
		)
		(layer "In2.Cu")
	)
	(gr_line
		(start 55.45455 -9.0297)
		(end 55.55869 -9.0297)
		(stroke
			(width 0.05715)
			(type default)
		)
		(layer "In2.Cu")
	)
	(gr_line
		(start 55.67807 -8.48614)
		(end 55.88889 -8.69696)
		(stroke
			(width 0.05715)
			(type default)
		)
		(layer "In2.Cu")
	)
	(gr_line
		(start 56.23687 -8.69696)
		(end 56.44769 -8.48614)
		(stroke
			(width 0.05715)
			(type default)
		)
		(layer "In2.Cu")
	)
	(gr_line
		(start 56.437022 -49.022)
		(end 56.510682 -49.09566)
		(stroke
			(width 0.05715)
			(type default)
		)
		(layer "In2.Cu")
	)
	(gr_line
		(start 56.4388 -48.553116)
		(end 56.736996 -48.553116)
		(stroke
			(width 0.05715)
			(type default)
		)
		(layer "In2.Cu")
	)
	(gr_line
		(start 56.44769 -8.48614)
		(end 56.79059 -8.48614)
		(stroke
			(width 0.05715)
			(type default)
		)
		(layer "In2.Cu")
	)
	(gr_line
		(start 56.56707 -9.0297)
		(end 56.67121 -9.0297)
		(stroke
			(width 0.05715)
			(type default)
		)
		(layer "In2.Cu")
	)
	(gr_line
		(start 56.736996 -48.553116)
		(end 56.979566 -48.795686)
		(stroke
			(width 0.05715)
			(type default)
		)
		(layer "In2.Cu")
	)
	(gr_line
		(start 56.79059 -8.48614)
		(end 57.00141 -8.69696)
		(stroke
			(width 0.05715)
			(type default)
		)
		(layer "In2.Cu")
	)
	(gr_line
		(start 56.979566 -48.795686)
		(end 56.979566 -49.093882)
		(stroke
			(width 0.05715)
			(type default)
		)
		(layer "In2.Cu")
	)
	(gr_line
		(start 59.078114 -10.936478)
		(end 59.30265 -11.161014)
		(stroke
			(width 0.05715)
			(type default)
		)
		(layer "In2.Cu")
	)
	(gr_line
		(start 59.720226 -53.65242)
		(end 59.793632 -53.725826)
		(stroke
			(width 0.05715)
			(type default)
		)
		(layer "In2.Cu")
	)
	(gr_line
		(start 59.722004 -53.183536)
		(end 60.0202 -53.183536)
		(stroke
			(width 0.05715)
			(type default)
		)
		(layer "In2.Cu")
	)
	(gr_line
		(start 59.773058 -11.161014)
		(end 59.997594 -10.936478)
		(stroke
			(width 0.05715)
			(type default)
		)
		(layer "In2.Cu")
	)
	(gr_line
		(start 60.0202 -53.183536)
		(end 60.262516 -53.425852)
		(stroke
			(width 0.05715)
			(type default)
		)
		(layer "In2.Cu")
	)
	(gr_line
		(start 60.262516 -53.425852)
		(end 60.262516 -53.724048)
		(stroke
			(width 0.05715)
			(type default)
		)
		(layer "In2.Cu")
	)
	(gr_line
		(start 60.318142 -51.11877)
		(end 60.391548 -51.192176)
		(stroke
			(width 0.05715)
			(type default)
		)
		(layer "In2.Cu")
	)
	(gr_line
		(start 60.31992 -50.649886)
		(end 60.618116 -50.649886)
		(stroke
			(width 0.05715)
			(type default)
		)
		(layer "In2.Cu")
	)
	(gr_line
		(start 60.506864 -54.439058)
		(end 60.58027 -54.512464)
		(stroke
			(width 0.05715)
			(type default)
		)
		(layer "In2.Cu")
	)
	(gr_line
		(start 60.508642 -53.970174)
		(end 60.806838 -53.970174)
		(stroke
			(width 0.05715)
			(type default)
		)
		(layer "In2.Cu")
	)
	(gr_line
		(start 60.618116 -50.649886)
		(end 60.860432 -50.892202)
		(stroke
			(width 0.05715)
			(type default)
		)
		(layer "In2.Cu")
	)
	(gr_line
		(start 60.806838 -53.970174)
		(end 61.049154 -54.21249)
		(stroke
			(width 0.05715)
			(type default)
		)
		(layer "In2.Cu")
	)
	(gr_line
		(start 60.860432 -50.892202)
		(end 60.860432 -51.190398)
		(stroke
			(width 0.05715)
			(type default)
		)
		(layer "In2.Cu")
	)
	(gr_line
		(start 61.049154 -54.21249)
		(end 61.049154 -54.510686)
		(stroke
			(width 0.05715)
			(type default)
		)
		(layer "In2.Cu")
	)
	(gr_line
		(start 61.10478 -51.905408)
		(end 61.178186 -51.978814)
		(stroke
			(width 0.05715)
			(type default)
		)
		(layer "In2.Cu")
	)
	(gr_line
		(start 61.106558 -51.436524)
		(end 61.404754 -51.436524)
		(stroke
			(width 0.05715)
			(type default)
		)
		(layer "In2.Cu")
	)
	(gr_line
		(start 61.404754 -51.436524)
		(end 61.64707 -51.67884)
		(stroke
			(width 0.05715)
			(type default)
		)
		(layer "In2.Cu")
	)
	(gr_line
		(start 61.40831 -10.250678)
		(end 61.632846 -10.475214)
		(stroke
			(width 0.05715)
			(type default)
		)
		(layer "In2.Cu")
	)
	(gr_line
		(start 61.64707 -51.67884)
		(end 61.64707 -51.977036)
		(stroke
			(width 0.05715)
			(type default)
		)
		(layer "In2.Cu")
	)
	(gr_line
		(start 61.891418 -52.692046)
		(end 61.964824 -52.765452)
		(stroke
			(width 0.05715)
			(type default)
		)
		(layer "In2.Cu")
	)
	(gr_line
		(start 61.893196 -52.223162)
		(end 62.191392 -52.223162)
		(stroke
			(width 0.05715)
			(type default)
		)
		(layer "In2.Cu")
	)
	(gr_line
		(start 62.103254 -10.475214)
		(end 62.32779 -10.250678)
		(stroke
			(width 0.05715)
			(type default)
		)
		(layer "In2.Cu")
	)
	(gr_line
		(start 62.191392 -52.223162)
		(end 62.433708 -52.465478)
		(stroke
			(width 0.05715)
			(type default)
		)
		(layer "In2.Cu")
	)
	(gr_line
		(start 62.410848 -47.561754)
		(end 62.484254 -47.63516)
		(stroke
			(width 0.05715)
			(type default)
		)
		(layer "In2.Cu")
	)
	(gr_line
		(start 62.412626 -47.09287)
		(end 62.710822 -47.09287)
		(stroke
			(width 0.05715)
			(type default)
		)
		(layer "In2.Cu")
	)
	(gr_line
		(start 62.433708 -52.465478)
		(end 62.433708 -52.763674)
		(stroke
			(width 0.05715)
			(type default)
		)
		(layer "In2.Cu")
	)
	(gr_line
		(start 62.710822 -47.09287)
		(end 62.953138 -47.335186)
		(stroke
			(width 0.05715)
			(type default)
		)
		(layer "In2.Cu")
	)
	(gr_line
		(start 62.953138 -47.335186)
		(end 62.953138 -47.633382)
		(stroke
			(width 0.05715)
			(type default)
		)
		(layer "In2.Cu")
	)
	(gr_line
		(start 63.197486 -48.348392)
		(end 63.270892 -48.421798)
		(stroke
			(width 0.05715)
			(type default)
		)
		(layer "In2.Cu")
	)
	(gr_line
		(start 63.199264 -47.879508)
		(end 63.49746 -47.879508)
		(stroke
			(width 0.05715)
			(type default)
		)
		(layer "In2.Cu")
	)
	(gr_line
		(start 63.49746 -47.879508)
		(end 63.739776 -48.121824)
		(stroke
			(width 0.05715)
			(type default)
		)
		(layer "In2.Cu")
	)
	(gr_line
		(start 63.52794 -56.42356)
		(end 63.73876 -56.21274)
		(stroke
			(width 0.05715)
			(type default)
		)
		(layer "In2.Cu")
	)
	(gr_line
		(start 63.73876 -56.21274)
		(end 64.08166 -56.21274)
		(stroke
			(width 0.05715)
			(type default)
		)
		(layer "In2.Cu")
	)
	(gr_line
		(start 63.739776 -48.121824)
		(end 63.739776 -48.42002)
		(stroke
			(width 0.05715)
			(type default)
		)
		(layer "In2.Cu")
	)
	(gr_line
		(start 63.85814 -56.7563)
		(end 63.96228 -56.7563)
		(stroke
			(width 0.05715)
			(type default)
		)
		(layer "In2.Cu")
	)
	(gr_line
		(start 64.08166 -56.21274)
		(end 64.29248 -56.42356)
		(stroke
			(width 0.05715)
			(type default)
		)
		(layer "In2.Cu")
	)
	(gr_line
		(start 67.401948 -56.420766)
		(end 67.475354 -56.494172)
		(stroke
			(width 0.05715)
			(type default)
		)
		(layer "In2.Cu")
	)
	(gr_line
		(start 67.403726 -55.951882)
		(end 67.701922 -55.951882)
		(stroke
			(width 0.05715)
			(type default)
		)
		(layer "In2.Cu")
	)
	(gr_line
		(start 67.631056 -31.14675)
		(end 67.69989 -31.077916)
		(stroke
			(width 0.05715)
			(type default)
		)
		(layer "In2.Cu")
	)
	(gr_line
		(start 67.701922 -55.951882)
		(end 67.944238 -56.194198)
		(stroke
			(width 0.05715)
			(type default)
		)
		(layer "In2.Cu")
	)
	(gr_line
		(start 67.944238 -56.194198)
		(end 67.944238 -56.492394)
		(stroke
			(width 0.05715)
			(type default)
		)
		(layer "In2.Cu")
	)
	(gr_line
		(start 68.072 -14.605)
		(end 68.217796 -14.750796)
		(stroke
			(width 0.05715)
			(type default)
		)
		(layer "In2.Cu")
	)
	(gr_line
		(start 68.578222 -49.76876)
		(end 68.789042 -49.55794)
		(stroke
			(width 0.05715)
			(type default)
		)
		(layer "In2.Cu")
	)
	(gr_line
		(start 68.688204 -14.750796)
		(end 68.834 -14.605)
		(stroke
			(width 0.05715)
			(type default)
		)
		(layer "In2.Cu")
	)
	(gr_line
		(start 68.789042 -49.55794)
		(end 69.131942 -49.55794)
		(stroke
			(width 0.05715)
			(type default)
		)
		(layer "In2.Cu")
	)
	(gr_line
		(start 68.908422 -50.1015)
		(end 69.012562 -50.1015)
		(stroke
			(width 0.05715)
			(type default)
		)
		(layer "In2.Cu")
	)
	(gr_line
		(start 69.131942 -49.55794)
		(end 69.342762 -49.76876)
		(stroke
			(width 0.05715)
			(type default)
		)
		(layer "In2.Cu")
	)
	(gr_line
		(start 69.690742 -49.76876)
		(end 69.901562 -49.55794)
		(stroke
			(width 0.05715)
			(type default)
		)
		(layer "In2.Cu")
	)
	(gr_line
		(start 69.901562 -49.55794)
		(end 70.244462 -49.55794)
		(stroke
			(width 0.05715)
			(type default)
		)
		(layer "In2.Cu")
	)
	(gr_line
		(start 70.020942 -50.1015)
		(end 70.125082 -50.1015)
		(stroke
			(width 0.05715)
			(type default)
		)
		(layer "In2.Cu")
	)
	(gr_line
		(start 70.244462 -49.55794)
		(end 70.455282 -49.76876)
		(stroke
			(width 0.05715)
			(type default)
		)
		(layer "In2.Cu")
	)
	(gr_line
		(start 70.551294 -62.18936)
		(end 70.762114 -61.97854)
		(stroke
			(width 0.05715)
			(type default)
		)
		(layer "In2.Cu")
	)
	(gr_line
		(start 70.762114 -61.97854)
		(end 71.105014 -61.97854)
		(stroke
			(width 0.05715)
			(type default)
		)
		(layer "In2.Cu")
	)
	(gr_line
		(start 70.804532 -52.694332)
		(end 70.877938 -52.767738)
		(stroke
			(width 0.05715)
			(type default)
		)
		(layer "In2.Cu")
	)
	(gr_line
		(start 70.80631 -52.225448)
		(end 71.104506 -52.225448)
		(stroke
			(width 0.05715)
			(type default)
		)
		(layer "In2.Cu")
	)
	(gr_line
		(start 70.86854 -58.65876)
		(end 71.07936 -58.44794)
		(stroke
			(width 0.05715)
			(type default)
		)
		(layer "In2.Cu")
	)
	(gr_line
		(start 70.881494 -62.5221)
		(end 70.985634 -62.5221)
		(stroke
			(width 0.05715)
			(type default)
		)
		(layer "In2.Cu")
	)
	(gr_line
		(start 71.07936 -58.44794)
		(end 71.42226 -58.44794)
		(stroke
			(width 0.05715)
			(type default)
		)
		(layer "In2.Cu")
	)
	(gr_line
		(start 71.104506 -52.225448)
		(end 71.346822 -52.467764)
		(stroke
			(width 0.05715)
			(type default)
		)
		(layer "In2.Cu")
	)
	(gr_line
		(start 71.105014 -61.97854)
		(end 71.315834 -62.18936)
		(stroke
			(width 0.05715)
			(type default)
		)
		(layer "In2.Cu")
	)
	(gr_line
		(start 71.19874 -58.9915)
		(end 71.30288 -58.9915)
		(stroke
			(width 0.05715)
			(type default)
		)
		(layer "In2.Cu")
	)
	(gr_line
		(start 71.346822 -52.467764)
		(end 71.346822 -52.76596)
		(stroke
			(width 0.05715)
			(type default)
		)
		(layer "In2.Cu")
	)
	(gr_line
		(start 71.42226 -58.44794)
		(end 71.63308 -58.65876)
		(stroke
			(width 0.05715)
			(type default)
		)
		(layer "In2.Cu")
	)
	(gr_line
		(start 71.42226 -43.11396)
		(end 71.63308 -42.90314)
		(stroke
			(width 0.05715)
			(type default)
		)
		(layer "In2.Cu")
	)
	(gr_line
		(start 71.560436 -51.02352)
		(end 71.633842 -51.096926)
		(stroke
			(width 0.05715)
			(type default)
		)
		(layer "In2.Cu")
	)
	(gr_line
		(start 71.562214 -50.554636)
		(end 71.86041 -50.554636)
		(stroke
			(width 0.05715)
			(type default)
		)
		(layer "In2.Cu")
	)
	(gr_line
		(start 71.59117 -53.48097)
		(end 71.664576 -53.554376)
		(stroke
			(width 0.05715)
			(type default)
		)
		(layer "In2.Cu")
	)
	(gr_line
		(start 71.592948 -53.012086)
		(end 71.891144 -53.012086)
		(stroke
			(width 0.05715)
			(type default)
		)
		(layer "In2.Cu")
	)
	(gr_line
		(start 71.63308 -42.90314)
		(end 71.97598 -42.90314)
		(stroke
			(width 0.05715)
			(type default)
		)
		(layer "In2.Cu")
	)
	(gr_line
		(start 71.663814 -62.18936)
		(end 71.874634 -61.97854)
		(stroke
			(width 0.05715)
			(type default)
		)
		(layer "In2.Cu")
	)
	(gr_line
		(start 71.75246 -43.4467)
		(end 71.8566 -43.4467)
		(stroke
			(width 0.05715)
			(type default)
		)
		(layer "In2.Cu")
	)
	(gr_line
		(start 71.86041 -50.554636)
		(end 72.102726 -50.796952)
		(stroke
			(width 0.05715)
			(type default)
		)
		(layer "In2.Cu")
	)
	(gr_line
		(start 71.874634 -61.97854)
		(end 72.217534 -61.97854)
		(stroke
			(width 0.05715)
			(type default)
		)
		(layer "In2.Cu")
	)
	(gr_line
		(start 71.891144 -53.012086)
		(end 72.13346 -53.254402)
		(stroke
			(width 0.05715)
			(type default)
		)
		(layer "In2.Cu")
	)
	(gr_line
		(start 71.97598 -42.90314)
		(end 72.1868 -43.11396)
		(stroke
			(width 0.05715)
			(type default)
		)
		(layer "In2.Cu")
	)
	(gr_line
		(start 71.994014 -62.5221)
		(end 72.098154 -62.5221)
		(stroke
			(width 0.05715)
			(type default)
		)
		(layer "In2.Cu")
	)
	(gr_line
		(start 72.102726 -50.796952)
		(end 72.102726 -51.095148)
		(stroke
			(width 0.05715)
			(type default)
		)
		(layer "In2.Cu")
	)
	(gr_line
		(start 72.13346 -53.254402)
		(end 72.13346 -53.552598)
		(stroke
			(width 0.05715)
			(type default)
		)
		(layer "In2.Cu")
	)
	(gr_line
		(start 72.217534 -61.97854)
		(end 72.428354 -62.18936)
		(stroke
			(width 0.05715)
			(type default)
		)
		(layer "In2.Cu")
	)
	(gr_line
		(start 72.347074 -51.810158)
		(end 72.42048 -51.883564)
		(stroke
			(width 0.05715)
			(type default)
		)
		(layer "In2.Cu")
	)
	(gr_line
		(start 72.348852 -51.341274)
		(end 72.647048 -51.341274)
		(stroke
			(width 0.05715)
			(type default)
		)
		(layer "In2.Cu")
	)
	(gr_line
		(start 72.647048 -51.341274)
		(end 72.889364 -51.58359)
		(stroke
			(width 0.05715)
			(type default)
		)
		(layer "In2.Cu")
	)
	(gr_line
		(start 72.776334 -62.18936)
		(end 72.987154 -61.97854)
		(stroke
			(width 0.05715)
			(type default)
		)
		(layer "In2.Cu")
	)
	(gr_line
		(start 72.8472 -14.7066)
		(end 73.043796 -14.903196)
		(stroke
			(width 0.05715)
			(type default)
		)
		(layer "In2.Cu")
	)
	(gr_line
		(start 72.889364 -51.58359)
		(end 72.889364 -51.881786)
		(stroke
			(width 0.05715)
			(type default)
		)
		(layer "In2.Cu")
	)
	(gr_line
		(start 72.987154 -61.97854)
		(end 73.330054 -61.97854)
		(stroke
			(width 0.05715)
			(type default)
		)
		(layer "In2.Cu")
	)
	(gr_line
		(start 73.106534 -62.5221)
		(end 73.210674 -62.5221)
		(stroke
			(width 0.05715)
			(type default)
		)
		(layer "In2.Cu")
	)
	(gr_line
		(start 73.133712 -52.596796)
		(end 73.207118 -52.670202)
		(stroke
			(width 0.05715)
			(type default)
		)
		(layer "In2.Cu")
	)
	(gr_line
		(start 73.13549 -52.127912)
		(end 73.433686 -52.127912)
		(stroke
			(width 0.05715)
			(type default)
		)
		(layer "In2.Cu")
	)
	(gr_line
		(start 73.244202 -45.534072)
		(end 73.317608 -45.607478)
		(stroke
			(width 0.05715)
			(type default)
		)
		(layer "In2.Cu")
	)
	(gr_line
		(start 73.24598 -45.065188)
		(end 73.544176 -45.065188)
		(stroke
			(width 0.05715)
			(type default)
		)
		(layer "In2.Cu")
	)
	(gr_line
		(start 73.330054 -61.97854)
		(end 73.540874 -62.18936)
		(stroke
			(width 0.05715)
			(type default)
		)
		(layer "In2.Cu")
	)
	(gr_line
		(start 73.433686 -52.127912)
		(end 73.676002 -52.370228)
		(stroke
			(width 0.05715)
			(type default)
		)
		(layer "In2.Cu")
	)
	(gr_line
		(start 73.514204 -14.903196)
		(end 73.7108 -14.7066)
		(stroke
			(width 0.05715)
			(type default)
		)
		(layer "In2.Cu")
	)
	(gr_line
		(start 73.544176 -45.065188)
		(end 73.786492 -45.307504)
		(stroke
			(width 0.05715)
			(type default)
		)
		(layer "In2.Cu")
	)
	(gr_line
		(start 73.676002 -52.370228)
		(end 73.676002 -52.668424)
		(stroke
			(width 0.05715)
			(type default)
		)
		(layer "In2.Cu")
	)
	(gr_line
		(start 73.786492 -45.307504)
		(end 73.786492 -45.6057)
		(stroke
			(width 0.05715)
			(type default)
		)
		(layer "In2.Cu")
	)
	(gr_line
		(start 73.842626 -21.0566)
		(end 73.910952 -20.988528)
		(stroke
			(width 0.05715)
			(type default)
		)
		(layer "In2.Cu")
	)
	(gr_line
		(start 74.03084 -46.32071)
		(end 74.104246 -46.394116)
		(stroke
			(width 0.05715)
			(type default)
		)
		(layer "In2.Cu")
	)
	(gr_line
		(start 74.032618 -45.851826)
		(end 74.330814 -45.851826)
		(stroke
			(width 0.05715)
			(type default)
		)
		(layer "In2.Cu")
	)
	(gr_line
		(start 74.330814 -45.851826)
		(end 74.57313 -46.094142)
		(stroke
			(width 0.05715)
			(type default)
		)
		(layer "In2.Cu")
	)
	(gr_line
		(start 74.57313 -46.094142)
		(end 74.57313 -46.392338)
		(stroke
			(width 0.05715)
			(type default)
		)
		(layer "In2.Cu")
	)
	(gr_line
		(start 76.205842 -18.693638)
		(end 76.273914 -18.625566)
		(stroke
			(width 0.05715)
			(type default)
		)
		(layer "In2.Cu")
	)
	(gr_line
		(start 76.711048 -62.18936)
		(end 76.921868 -61.97854)
		(stroke
			(width 0.05715)
			(type default)
		)
		(layer "In2.Cu")
	)
	(gr_line
		(start 76.921868 -61.97854)
		(end 77.264768 -61.97854)
		(stroke
			(width 0.05715)
			(type default)
		)
		(layer "In2.Cu")
	)
	(gr_line
		(start 77.041248 -62.5221)
		(end 77.145388 -62.5221)
		(stroke
			(width 0.05715)
			(type default)
		)
		(layer "In2.Cu")
	)
	(gr_line
		(start 77.264768 -61.97854)
		(end 77.475588 -62.18936)
		(stroke
			(width 0.05715)
			(type default)
		)
		(layer "In2.Cu")
	)
	(gr_line
		(start 77.4192 -14.5796)
		(end 77.615796 -14.776196)
		(stroke
			(width 0.05715)
			(type default)
		)
		(layer "In2.Cu")
	)
	(gr_line
		(start 77.823568 -62.18936)
		(end 78.034388 -61.97854)
		(stroke
			(width 0.05715)
			(type default)
		)
		(layer "In2.Cu")
	)
	(gr_line
		(start 78.034388 -61.97854)
		(end 78.377288 -61.97854)
		(stroke
			(width 0.05715)
			(type default)
		)
		(layer "In2.Cu")
	)
	(gr_line
		(start 78.086204 -14.776196)
		(end 78.2828 -14.5796)
		(stroke
			(width 0.05715)
			(type default)
		)
		(layer "In2.Cu")
	)
	(gr_line
		(start 78.153768 -62.5221)
		(end 78.257908 -62.5221)
		(stroke
			(width 0.05715)
			(type default)
		)
		(layer "In2.Cu")
	)
	(gr_line
		(start 78.26375 -54.00421)
		(end 78.47457 -53.79339)
		(stroke
			(width 0.05715)
			(type default)
		)
		(layer "In2.Cu")
	)
	(gr_line
		(start 78.377288 -61.97854)
		(end 78.588108 -62.18936)
		(stroke
			(width 0.05715)
			(type default)
		)
		(layer "In2.Cu")
	)
	(gr_line
		(start 78.47457 -53.79339)
		(end 78.81747 -53.79339)
		(stroke
			(width 0.05715)
			(type default)
		)
		(layer "In2.Cu")
	)
	(gr_line
		(start 78.567534 -51.66106)
		(end 78.778354 -51.45024)
		(stroke
			(width 0.05715)
			(type default)
		)
		(layer "In2.Cu")
	)
	(gr_line
		(start 78.59395 -54.33695)
		(end 78.69809 -54.33695)
		(stroke
			(width 0.05715)
			(type default)
		)
		(layer "In2.Cu")
	)
	(gr_line
		(start 78.778354 -51.45024)
		(end 79.121254 -51.45024)
		(stroke
			(width 0.05715)
			(type default)
		)
		(layer "In2.Cu")
	)
	(gr_line
		(start 78.81747 -53.79339)
		(end 79.02829 -54.00421)
		(stroke
			(width 0.05715)
			(type default)
		)
		(layer "In2.Cu")
	)
	(gr_line
		(start 78.897734 -51.9938)
		(end 79.001874 -51.9938)
		(stroke
			(width 0.05715)
			(type default)
		)
		(layer "In2.Cu")
	)
	(gr_line
		(start 78.936088 -62.18936)
		(end 79.146908 -61.97854)
		(stroke
			(width 0.05715)
			(type default)
		)
		(layer "In2.Cu")
	)
	(gr_line
		(start 79.121254 -51.45024)
		(end 79.332074 -51.66106)
		(stroke
			(width 0.05715)
			(type default)
		)
		(layer "In2.Cu")
	)
	(gr_line
		(start 79.146908 -61.97854)
		(end 79.489808 -61.97854)
		(stroke
			(width 0.05715)
			(type default)
		)
		(layer "In2.Cu")
	)
	(gr_line
		(start 79.266288 -62.5221)
		(end 79.370428 -62.5221)
		(stroke
			(width 0.05715)
			(type default)
		)
		(layer "In2.Cu")
	)
	(gr_line
		(start 79.489808 -61.97854)
		(end 79.700628 -62.18936)
		(stroke
			(width 0.05715)
			(type default)
		)
		(layer "In2.Cu")
	)
	(gr_line
		(start 79.680054 -51.66106)
		(end 79.890874 -51.45024)
		(stroke
			(width 0.05715)
			(type default)
		)
		(layer "In2.Cu")
	)
	(gr_line
		(start 79.890874 -51.45024)
		(end 80.233774 -51.45024)
		(stroke
			(width 0.05715)
			(type default)
		)
		(layer "In2.Cu")
	)
	(gr_line
		(start 80.010254 -51.9938)
		(end 80.114394 -51.9938)
		(stroke
			(width 0.05715)
			(type default)
		)
		(layer "In2.Cu")
	)
	(gr_line
		(start 80.2132 -14.5796)
		(end 80.409796 -14.776196)
		(stroke
			(width 0.05715)
			(type default)
		)
		(layer "In2.Cu")
	)
	(gr_line
		(start 80.233774 -51.45024)
		(end 80.444594 -51.66106)
		(stroke
			(width 0.05715)
			(type default)
		)
		(layer "In2.Cu")
	)
	(gr_line
		(start 80.3402 -56.261)
		(end 80.3656 -56.261)
		(stroke
			(width 0.0508)
			(type default)
		)
		(layer "In2.Cu")
	)
	(gr_line
		(start 80.3402 -55.9308)
		(end 80.3656 -55.9308)
		(stroke
			(width 0.0508)
			(type default)
		)
		(layer "In2.Cu")
	)
	(gr_line
		(start 80.3656 -56.261)
		(end 80.385158 -56.241442)
		(stroke
			(width 0.0508)
			(type default)
		)
		(layer "In2.Cu")
	)
	(gr_line
		(start 80.3656 -55.9308)
		(end 80.385158 -55.950358)
		(stroke
			(width 0.0508)
			(type default)
		)
		(layer "In2.Cu")
	)
	(gr_line
		(start 80.386936 -56.239664)
		(end 80.4291 -56.1975)
		(stroke
			(width 0.0508)
			(type default)
		)
		(layer "In2.Cu")
	)
	(gr_line
		(start 80.386936 -55.952136)
		(end 80.4291 -55.9943)
		(stroke
			(width 0.0508)
			(type default)
		)
		(layer "In2.Cu")
	)
	(gr_line
		(start 80.4164 -55.5625)
		(end 80.4291 -55.5625)
		(stroke
			(width 0.0508)
			(type default)
		)
		(layer "In2.Cu")
	)
	(gr_line
		(start 80.4164 -55.2323)
		(end 80.442308 -55.258208)
		(stroke
			(width 0.0508)
			(type default)
		)
		(layer "In2.Cu")
	)
	(gr_line
		(start 80.4291 -55.5625)
		(end 80.442308 -55.549292)
		(stroke
			(width 0.0508)
			(type default)
		)
		(layer "In2.Cu")
	)
	(gr_line
		(start 80.444086 -55.547514)
		(end 80.4926 -55.499)
		(stroke
			(width 0.0508)
			(type default)
		)
		(layer "In2.Cu")
	)
	(gr_line
		(start 80.444086 -55.259986)
		(end 80.4799 -55.2958)
		(stroke
			(width 0.0508)
			(type default)
		)
		(layer "In2.Cu")
	)
	(gr_line
		(start 80.524604 -54.642004)
		(end 80.5688 -54.6862)
		(stroke
			(width 0.05715)
			(type default)
		)
		(layer "In2.Cu")
	)
	(gr_line
		(start 80.524604 -54.171596)
		(end 80.5688 -54.1274)
		(stroke
			(width 0.05715)
			(type default)
		)
		(layer "In2.Cu")
	)
	(gr_line
		(start 80.71612 -55.99176)
		(end 80.81264 -55.89524)
		(stroke
			(width 0.0508)
			(type default)
		)
		(layer "In2.Cu")
	)
	(gr_line
		(start 80.792574 -51.66106)
		(end 81.003394 -51.45024)
		(stroke
			(width 0.05715)
			(type default)
		)
		(layer "In2.Cu")
	)
	(gr_line
		(start 80.81264 -55.89524)
		(end 81.11744 -55.89524)
		(stroke
			(width 0.0508)
			(type default)
		)
		(layer "In2.Cu")
	)
	(gr_line
		(start 80.880204 -14.776196)
		(end 81.0768 -14.5796)
		(stroke
			(width 0.05715)
			(type default)
		)
		(layer "In2.Cu")
	)
	(gr_line
		(start 80.91932 -56.1975)
		(end 81.01076 -56.1975)
		(stroke
			(width 0.0508)
			(type default)
		)
		(layer "In2.Cu")
	)
	(gr_line
		(start 81.003394 -51.45024)
		(end 81.346294 -51.45024)
		(stroke
			(width 0.05715)
			(type default)
		)
		(layer "In2.Cu")
	)
	(gr_line
		(start 81.11744 -55.89524)
		(end 81.21396 -55.99176)
		(stroke
			(width 0.0508)
			(type default)
		)
		(layer "In2.Cu")
	)
	(gr_line
		(start 81.122774 -51.9938)
		(end 81.226914 -51.9938)
		(stroke
			(width 0.05715)
			(type default)
		)
		(layer "In2.Cu")
	)
	(gr_line
		(start 81.346294 -51.45024)
		(end 81.557114 -51.66106)
		(stroke
			(width 0.05715)
			(type default)
		)
		(layer "In2.Cu")
	)
	(gr_line
		(start 81.629504 -53.537104)
		(end 81.6864 -53.594)
		(stroke
			(width 0.05715)
			(type default)
		)
		(layer "In2.Cu")
	)
	(gr_line
		(start 81.629504 -53.066696)
		(end 81.6864 -53.0098)
		(stroke
			(width 0.05715)
			(type default)
		)
		(layer "In2.Cu")
	)
	(gr_line
		(start 81.749392 -50.34534)
		(end 81.853024 -50.448972)
		(stroke
			(width 0.05715)
			(type default)
		)
		(layer "In2.Cu")
	)
	(gr_line
		(start 82.066384 -50.0126)
		(end 82.1182 -49.960784)
		(stroke
			(width 0.05715)
			(type default)
		)
		(layer "In2.Cu")
	)
	(gr_line
		(start 82.1182 -49.960784)
		(end 82.126074 -49.960784)
		(stroke
			(width 0.05715)
			(type default)
		)
		(layer "In2.Cu")
	)
	(gr_line
		(start 82.268822 -55.233824)
		(end 82.268822 -55.370222)
		(stroke
			(width 0.0508)
			(type default)
		)
		(layer "In2.Cu")
	)
	(gr_line
		(start 82.268822 -55.233824)
		(end 82.484214 -55.018178)
		(stroke
			(width 0.0508)
			(type default)
		)
		(layer "In2.Cu")
	)
	(gr_line
		(start 82.484214 -55.018178)
		(end 82.620866 -55.018178)
		(stroke
			(width 0.0508)
			(type default)
		)
		(layer "In2.Cu")
	)
	(gr_line
		(start 82.558128 -55.372)
		(end 82.622644 -55.307484)
		(stroke
			(width 0.0508)
			(type default)
		)
		(layer "In2.Cu")
	)
	(gr_line
		(start 82.656934 -57.554876)
		(end 82.674714 -57.537096)
		(stroke
			(width 0.0508)
			(type default)
		)
		(layer "In2.Cu")
	)
	(gr_line
		(start 82.674714 -57.537096)
		(end 82.702654 -57.537096)
		(stroke
			(width 0.0508)
			(type default)
		)
		(layer "In2.Cu")
	)
	(gr_line
		(start 82.705194 -57.537096)
		(end 82.764376 -57.537096)
		(stroke
			(width 0.0508)
			(type default)
		)
		(layer "In2.Cu")
	)
	(gr_line
		(start 82.713068 -51.460908)
		(end 82.713068 -51.525932)
		(stroke
			(width 0.05715)
			(type default)
		)
		(layer "In2.Cu")
	)
	(gr_line
		(start 82.713068 -51.39055)
		(end 82.713068 -51.458368)
		(stroke
			(width 0.05715)
			(type default)
		)
		(layer "In2.Cu")
	)
	(gr_line
		(start 82.771742 -56.685942)
		(end 82.808826 -56.685942)
		(stroke
			(width 0.0508)
			(type default)
		)
		(layer "In2.Cu")
	)
	(gr_line
		(start 82.811366 -56.685942)
		(end 82.861658 -56.685942)
		(stroke
			(width 0.0508)
			(type default)
		)
		(layer "In2.Cu")
	)
	(gr_line
		(start 82.839814 -54.662578)
		(end 82.839814 -54.79923)
		(stroke
			(width 0.0508)
			(type default)
		)
		(layer "In2.Cu")
	)
	(gr_line
		(start 82.839814 -54.662578)
		(end 83.05546 -54.447186)
		(stroke
			(width 0.0508)
			(type default)
		)
		(layer "In2.Cu")
	)
	(gr_line
		(start 82.89036 -57.788556)
		(end 82.908394 -57.770522)
		(stroke
			(width 0.0508)
			(type default)
		)
		(layer "In2.Cu")
	)
	(gr_line
		(start 82.908394 -57.742836)
		(end 82.908394 -57.770522)
		(stroke
			(width 0.0508)
			(type default)
		)
		(layer "In2.Cu")
	)
	(gr_line
		(start 82.908394 -57.680606)
		(end 82.908394 -57.740296)
		(stroke
			(width 0.0508)
			(type default)
		)
		(layer "In2.Cu")
	)
	(gr_line
		(start 82.914998 -51.791108)
		(end 83.043268 -51.791108)
		(stroke
			(width 0.05715)
			(type default)
		)
		(layer "In2.Cu")
	)
	(gr_line
		(start 83.005422 -56.919622)
		(end 83.014566 -56.910478)
		(stroke
			(width 0.0508)
			(type default)
		)
		(layer "In2.Cu")
	)
	(gr_line
		(start 83.014566 -56.891682)
		(end 83.014566 -56.910478)
		(stroke
			(width 0.0508)
			(type default)
		)
		(layer "In2.Cu")
	)
	(gr_line
		(start 83.014566 -56.820562)
		(end 83.014566 -56.889142)
		(stroke
			(width 0.0508)
			(type default)
		)
		(layer "In2.Cu")
	)
	(gr_line
		(start 83.045808 -51.791108)
		(end 83.112864 -51.791108)
		(stroke
			(width 0.05715)
			(type default)
		)
		(layer "In2.Cu")
	)
	(gr_line
		(start 83.05546 -54.447186)
		(end 83.191858 -54.447186)
		(stroke
			(width 0.0508)
			(type default)
		)
		(layer "In2.Cu")
	)
	(gr_line
		(start 83.12912 -54.801008)
		(end 83.193636 -54.736492)
		(stroke
			(width 0.0508)
			(type default)
		)
		(layer "In2.Cu")
	)
	(gr_line
		(start 83.283552 -10.51814)
		(end 83.388962 -10.41273)
		(stroke
			(width 0.05715)
			(type default)
		)
		(layer "In2.Cu")
	)
	(gr_line
		(start 83.423506 -52.775358)
		(end 83.423506 -52.91201)
		(stroke
			(width 0.0508)
			(type default)
		)
		(layer "In2.Cu")
	)
	(gr_line
		(start 83.423506 -52.775358)
		(end 83.639152 -52.559966)
		(stroke
			(width 0.0508)
			(type default)
		)
		(layer "In2.Cu")
	)
	(gr_line
		(start 83.58378 -62.18936)
		(end 83.7946 -61.97854)
		(stroke
			(width 0.05715)
			(type default)
		)
		(layer "In2.Cu")
	)
	(gr_line
		(start 83.613752 -10.85088)
		(end 83.872324 -10.85088)
		(stroke
			(width 0.05715)
			(type default)
		)
		(layer "In2.Cu")
	)
	(gr_line
		(start 83.639152 -52.559966)
		(end 83.77555 -52.559966)
		(stroke
			(width 0.0508)
			(type default)
		)
		(layer "In2.Cu")
	)
	(gr_line
		(start 83.712812 -52.913788)
		(end 83.777328 -52.849272)
		(stroke
			(width 0.0508)
			(type default)
		)
		(layer "In2.Cu")
	)
	(gr_line
		(start 83.7946 -61.97854)
		(end 84.1375 -61.97854)
		(stroke
			(width 0.05715)
			(type default)
		)
		(layer "In2.Cu")
	)
	(gr_line
		(start 83.872324 -10.85088)
		(end 84.310474 -10.41273)
		(stroke
			(width 0.05715)
			(type default)
		)
		(layer "In2.Cu")
	)
	(gr_line
		(start 83.91398 -62.5221)
		(end 84.01812 -62.5221)
		(stroke
			(width 0.05715)
			(type default)
		)
		(layer "In2.Cu")
	)
	(gr_line
		(start 83.99145 -57.2262)
		(end 84.120736 -57.096914)
		(stroke
			(width 0.05715)
			(type default)
		)
		(layer "In2.Cu")
	)
	(gr_line
		(start 83.994752 -52.204366)
		(end 83.994752 -52.340764)
		(stroke
			(width 0.0508)
			(type default)
		)
		(layer "In2.Cu")
	)
	(gr_line
		(start 83.994752 -52.204366)
		(end 84.210144 -51.98872)
		(stroke
			(width 0.0508)
			(type default)
		)
		(layer "In2.Cu")
	)
	(gr_line
		(start 84.050632 -54.20614)
		(end 84.100162 -54.15661)
		(stroke
			(width 0.0508)
			(type default)
		)
		(layer "In2.Cu")
	)
	(gr_line
		(start 84.065364 -54.40934)
		(end 84.100162 -54.444138)
		(stroke
			(width 0.0508)
			(type default)
		)
		(layer "In2.Cu")
	)
	(gr_line
		(start 84.10194 -54.445916)
		(end 84.230464 -54.57444)
		(stroke
			(width 0.0508)
			(type default)
		)
		(layer "In2.Cu")
	)
	(gr_line
		(start 84.10194 -54.154832)
		(end 84.241132 -54.01564)
		(stroke
			(width 0.0508)
			(type default)
		)
		(layer "In2.Cu")
	)
	(gr_line
		(start 84.120736 -57.096914)
		(end 84.159344 -57.096914)
		(stroke
			(width 0.0508)
			(type default)
		)
		(layer "In2.Cu")
	)
	(gr_line
		(start 84.1375 -61.97854)
		(end 84.34832 -62.18936)
		(stroke
			(width 0.05715)
			(type default)
		)
		(layer "In2.Cu")
	)
	(gr_line
		(start 84.161884 -57.096914)
		(end 84.203286 -57.096914)
		(stroke
			(width 0.0508)
			(type default)
		)
		(layer "In2.Cu")
	)
	(gr_line
		(start 84.210144 -51.98872)
		(end 84.346796 -51.98872)
		(stroke
			(width 0.0508)
			(type default)
		)
		(layer "In2.Cu")
	)
	(gr_line
		(start 84.284058 -52.342542)
		(end 84.348574 -52.278026)
		(stroke
			(width 0.0508)
			(type default)
		)
		(layer "In2.Cu")
	)
	(gr_line
		(start 84.354416 -57.33034)
		(end 84.365084 -57.319672)
		(stroke
			(width 0.0508)
			(type default)
		)
		(layer "In2.Cu")
	)
	(gr_line
		(start 84.365084 -57.302654)
		(end 84.365084 -57.319672)
		(stroke
			(width 0.0508)
			(type default)
		)
		(layer "In2.Cu")
	)
	(gr_line
		(start 84.365084 -57.222644)
		(end 84.365084 -57.300114)
		(stroke
			(width 0.0508)
			(type default)
		)
		(layer "In2.Cu")
	)
	(gr_line
		(start 84.365084 -57.222644)
		(end 84.49437 -57.093358)
		(stroke
			(width 0.0508)
			(type default)
		)
		(layer "In2.Cu")
	)
	(gr_line
		(start 84.6963 -62.18936)
		(end 84.90712 -61.97854)
		(stroke
			(width 0.05715)
			(type default)
		)
		(layer "In2.Cu")
	)
	(gr_line
		(start 84.90712 -61.97854)
		(end 85.25002 -61.97854)
		(stroke
			(width 0.05715)
			(type default)
		)
		(layer "In2.Cu")
	)
	(gr_line
		(start 84.921598 -57.38114)
		(end 84.939632 -57.363106)
		(stroke
			(width 0.0508)
			(type default)
		)
		(layer "In2.Cu")
	)
	(gr_line
		(start 84.939632 -57.363106)
		(end 84.967318 -57.363106)
		(stroke
			(width 0.0508)
			(type default)
		)
		(layer "In2.Cu")
	)
	(gr_line
		(start 84.969858 -57.363106)
		(end 85.029294 -57.363106)
		(stroke
			(width 0.0508)
			(type default)
		)
		(layer "In2.Cu")
	)
	(gr_line
		(start 85.0265 -62.5221)
		(end 85.13064 -62.5221)
		(stroke
			(width 0.05715)
			(type default)
		)
		(layer "In2.Cu")
	)
	(gr_line
		(start 85.155024 -57.61482)
		(end 85.173058 -57.596786)
		(stroke
			(width 0.0508)
			(type default)
		)
		(layer "In2.Cu")
	)
	(gr_line
		(start 85.173058 -57.568846)
		(end 85.173058 -57.596786)
		(stroke
			(width 0.0508)
			(type default)
		)
		(layer "In2.Cu")
	)
	(gr_line
		(start 85.173058 -57.50687)
		(end 85.173058 -57.566306)
		(stroke
			(width 0.0508)
			(type default)
		)
		(layer "In2.Cu")
	)
	(gr_line
		(start 85.1916 -50.0126)
		(end 85.3948 -50.2158)
		(stroke
			(width 0.0508)
			(type default)
		)
		(layer "In2.Cu")
	)
	(gr_line
		(start 85.1916 -49.8602)
		(end 85.1916 -50.0126)
		(stroke
			(width 0.0508)
			(type default)
		)
		(layer "In2.Cu")
	)
	(gr_line
		(start 85.25002 -61.97854)
		(end 85.46084 -62.18936)
		(stroke
			(width 0.05715)
			(type default)
		)
		(layer "In2.Cu")
	)
	(gr_line
		(start 85.277706 -50.626518)
		(end 85.482684 -50.42154)
		(stroke
			(width 0.0508)
			(type default)
		)
		(layer "In2.Cu")
	)
	(gr_line
		(start 85.346286 -59.460638)
		(end 85.471508 -59.335416)
		(stroke
			(width 0.05715)
			(type default)
		)
		(layer "In2.Cu")
	)
	(gr_line
		(start 85.469984 -55.1561)
		(end 85.54085 -55.226966)
		(stroke
			(width 0.0508)
			(type default)
		)
		(layer "In2.Cu")
	)
	(gr_line
		(start 85.471508 -59.335416)
		(end 85.480906 -59.326018)
		(stroke
			(width 0.0508)
			(type default)
		)
		(layer "In2.Cu")
	)
	(gr_line
		(start 85.480906 -59.326018)
		(end 85.517482 -59.326018)
		(stroke
			(width 0.0508)
			(type default)
		)
		(layer "In2.Cu")
	)
	(gr_line
		(start 85.520022 -59.326018)
		(end 85.570314 -59.326018)
		(stroke
			(width 0.0508)
			(type default)
		)
		(layer "In2.Cu")
	)
	(gr_line
		(start 85.527388 -54.9529)
		(end 85.54085 -54.939438)
		(stroke
			(width 0.0508)
			(type default)
		)
		(layer "In2.Cu")
	)
	(gr_line
		(start 85.542628 -55.228744)
		(end 85.675978 -55.362094)
		(stroke
			(width 0.0508)
			(type default)
		)
		(layer "In2.Cu")
	)
	(gr_line
		(start 85.542628 -54.93766)
		(end 85.684614 -54.795674)
		(stroke
			(width 0.0508)
			(type default)
		)
		(layer "In2.Cu")
	)
	(gr_line
		(start 85.704934 -59.569096)
		(end 85.723222 -59.550808)
		(stroke
			(width 0.0508)
			(type default)
		)
		(layer "In2.Cu")
	)
	(gr_line
		(start 85.723222 -59.531758)
		(end 85.723222 -59.550808)
		(stroke
			(width 0.0508)
			(type default)
		)
		(layer "In2.Cu")
	)
	(gr_line
		(start 85.723222 -59.460638)
		(end 85.723222 -59.529218)
		(stroke
			(width 0.0508)
			(type default)
		)
		(layer "In2.Cu")
	)
	(gr_line
		(start 85.723222 -59.460638)
		(end 85.848444 -59.335416)
		(stroke
			(width 0.0508)
			(type default)
		)
		(layer "In2.Cu")
	)
	(gr_line
		(start 85.80882 -62.18936)
		(end 86.01964 -61.97854)
		(stroke
			(width 0.05715)
			(type default)
		)
		(layer "In2.Cu")
	)
	(gr_line
		(start 85.890608 -53.5686)
		(end 85.954362 -53.632354)
		(stroke
			(width 0.0508)
			(type default)
		)
		(layer "In2.Cu")
	)
	(gr_line
		(start 85.933788 -53.3654)
		(end 85.954362 -53.344826)
		(stroke
			(width 0.0508)
			(type default)
		)
		(layer "In2.Cu")
	)
	(gr_line
		(start 85.95614 -53.634132)
		(end 86.087204 -53.765196)
		(stroke
			(width 0.0508)
			(type default)
		)
		(layer "In2.Cu")
	)
	(gr_line
		(start 85.95614 -53.343048)
		(end 86.097618 -53.20157)
		(stroke
			(width 0.0508)
			(type default)
		)
		(layer "In2.Cu")
	)
	(gr_line
		(start 86.01964 -61.97854)
		(end 86.36254 -61.97854)
		(stroke
			(width 0.05715)
			(type default)
		)
		(layer "In2.Cu")
	)
	(gr_line
		(start 86.13902 -62.5221)
		(end 86.24316 -62.5221)
		(stroke
			(width 0.05715)
			(type default)
		)
		(layer "In2.Cu")
	)
	(gr_line
		(start 86.36254 -61.97854)
		(end 86.57336 -62.18936)
		(stroke
			(width 0.05715)
			(type default)
		)
		(layer "In2.Cu")
	)
	(gr_line
		(start 86.92134 -62.18936)
		(end 87.13216 -61.97854)
		(stroke
			(width 0.05715)
			(type default)
		)
		(layer "In2.Cu")
	)
	(gr_line
		(start 87.041482 -54.71033)
		(end 87.172292 -54.84114)
		(stroke
			(width 0.0508)
			(type default)
		)
		(layer "In2.Cu")
	)
	(gr_line
		(start 87.041482 -54.419246)
		(end 87.183468 -54.27726)
		(stroke
			(width 0.0508)
			(type default)
		)
		(layer "In2.Cu")
	)
	(gr_line
		(start 87.13216 -61.97854)
		(end 87.47506 -61.97854)
		(stroke
			(width 0.05715)
			(type default)
		)
		(layer "In2.Cu")
	)
	(gr_line
		(start 87.25154 -62.5221)
		(end 87.35568 -62.5221)
		(stroke
			(width 0.05715)
			(type default)
		)
		(layer "In2.Cu")
	)
	(gr_line
		(start 87.47506 -61.97854)
		(end 87.68588 -62.18936)
		(stroke
			(width 0.05715)
			(type default)
		)
		(layer "In2.Cu")
	)
	(gr_line
		(start 88.03386 -62.18936)
		(end 88.24468 -61.97854)
		(stroke
			(width 0.05715)
			(type default)
		)
		(layer "In2.Cu")
	)
	(gr_line
		(start 88.073992 -53.73624)
		(end 88.306656 -53.968904)
		(stroke
			(width 0.0508)
			(type default)
		)
		(layer "In2.Cu")
	)
	(gr_line
		(start 88.16848 -53.5305)
		(end 88.288622 -53.410358)
		(stroke
			(width 0.0508)
			(type default)
		)
		(layer "In2.Cu")
	)
	(gr_line
		(start 88.24468 -61.97854)
		(end 88.58758 -61.97854)
		(stroke
			(width 0.05715)
			(type default)
		)
		(layer "In2.Cu")
	)
	(gr_line
		(start 88.36406 -62.5221)
		(end 88.4682 -62.5221)
		(stroke
			(width 0.05715)
			(type default)
		)
		(layer "In2.Cu")
	)
	(gr_line
		(start 88.58758 -61.97854)
		(end 88.7984 -62.18936)
		(stroke
			(width 0.05715)
			(type default)
		)
		(layer "In2.Cu")
	)
	(gr_line
		(start 89.595198 -53.9115)
		(end 89.65184 -53.968142)
		(stroke
			(width 0.0508)
			(type default)
		)
		(layer "In2.Cu")
	)
	(gr_line
		(start 89.624154 -53.7083)
		(end 89.65184 -53.680614)
		(stroke
			(width 0.0508)
			(type default)
		)
		(layer "In2.Cu")
	)
	(gr_line
		(start 89.653618 -53.96992)
		(end 89.75979 -54.076092)
		(stroke
			(width 0.0508)
			(type default)
		)
		(layer "In2.Cu")
	)
	(gr_line
		(start 89.653618 -53.678836)
		(end 89.812876 -53.519578)
		(stroke
			(width 0.0508)
			(type default)
		)
		(layer "In2.Cu")
	)
	(gr_line
		(start 90.923364 -55.249064)
		(end 91.063318 -55.249064)
		(stroke
			(width 0.05715)
			(type default)
		)
		(layer "In2.Cu")
	)
	(gr_line
		(start 91.065858 -55.249064)
		(end 91.088464 -55.249064)
		(stroke
			(width 0.05715)
			(type default)
		)
		(layer "In2.Cu")
	)
	(gr_line
		(start 91.088464 -55.249064)
		(end 91.32316 -55.48376)
		(stroke
			(width 0.05715)
			(type default)
		)
		(layer "In2.Cu")
	)
	(gr_line
		(start 91.11234 -56.38546)
		(end 91.32316 -56.59628)
		(stroke
			(width 0.05715)
			(type default)
		)
		(layer "In2.Cu")
	)
	(gr_line
		(start 91.11234 -56.04256)
		(end 91.11234 -56.38546)
		(stroke
			(width 0.05715)
			(type default)
		)
		(layer "In2.Cu")
	)
	(gr_line
		(start 91.11234 -56.04256)
		(end 91.32316 -55.83174)
		(stroke
			(width 0.05715)
			(type default)
		)
		(layer "In2.Cu")
	)
	(gr_line
		(start 91.396058 -55.064152)
		(end 91.6559 -55.323994)
		(stroke
			(width 0.05715)
			(type default)
		)
		(layer "In2.Cu")
	)
	(gr_line
		(start 91.396058 -54.950614)
		(end 91.396058 -55.064152)
		(stroke
			(width 0.05715)
			(type default)
		)
		(layer "In2.Cu")
	)
	(gr_line
		(start 91.6559 -56.16194)
		(end 91.6559 -56.26608)
		(stroke
			(width 0.05715)
			(type default)
		)
		(layer "In2.Cu")
	)
	(gr_line
		(start 95.92818 -22.54758)
		(end 96.393 -23.0124)
		(stroke
			(width 0.0762)
			(type default)
		)
		(layer "In2.Cu")
	)
	(gr_line
		(start 95.92818 -20.98802)
		(end 95.92818 -22.54758)
		(stroke
			(width 0.0762)
			(type default)
		)
		(layer "In2.Cu")
	)
	(gr_line
		(start 95.92818 -20.98802)
		(end 95.995998 -20.920202)
		(stroke
			(width 0.0762)
			(type default)
		)
		(layer "In2.Cu")
	)
	(gr_line
		(start 96.393 -20.92198)
		(end 96.393 -21.158708)
		(stroke
			(width 0.0762)
			(type default)
		)
		(layer "In2.Cu")
	)
	(gr_line
		(start 104.6607 -57.1754)
		(end 104.8639 -57.3786)
		(stroke
			(width 0.0508)
			(type default)
		)
		(layer "In2.Cu")
	)
	(gr_line
		(start 104.6734 -55.4736)
		(end 105.1433 -55.9435)
		(stroke
			(width 0.0508)
			(type default)
		)
		(layer "In2.Cu")
	)
	(gr_line
		(start 104.8639 -57.3786)
		(end 104.8639 -57.7723)
		(stroke
			(width 0.0508)
			(type default)
		)
		(layer "In2.Cu")
	)
	(gr_line
		(start 104.9528 -24.530812)
		(end 105.313988 -24.892)
		(stroke
			(width 0.0508)
			(type default)
		)
		(layer "In2.Cu")
	)
	(gr_line
		(start 104.9528 -22.6822)
		(end 104.9528 -24.530812)
		(stroke
			(width 0.0508)
			(type default)
		)
		(layer "In2.Cu")
	)
	(gr_line
		(start 104.9528 -22.6822)
		(end 105.050082 -22.584918)
		(stroke
			(width 0.0508)
			(type default)
		)
		(layer "In2.Cu")
	)
	(gr_line
		(start 105.1433 -55.9435)
		(end 105.1433 -57.656476)
		(stroke
			(width 0.0508)
			(type default)
		)
		(layer "In2.Cu")
	)
	(gr_line
		(start 105.339388 -22.586696)
		(end 105.339388 -22.9235)
		(stroke
			(width 0.0508)
			(type default)
		)
		(layer "In2.Cu")
	)
	(gr_line
		(start 106.898694 -38.020498)
		(end 107.10418 -37.815012)
		(stroke
			(width 0.0508)
			(type default)
		)
		(layer "In2.Cu")
	)
	(gr_line
		(start 106.898694 -37.318442)
		(end 107.10418 -37.523928)
		(stroke
			(width 0.0508)
			(type default)
		)
		(layer "In2.Cu")
	)
	(gr_line
		(start 107.105958 -37.813234)
		(end 107.172506 -37.746686)
		(stroke
			(width 0.0508)
			(type default)
		)
		(layer "In2.Cu")
	)
	(gr_line
		(start 107.105958 -37.525706)
		(end 107.123738 -37.543486)
		(stroke
			(width 0.0508)
			(type default)
		)
		(layer "In2.Cu")
	)
	(gr_line
		(start 110.643924 -21.8186)
		(end 110.7186 -21.8186)
		(stroke
			(width 0.0508)
			(type default)
		)
		(layer "In2.Cu")
	)
	(gr_line
		(start 110.72114 -21.81606)
		(end 110.7694 -21.7678)
		(stroke
			(width 0.0508)
			(type default)
		)
		(layer "In2.Cu")
	)
	(gr_line
		(start 110.859824 -22.0218)
		(end 110.885224 -22.0472)
		(stroke
			(width 0.0508)
			(type default)
		)
		(layer "In2.Cu")
	)
	(gr_line
		(start 110.885224 -22.0472)
		(end 110.9599 -22.0472)
		(stroke
			(width 0.0762)
			(type default)
		)
		(layer "In2.Cu")
	)
	(gr_line
		(start 112.829594 -15.034006)
		(end 112.9792 -14.8844)
		(stroke
			(width 0.0762)
			(type default)
		)
		(layer "In2.Cu")
	)
	(gr_line
		(start 112.9792 -14.8844)
		(end 113.436654 -14.8844)
		(stroke
			(width 0.0762)
			(type default)
		)
		(layer "In2.Cu")
	)
	(gr_line
		(start 113.108994 -15.315946)
		(end 113.30686 -15.315946)
		(stroke
			(width 0.0762)
			(type default)
		)
		(layer "In2.Cu")
	)
	(gr_line
		(start 113.436654 -14.8844)
		(end 113.58626 -15.034006)
		(stroke
			(width 0.0762)
			(type default)
		)
		(layer "In2.Cu")
	)
	(gr_line
		(start 115.062 -44.4246)
		(end 115.4938 -43.9928)
		(stroke
			(width 0.0508)
			(type default)
		)
		(layer "In2.Cu")
	)
	(gr_line
		(start 115.1636 -49.0982)
		(end 115.566952 -48.694848)
		(stroke
			(width 0.0508)
			(type default)
		)
		(layer "In2.Cu")
	)
	(gr_line
		(start 115.4938 -43.9928)
		(end 116.86286 -43.9928)
		(stroke
			(width 0.0508)
			(type default)
		)
		(layer "In2.Cu")
	)
	(gr_line
		(start 115.566952 -48.694848)
		(end 116.936012 -48.694848)
		(stroke
			(width 0.0508)
			(type default)
		)
		(layer "In2.Cu")
	)
	(gr_line
		(start 115.951 -32.0294)
		(end 116.2939 -31.6865)
		(stroke
			(width 0.0508)
			(type default)
		)
		(layer "In2.Cu")
	)
	(gr_line
		(start 116.2939 -31.6865)
		(end 117.371114 -31.6865)
		(stroke
			(width 0.0508)
			(type default)
		)
		(layer "In2.Cu")
	)
	(gr_line
		(start 116.84 -44.4246)
		(end 117.06606 -44.19854)
		(stroke
			(width 0.0508)
			(type default)
		)
		(layer "In2.Cu")
	)
	(gr_line
		(start 116.9416 -49.0982)
		(end 117.139212 -48.900588)
		(stroke
			(width 0.0508)
			(type default)
		)
		(layer "In2.Cu")
	)
	(gr_line
		(start 117.3861 -36.66744)
		(end 117.512084 -36.66744)
		(stroke
			(width 0.0508)
			(type default)
		)
		(layer "In2.Cu")
	)
	(gr_line
		(start 117.512084 -36.66744)
		(end 117.520212 -36.675568)
		(stroke
			(width 0.0508)
			(type default)
		)
		(layer "In2.Cu")
	)
	(gr_line
		(start 117.583458 -36.738814)
		(end 117.6147 -36.738814)
		(stroke
			(width 0.0508)
			(type default)
		)
		(layer "In2.Cu")
	)
	(gr_line
		(start 117.59819 -36.462462)
		(end 117.601238 -36.459414)
		(stroke
			(width 0.0508)
			(type default)
		)
		(layer "In2.Cu")
	)
	(gr_line
		(start 117.601238 -36.459414)
		(end 117.6274 -36.459414)
		(stroke
			(width 0.0508)
			(type default)
		)
		(layer "In2.Cu")
	)
	(gr_line
		(start 117.6274 -36.459414)
		(end 117.753384 -36.459414)
		(stroke
			(width 0.0762)
			(type default)
		)
		(layer "In2.Cu")
	)
	(gr_line
		(start 117.6528 -31.695898)
		(end 117.6528 -32.0548)
		(stroke
			(width 0.0508)
			(type default)
		)
		(layer "In2.Cu")
	)
	(gr_line
		(start 118.501668 -43.880532)
		(end 118.618 -43.7642)
		(stroke
			(width 0.0508)
			(type default)
		)
		(layer "In2.Cu")
	)
	(gr_line
		(start 118.501668 -43.593258)
		(end 118.62308 -43.471846)
		(stroke
			(width 0.0508)
			(type default)
		)
		(layer "In2.Cu")
	)
	(gr_line
		(start 118.501668 -43.593004)
		(end 118.501668 -43.593258)
		(stroke
			(width 0.0508)
			(type default)
		)
		(layer "In2.Cu")
	)
	(gr_line
		(start 118.618 -43.7642)
		(end 118.654068 -43.7642)
		(stroke
			(width 0.0508)
			(type default)
		)
		(layer "In2.Cu")
	)
	(gr_line
		(start 118.628414 -43.466512)
		(end 118.686326 -43.4086)
		(stroke
			(width 0.0508)
			(type default)
		)
		(layer "In2.Cu")
	)
	(gr_line
		(start 118.654068 -43.7642)
		(end 118.730268 -43.688)
		(stroke
			(width 0.0508)
			(type default)
		)
		(layer "In2.Cu")
	)
	(gr_line
		(start 118.730268 -43.688)
		(end 118.748302 -43.688)
		(stroke
			(width 0.0762)
			(type default)
		)
		(layer "In2.Cu")
	)
	(gr_line
		(start 118.775226 -30.861254)
		(end 118.810786 -30.896814)
		(stroke
			(width 0.0508)
			(type default)
		)
		(layer "In2.Cu")
	)
	(gr_line
		(start 118.854982 -13.63726)
		(end 118.976902 -13.51534)
		(stroke
			(width 0.0762)
			(type default)
		)
		(layer "In2.Cu")
	)
	(gr_line
		(start 118.885716 -49.800256)
		(end 119.0244 -49.800256)
		(stroke
			(width 0.0508)
			(type default)
		)
		(layer "In2.Cu")
	)
	(gr_line
		(start 118.976902 -13.51534)
		(end 119.434102 -13.51534)
		(stroke
			(width 0.0762)
			(type default)
		)
		(layer "In2.Cu")
	)
	(gr_line
		(start 119.134382 -13.9192)
		(end 119.276622 -13.9192)
		(stroke
			(width 0.0762)
			(type default)
		)
		(layer "In2.Cu")
	)
	(gr_line
		(start 119.434102 -13.51534)
		(end 119.556022 -13.63726)
		(stroke
			(width 0.0762)
			(type default)
		)
		(layer "In2.Cu")
	)
	(gr_line
		(start 120.018302 -13.63726)
		(end 120.140222 -13.51534)
		(stroke
			(width 0.0762)
			(type default)
		)
		(layer "In2.Cu")
	)
	(gr_line
		(start 120.140222 -13.51534)
		(end 120.597422 -13.51534)
		(stroke
			(width 0.0762)
			(type default)
		)
		(layer "In2.Cu")
	)
	(gr_line
		(start 120.297702 -13.9192)
		(end 120.439942 -13.9192)
		(stroke
			(width 0.0762)
			(type default)
		)
		(layer "In2.Cu")
	)
	(gr_line
		(start 120.597422 -13.51534)
		(end 120.719342 -13.63726)
		(stroke
			(width 0.0762)
			(type default)
		)
		(layer "In2.Cu")
	)
	(gr_line
		(start 121.181622 -13.63726)
		(end 121.303542 -13.51534)
		(stroke
			(width 0.0762)
			(type default)
		)
		(layer "In2.Cu")
	)
	(gr_line
		(start 121.303542 -13.51534)
		(end 121.760742 -13.51534)
		(stroke
			(width 0.0762)
			(type default)
		)
		(layer "In2.Cu")
	)
	(gr_line
		(start 121.461022 -13.9192)
		(end 121.603262 -13.9192)
		(stroke
			(width 0.0762)
			(type default)
		)
		(layer "In2.Cu")
	)
	(gr_line
		(start 121.760742 -13.51534)
		(end 121.882662 -13.63726)
		(stroke
			(width 0.0762)
			(type default)
		)
		(layer "In2.Cu")
	)
	(gr_line
		(start 123.759722 -13.63726)
		(end 123.881642 -13.51534)
		(stroke
			(width 0.0762)
			(type default)
		)
		(layer "In2.Cu")
	)
	(gr_line
		(start 123.881642 -13.51534)
		(end 124.338842 -13.51534)
		(stroke
			(width 0.0762)
			(type default)
		)
		(layer "In2.Cu")
	)
	(gr_line
		(start 124.039122 -13.9192)
		(end 124.181362 -13.9192)
		(stroke
			(width 0.0762)
			(type default)
		)
		(layer "In2.Cu")
	)
	(gr_line
		(start 124.338842 -13.51534)
		(end 124.460762 -13.63726)
		(stroke
			(width 0.0762)
			(type default)
		)
		(layer "In2.Cu")
	)
	(gr_line
		(start 124.923042 -13.63726)
		(end 125.044962 -13.51534)
		(stroke
			(width 0.0762)
			(type default)
		)
		(layer "In2.Cu")
	)
	(gr_line
		(start 125.044962 -13.51534)
		(end 125.502162 -13.51534)
		(stroke
			(width 0.0762)
			(type default)
		)
		(layer "In2.Cu")
	)
	(gr_line
		(start 125.202442 -13.9192)
		(end 125.344682 -13.9192)
		(stroke
			(width 0.0762)
			(type default)
		)
		(layer "In2.Cu")
	)
	(gr_line
		(start 125.502162 -13.51534)
		(end 125.624082 -13.63726)
		(stroke
			(width 0.0762)
			(type default)
		)
		(layer "In2.Cu")
	)
	(gr_line
		(start 126.657354 -28.64612)
		(end 126.779274 -28.76804)
		(stroke
			(width 0.0762)
			(type default)
		)
		(layer "In2.Cu")
	)
	(gr_line
		(start 126.779274 -28.76804)
		(end 127.236474 -28.76804)
		(stroke
			(width 0.0762)
			(type default)
		)
		(layer "In2.Cu")
	)
	(gr_line
		(start 126.936754 -28.36418)
		(end 127.078994 -28.36418)
		(stroke
			(width 0.0762)
			(type default)
		)
		(layer "In2.Cu")
	)
	(gr_line
		(start 127.236474 -28.76804)
		(end 127.358394 -28.64612)
		(stroke
			(width 0.0762)
			(type default)
		)
		(layer "In2.Cu")
	)
	(gr_line
		(start 127.820674 -28.64612)
		(end 127.942594 -28.76804)
		(stroke
			(width 0.0762)
			(type default)
		)
		(layer "In2.Cu")
	)
	(gr_line
		(start 127.942594 -28.76804)
		(end 128.399794 -28.76804)
		(stroke
			(width 0.0762)
			(type default)
		)
		(layer "In2.Cu")
	)
	(gr_line
		(start 128.100074 -28.36418)
		(end 128.242314 -28.36418)
		(stroke
			(width 0.0762)
			(type default)
		)
		(layer "In2.Cu")
	)
	(gr_line
		(start 128.399794 -28.76804)
		(end 128.521714 -28.64612)
		(stroke
			(width 0.0762)
			(type default)
		)
		(layer "In2.Cu")
	)
	(gr_line
		(start 128.983994 -28.64612)
		(end 129.105914 -28.76804)
		(stroke
			(width 0.0762)
			(type default)
		)
		(layer "In2.Cu")
	)
	(gr_line
		(start 129.105914 -28.76804)
		(end 129.563114 -28.76804)
		(stroke
			(width 0.0762)
			(type default)
		)
		(layer "In2.Cu")
	)
	(gr_line
		(start 129.263394 -28.36418)
		(end 129.405634 -28.36418)
		(stroke
			(width 0.0762)
			(type default)
		)
		(layer "In2.Cu")
	)
	(gr_line
		(start 129.563114 -28.76804)
		(end 129.685034 -28.64612)
		(stroke
			(width 0.0762)
			(type default)
		)
		(layer "In2.Cu")
	)
	(gr_line
		(start 132.74294 -59.17946)
		(end 132.86486 -59.05754)
		(stroke
			(width 0.0762)
			(type default)
		)
		(layer "In2.Cu")
	)
	(gr_line
		(start 132.86486 -59.05754)
		(end 133.32206 -59.05754)
		(stroke
			(width 0.0762)
			(type default)
		)
		(layer "In2.Cu")
	)
	(gr_line
		(start 133.02234 -59.4614)
		(end 133.16458 -59.4614)
		(stroke
			(width 0.0762)
			(type default)
		)
		(layer "In2.Cu")
	)
	(gr_line
		(start 133.32206 -59.05754)
		(end 133.44398 -59.17946)
		(stroke
			(width 0.0762)
			(type default)
		)
		(layer "In2.Cu")
	)
	(gr_line
		(start 133.90626 -59.17946)
		(end 134.02818 -59.05754)
		(stroke
			(width 0.0762)
			(type default)
		)
		(layer "In2.Cu")
	)
	(gr_line
		(start 134.02818 -59.05754)
		(end 134.48538 -59.05754)
		(stroke
			(width 0.0762)
			(type default)
		)
		(layer "In2.Cu")
	)
	(gr_line
		(start 134.18566 -59.4614)
		(end 134.3279 -59.4614)
		(stroke
			(width 0.0762)
			(type default)
		)
		(layer "In2.Cu")
	)
	(gr_line
		(start 134.48538 -59.05754)
		(end 134.6073 -59.17946)
		(stroke
			(width 0.0762)
			(type default)
		)
		(layer "In2.Cu")
	)
	(gr_line
		(start 135.4328 -5.818378)
		(end 135.650732 -6.03631)
		(stroke
			(width 0.0762)
			(type default)
		)
		(layer "In2.Cu")
	)
	(gr_line
		(start 136.049258 -6.03631)
		(end 136.26719 -5.818378)
		(stroke
			(width 0.0762)
			(type default)
		)
		(layer "In2.Cu")
	)
	(gr_line
		(start 136.374378 -36.456874)
		(end 136.496298 -36.334954)
		(stroke
			(width 0.0762)
			(type default)
		)
		(layer "In2.Cu")
	)
	(gr_line
		(start 136.496298 -36.334954)
		(end 136.953498 -36.334954)
		(stroke
			(width 0.0762)
			(type default)
		)
		(layer "In2.Cu")
	)
	(gr_line
		(start 136.653778 -36.738814)
		(end 136.796018 -36.738814)
		(stroke
			(width 0.0762)
			(type default)
		)
		(layer "In2.Cu")
	)
	(gr_line
		(start 136.953498 -36.334954)
		(end 137.075418 -36.456874)
		(stroke
			(width 0.0762)
			(type default)
		)
		(layer "In2.Cu")
	)
	(gr_line
		(start 137.537698 -36.456874)
		(end 137.659618 -36.334954)
		(stroke
			(width 0.0762)
			(type default)
		)
		(layer "In2.Cu")
	)
	(gr_line
		(start 137.659618 -36.334954)
		(end 138.116818 -36.334954)
		(stroke
			(width 0.0762)
			(type default)
		)
		(layer "In2.Cu")
	)
	(gr_line
		(start 137.817098 -36.738814)
		(end 137.959338 -36.738814)
		(stroke
			(width 0.0762)
			(type default)
		)
		(layer "In2.Cu")
	)
	(gr_line
		(start 138.116818 -36.334954)
		(end 138.238738 -36.456874)
		(stroke
			(width 0.0762)
			(type default)
		)
		(layer "In2.Cu")
	)
	(gr_line
		(start 138.701018 -36.456874)
		(end 138.822938 -36.334954)
		(stroke
			(width 0.0762)
			(type default)
		)
		(layer "In2.Cu")
	)
	(gr_line
		(start 138.822938 -36.334954)
		(end 139.280138 -36.334954)
		(stroke
			(width 0.0762)
			(type default)
		)
		(layer "In2.Cu")
	)
	(gr_line
		(start 138.980418 -36.738814)
		(end 139.122658 -36.738814)
		(stroke
			(width 0.0762)
			(type default)
		)
		(layer "In2.Cu")
	)
	(gr_line
		(start 139.280138 -36.334954)
		(end 139.402058 -36.456874)
		(stroke
			(width 0.0762)
			(type default)
		)
		(layer "In2.Cu")
	)
	(gr_line
		(start 139.505182 -60.00369)
		(end 139.605766 -60.104274)
		(stroke
			(width 0.0762)
			(type default)
		)
		(layer "In2.Cu")
	)
	(gr_line
		(start 139.50696 -59.606688)
		(end 139.679426 -59.606688)
		(stroke
			(width 0.0762)
			(type default)
		)
		(layer "In2.Cu")
	)
	(gr_line
		(start 139.679426 -59.606688)
		(end 140.002768 -59.93003)
		(stroke
			(width 0.0762)
			(type default)
		)
		(layer "In2.Cu")
	)
	(gr_line
		(start 140.002768 -59.93003)
		(end 140.002768 -60.102496)
		(stroke
			(width 0.0762)
			(type default)
		)
		(layer "In2.Cu")
	)
	(gr_line
		(start 140.327888 -60.826396)
		(end 140.428218 -60.926726)
		(stroke
			(width 0.0762)
			(type default)
		)
		(layer "In2.Cu")
	)
	(gr_line
		(start 140.329666 -60.429394)
		(end 140.502132 -60.429394)
		(stroke
			(width 0.0762)
			(type default)
		)
		(layer "In2.Cu")
	)
	(gr_line
		(start 140.502132 -60.429394)
		(end 140.82522 -60.752482)
		(stroke
			(width 0.0762)
			(type default)
		)
		(layer "In2.Cu")
	)
	(gr_line
		(start 140.82522 -60.752482)
		(end 140.82522 -60.924948)
		(stroke
			(width 0.0762)
			(type default)
		)
		(layer "In2.Cu")
	)
	(gr_line
		(start 141.132814 -66.672206)
		(end 141.350746 -66.454274)
		(stroke
			(width 0.0762)
			(type default)
		)
		(layer "In2.Cu")
	)
	(gr_line
		(start 141.749272 -66.454274)
		(end 141.967204 -66.672206)
		(stroke
			(width 0.0762)
			(type default)
		)
		(layer "In2.Cu")
	)
	(gr_line
		(start 145.926048 -51.866546)
		(end 145.98142 -51.811174)
		(stroke
			(width 0.0762)
			(type default)
		)
		(layer "In2.Cu")
	)
	(gr_line
		(start 146.357594 -52.298092)
		(end 146.412966 -52.242466)
		(stroke
			(width 0.0762)
			(type default)
		)
		(layer "In2.Cu")
	)
	(gr_line
		(start 146.470878 -50.926238)
		(end 146.52625 -50.870866)
		(stroke
			(width 0.0762)
			(type default)
		)
		(layer "In2.Cu")
	)
	(gr_line
		(start 147.297648 -51.753262)
		(end 147.35302 -51.697636)
		(stroke
			(width 0.0762)
			(type default)
		)
		(layer "In2.Cu")
	)
	(gr_line
		(start 148.197316 -55.60314)
		(end 148.319236 -55.72506)
		(stroke
			(width 0.0762)
			(type default)
		)
		(layer "In2.Cu")
	)
	(gr_line
		(start 148.319236 -55.72506)
		(end 148.776436 -55.72506)
		(stroke
			(width 0.0762)
			(type default)
		)
		(layer "In2.Cu")
	)
	(gr_line
		(start 148.476716 -55.3212)
		(end 148.618956 -55.3212)
		(stroke
			(width 0.0762)
			(type default)
		)
		(layer "In2.Cu")
	)
	(gr_line
		(start 148.776436 -55.72506)
		(end 148.898356 -55.60314)
		(stroke
			(width 0.0762)
			(type default)
		)
		(layer "In2.Cu")
	)
	(gr_line
		(start 149.360636 -55.60314)
		(end 149.482556 -55.72506)
		(stroke
			(width 0.0762)
			(type default)
		)
		(layer "In2.Cu")
	)
	(gr_line
		(start 149.482556 -55.72506)
		(end 149.939756 -55.72506)
		(stroke
			(width 0.0762)
			(type default)
		)
		(layer "In2.Cu")
	)
	(gr_line
		(start 149.640036 -55.3212)
		(end 149.782276 -55.3212)
		(stroke
			(width 0.0762)
			(type default)
		)
		(layer "In2.Cu")
	)
	(gr_line
		(start 149.939756 -55.72506)
		(end 150.061676 -55.60314)
		(stroke
			(width 0.0762)
			(type default)
		)
		(layer "In2.Cu")
	)
	(gr_line
		(start 150.523956 -55.60314)
		(end 150.645876 -55.72506)
		(stroke
			(width 0.0762)
			(type default)
		)
		(layer "In2.Cu")
	)
	(gr_line
		(start 150.645876 -55.72506)
		(end 151.103076 -55.72506)
		(stroke
			(width 0.0762)
			(type default)
		)
		(layer "In2.Cu")
	)
	(gr_line
		(start 150.803356 -55.3212)
		(end 150.945596 -55.3212)
		(stroke
			(width 0.0762)
			(type default)
		)
		(layer "In2.Cu")
	)
	(gr_line
		(start 151.103076 -55.72506)
		(end 151.224996 -55.60314)
		(stroke
			(width 0.0762)
			(type default)
		)
		(layer "In2.Cu")
	)
	(gr_line
		(start 151.7142 -17.176496)
		(end 151.7142 -17.318736)
		(stroke
			(width 0.0762)
			(type default)
		)
		(layer "In2.Cu")
	)
	(gr_line
		(start 151.7142 -15.587472)
		(end 151.7142 -15.729712)
		(stroke
			(width 0.0762)
			(type default)
		)
		(layer "In2.Cu")
	)
	(gr_line
		(start 151.7142 -13.918184)
		(end 151.7142 -14.060424)
		(stroke
			(width 0.0762)
			(type default)
		)
		(layer "In2.Cu")
	)
	(gr_line
		(start 151.7142 -12.70762)
		(end 151.7142 -12.84986)
		(stroke
			(width 0.0762)
			(type default)
		)
		(layer "In2.Cu")
	)
	(gr_line
		(start 151.7142 -11.5443)
		(end 151.7142 -11.68654)
		(stroke
			(width 0.0762)
			(type default)
		)
		(layer "In2.Cu")
	)
	(gr_line
		(start 151.7142 -10.38098)
		(end 151.7142 -10.52322)
		(stroke
			(width 0.0762)
			(type default)
		)
		(layer "In2.Cu")
	)
	(gr_line
		(start 151.99614 -17.598136)
		(end 152.11806 -17.476216)
		(stroke
			(width 0.0762)
			(type default)
		)
		(layer "In2.Cu")
	)
	(gr_line
		(start 151.99614 -16.897096)
		(end 152.11806 -17.019016)
		(stroke
			(width 0.0762)
			(type default)
		)
		(layer "In2.Cu")
	)
	(gr_line
		(start 151.99614 -16.009112)
		(end 152.11806 -15.887192)
		(stroke
			(width 0.0762)
			(type default)
		)
		(layer "In2.Cu")
	)
	(gr_line
		(start 151.99614 -15.308072)
		(end 152.11806 -15.429992)
		(stroke
			(width 0.0762)
			(type default)
		)
		(layer "In2.Cu")
	)
	(gr_line
		(start 151.99614 -14.339824)
		(end 152.11806 -14.217904)
		(stroke
			(width 0.0762)
			(type default)
		)
		(layer "In2.Cu")
	)
	(gr_line
		(start 151.99614 -13.638784)
		(end 152.11806 -13.760704)
		(stroke
			(width 0.0762)
			(type default)
		)
		(layer "In2.Cu")
	)
	(gr_line
		(start 151.99614 -13.12926)
		(end 152.11806 -13.00734)
		(stroke
			(width 0.0762)
			(type default)
		)
		(layer "In2.Cu")
	)
	(gr_line
		(start 151.99614 -12.42822)
		(end 152.11806 -12.55014)
		(stroke
			(width 0.0762)
			(type default)
		)
		(layer "In2.Cu")
	)
	(gr_line
		(start 151.99614 -11.96594)
		(end 152.11806 -11.84402)
		(stroke
			(width 0.0762)
			(type default)
		)
		(layer "In2.Cu")
	)
	(gr_line
		(start 151.99614 -11.2649)
		(end 152.11806 -11.38682)
		(stroke
			(width 0.0762)
			(type default)
		)
		(layer "In2.Cu")
	)
	(gr_line
		(start 151.99614 -10.80262)
		(end 152.11806 -10.6807)
		(stroke
			(width 0.0762)
			(type default)
		)
		(layer "In2.Cu")
	)
	(gr_line
		(start 151.99614 -10.10158)
		(end 152.11806 -10.2235)
		(stroke
			(width 0.0762)
			(type default)
		)
		(layer "In2.Cu")
	)
	(gr_line
		(start 152.11806 -17.019016)
		(end 152.11806 -17.476216)
		(stroke
			(width 0.0762)
			(type default)
		)
		(layer "In2.Cu")
	)
	(gr_line
		(start 152.11806 -15.429992)
		(end 152.11806 -15.887192)
		(stroke
			(width 0.0762)
			(type default)
		)
		(layer "In2.Cu")
	)
	(gr_line
		(start 152.11806 -13.760704)
		(end 152.11806 -14.217904)
		(stroke
			(width 0.0762)
			(type default)
		)
		(layer "In2.Cu")
	)
	(gr_line
		(start 152.11806 -12.55014)
		(end 152.11806 -13.00734)
		(stroke
			(width 0.0762)
			(type default)
		)
		(layer "In2.Cu")
	)
	(gr_line
		(start 152.11806 -11.38682)
		(end 152.11806 -11.84402)
		(stroke
			(width 0.0762)
			(type default)
		)
		(layer "In2.Cu")
	)
	(gr_line
		(start 152.11806 -10.2235)
		(end 152.11806 -10.6807)
		(stroke
			(width 0.0762)
			(type default)
		)
		(layer "In2.Cu")
	)
	(gr_line
		(start 152.2349 -7.497318)
		(end 152.335484 -7.396734)
		(stroke
			(width 0.0762)
			(type default)
		)
		(layer "In2.Cu")
	)
	(gr_line
		(start 152.236678 -7.89432)
		(end 152.409144 -7.89432)
		(stroke
			(width 0.0762)
			(type default)
		)
		(layer "In2.Cu")
	)
	(gr_line
		(start 152.409144 -7.89432)
		(end 152.732486 -7.570978)
		(stroke
			(width 0.0762)
			(type default)
		)
		(layer "In2.Cu")
	)
	(gr_line
		(start 152.732486 -7.398512)
		(end 152.732486 -7.570978)
		(stroke
			(width 0.0762)
			(type default)
		)
		(layer "In2.Cu")
	)
	(gr_line
		(start 152.832816 -5.818378)
		(end 153.050748 -6.03631)
		(stroke
			(width 0.0762)
			(type default)
		)
		(layer "In2.Cu")
	)
	(gr_line
		(start 153.449274 -6.03631)
		(end 153.667206 -5.818378)
		(stroke
			(width 0.0762)
			(type default)
		)
		(layer "In2.Cu")
	)
	(gr_line
		(start 160.620456 -55.845964)
		(end 160.943798 -56.169306)
		(stroke
			(width 0.0762)
			(type default)
		)
		(layer "In2.Cu")
	)
	(gr_line
		(start 160.620456 -55.673498)
		(end 160.620456 -55.845964)
		(stroke
			(width 0.0762)
			(type default)
		)
		(layer "In2.Cu")
	)
	(gr_line
		(start 160.943798 -56.169306)
		(end 161.116264 -56.169306)
		(stroke
			(width 0.0762)
			(type default)
		)
		(layer "In2.Cu")
	)
	(gr_line
		(start 161.017458 -55.67172)
		(end 161.118042 -55.772304)
		(stroke
			(width 0.0762)
			(type default)
		)
		(layer "In2.Cu")
	)
	(gr_line
		(start 161.442908 -56.668416)
		(end 161.76625 -56.991758)
		(stroke
			(width 0.0762)
			(type default)
		)
		(layer "In2.Cu")
	)
	(gr_line
		(start 161.442908 -56.49595)
		(end 161.442908 -56.668416)
		(stroke
			(width 0.0762)
			(type default)
		)
		(layer "In2.Cu")
	)
	(gr_line
		(start 161.76625 -56.991758)
		(end 161.938716 -56.991758)
		(stroke
			(width 0.0762)
			(type default)
		)
		(layer "In2.Cu")
	)
	(gr_line
		(start 161.83991 -56.494172)
		(end 161.940494 -56.594756)
		(stroke
			(width 0.0762)
			(type default)
		)
		(layer "In2.Cu")
	)
	(gr_line
		(start 162.265614 -57.491122)
		(end 162.588956 -57.814464)
		(stroke
			(width 0.0762)
			(type default)
		)
		(layer "In2.Cu")
	)
	(gr_line
		(start 162.265614 -57.318656)
		(end 162.265614 -57.491122)
		(stroke
			(width 0.0762)
			(type default)
		)
		(layer "In2.Cu")
	)
	(gr_line
		(start 162.37712 -44.77512)
		(end 162.477704 -44.875704)
		(stroke
			(width 0.0762)
			(type default)
		)
		(layer "In2.Cu")
	)
	(gr_line
		(start 162.378898 -44.378118)
		(end 162.551364 -44.378118)
		(stroke
			(width 0.0762)
			(type default)
		)
		(layer "In2.Cu")
	)
	(gr_line
		(start 162.551364 -44.378118)
		(end 162.874706 -44.70146)
		(stroke
			(width 0.0762)
			(type default)
		)
		(layer "In2.Cu")
	)
	(gr_line
		(start 162.588956 -57.814464)
		(end 162.761422 -57.814464)
		(stroke
			(width 0.0762)
			(type default)
		)
		(layer "In2.Cu")
	)
	(gr_line
		(start 162.662616 -57.316878)
		(end 162.7632 -57.417462)
		(stroke
			(width 0.0762)
			(type default)
		)
		(layer "In2.Cu")
	)
	(gr_line
		(start 162.874706 -44.70146)
		(end 162.874706 -44.873926)
		(stroke
			(width 0.0762)
			(type default)
		)
		(layer "In2.Cu")
	)
	(gr_line
		(start 163.199572 -45.597572)
		(end 163.300156 -45.698156)
		(stroke
			(width 0.0762)
			(type default)
		)
		(layer "In2.Cu")
	)
	(gr_line
		(start 163.20135 -45.20057)
		(end 163.373816 -45.20057)
		(stroke
			(width 0.0762)
			(type default)
		)
		(layer "In2.Cu")
	)
	(gr_line
		(start 163.373816 -45.20057)
		(end 163.697158 -45.523912)
		(stroke
			(width 0.0762)
			(type default)
		)
		(layer "In2.Cu")
	)
	(gr_line
		(start 163.673536 -58.899044)
		(end 163.996878 -59.222386)
		(stroke
			(width 0.0762)
			(type default)
		)
		(layer "In2.Cu")
	)
	(gr_line
		(start 163.673536 -58.726578)
		(end 163.673536 -58.899044)
		(stroke
			(width 0.0762)
			(type default)
		)
		(layer "In2.Cu")
	)
	(gr_line
		(start 163.697158 -45.523912)
		(end 163.697158 -45.696378)
		(stroke
			(width 0.0762)
			(type default)
		)
		(layer "In2.Cu")
	)
	(gr_line
		(start 163.996878 -59.222386)
		(end 164.169344 -59.222386)
		(stroke
			(width 0.0762)
			(type default)
		)
		(layer "In2.Cu")
	)
	(gr_line
		(start 164.022278 -46.420278)
		(end 164.122862 -46.520862)
		(stroke
			(width 0.0762)
			(type default)
		)
		(layer "In2.Cu")
	)
	(gr_line
		(start 164.024056 -46.023276)
		(end 164.196522 -46.023276)
		(stroke
			(width 0.0762)
			(type default)
		)
		(layer "In2.Cu")
	)
	(gr_line
		(start 164.070538 -58.7248)
		(end 164.171122 -58.825384)
		(stroke
			(width 0.0762)
			(type default)
		)
		(layer "In2.Cu")
	)
	(gr_line
		(start 164.196522 -46.023276)
		(end 164.519864 -46.346618)
		(stroke
			(width 0.0762)
			(type default)
		)
		(layer "In2.Cu")
	)
	(gr_line
		(start 164.496242 -59.72175)
		(end 164.819584 -60.045092)
		(stroke
			(width 0.0762)
			(type default)
		)
		(layer "In2.Cu")
	)
	(gr_line
		(start 164.496242 -59.549284)
		(end 164.496242 -59.72175)
		(stroke
			(width 0.0762)
			(type default)
		)
		(layer "In2.Cu")
	)
	(gr_line
		(start 164.519864 -46.346618)
		(end 164.519864 -46.519084)
		(stroke
			(width 0.0762)
			(type default)
		)
		(layer "In2.Cu")
	)
	(gr_line
		(start 164.819584 -60.045092)
		(end 164.99205 -60.045092)
		(stroke
			(width 0.0762)
			(type default)
		)
		(layer "In2.Cu")
	)
	(gr_line
		(start 164.832792 -66.672206)
		(end 165.050724 -66.454274)
		(stroke
			(width 0.0762)
			(type default)
		)
		(layer "In2.Cu")
	)
	(gr_line
		(start 164.893244 -59.547506)
		(end 164.993828 -59.64809)
		(stroke
			(width 0.0762)
			(type default)
		)
		(layer "In2.Cu")
	)
	(gr_line
		(start 165.318694 -60.544202)
		(end 165.642036 -60.867544)
		(stroke
			(width 0.0762)
			(type default)
		)
		(layer "In2.Cu")
	)
	(gr_line
		(start 165.318694 -60.371736)
		(end 165.318694 -60.544202)
		(stroke
			(width 0.0762)
			(type default)
		)
		(layer "In2.Cu")
	)
	(gr_line
		(start 165.44925 -66.454274)
		(end 165.667182 -66.672206)
		(stroke
			(width 0.0762)
			(type default)
		)
		(layer "In2.Cu")
	)
	(gr_line
		(start 165.642036 -60.867544)
		(end 165.814502 -60.867544)
		(stroke
			(width 0.0762)
			(type default)
		)
		(layer "In2.Cu")
	)
	(gr_line
		(start 165.715696 -60.369958)
		(end 165.81628 -60.470542)
		(stroke
			(width 0.0762)
			(type default)
		)
		(layer "In2.Cu")
	)
	(gr_line
		(start 168.675558 -54.79034)
		(end 168.776142 -54.890924)
		(stroke
			(width 0.0762)
			(type default)
		)
		(layer "In2.Cu")
	)
	(gr_line
		(start 168.677336 -54.393338)
		(end 168.849802 -54.393338)
		(stroke
			(width 0.0762)
			(type default)
		)
		(layer "In2.Cu")
	)
	(gr_line
		(start 168.849802 -54.393338)
		(end 169.173144 -54.71668)
		(stroke
			(width 0.0762)
			(type default)
		)
		(layer "In2.Cu")
	)
	(gr_line
		(start 169.173144 -54.71668)
		(end 169.173144 -54.889146)
		(stroke
			(width 0.0762)
			(type default)
		)
		(layer "In2.Cu")
	)
	(gr_line
		(start 169.498264 -55.613046)
		(end 169.598848 -55.71363)
		(stroke
			(width 0.0762)
			(type default)
		)
		(layer "In2.Cu")
	)
	(gr_line
		(start 169.500042 -55.216044)
		(end 169.672508 -55.216044)
		(stroke
			(width 0.0762)
			(type default)
		)
		(layer "In2.Cu")
	)
	(gr_line
		(start 169.672508 -55.216044)
		(end 169.99585 -55.539386)
		(stroke
			(width 0.0762)
			(type default)
		)
		(layer "In2.Cu")
	)
	(gr_line
		(start 169.99585 -55.539386)
		(end 169.99585 -55.711852)
		(stroke
			(width 0.0762)
			(type default)
		)
		(layer "In2.Cu")
	)
	(gr_line
		(start 170.320716 -56.435498)
		(end 170.4213 -56.536082)
		(stroke
			(width 0.0762)
			(type default)
		)
		(layer "In2.Cu")
	)
	(gr_line
		(start 170.322494 -56.038496)
		(end 170.49496 -56.038496)
		(stroke
			(width 0.0762)
			(type default)
		)
		(layer "In2.Cu")
	)
	(gr_line
		(start 170.49496 -56.038496)
		(end 170.818302 -56.361838)
		(stroke
			(width 0.0762)
			(type default)
		)
		(layer "In2.Cu")
	)
	(gr_line
		(start 170.818302 -56.361838)
		(end 170.818302 -56.534304)
		(stroke
			(width 0.0762)
			(type default)
		)
		(layer "In2.Cu")
	)
	(gr_line
		(start 171.732702 -66.672206)
		(end 171.950634 -66.454274)
		(stroke
			(width 0.0762)
			(type default)
		)
		(layer "In2.Cu")
	)
	(gr_line
		(start 172.34916 -66.454274)
		(end 172.567092 -66.672206)
		(stroke
			(width 0.0762)
			(type default)
		)
		(layer "In2.Cu")
	)
	(gr_line
		(start 176.537366 -5.804662)
		(end 176.541684 -5.804662)
		(stroke
			(width 0.0762)
			(type default)
		)
		(layer "In2.Cu")
	)
	(gr_line
		(start 176.541684 -5.804662)
		(end 176.749202 -6.01218)
		(stroke
			(width 0.0762)
			(type default)
		)
		(layer "In2.Cu")
	)
	(gr_line
		(start 176.784 -6.326378)
		(end 176.784 -6.337554)
		(stroke
			(width 0.0762)
			(type default)
		)
		(layer "In2.Cu")
	)
	(gr_line
		(start 176.911 -6.605778)
		(end 176.911 -6.616954)
		(stroke
			(width 0.0762)
			(type default)
		)
		(layer "In2.Cu")
	)
	(gr_line
		(start 177.147982 -6.01218)
		(end 177.354992 -5.80517)
		(stroke
			(width 0.0762)
			(type default)
		)
		(layer "In2.Cu")
	)
	(gr_line
		(start 177.354992 -5.80517)
		(end 177.362358 -5.80517)
		(stroke
			(width 0.0762)
			(type default)
		)
		(layer "In2.Cu")
	)
	(gr_line
		(start 186.132724 -5.996178)
		(end 186.350656 -6.21411)
		(stroke
			(width 0.0762)
			(type default)
		)
		(layer "In2.Cu")
	)
	(gr_line
		(start 186.2328 -6.885178)
		(end 186.40806 -7.060438)
		(stroke
			(width 0.0762)
			(type default)
		)
		(layer "In2.Cu")
	)
	(gr_line
		(start 186.2328 -6.656578)
		(end 186.2328 -6.885178)
		(stroke
			(width 0.0762)
			(type default)
		)
		(layer "In2.Cu")
	)
	(gr_line
		(start 186.2328 -6.656578)
		(end 186.40806 -6.481318)
		(stroke
			(width 0.0762)
			(type default)
		)
		(layer "In2.Cu")
	)
	(gr_line
		(start 186.69 -6.760718)
		(end 186.69 -6.781038)
		(stroke
			(width 0.0762)
			(type default)
		)
		(layer "In2.Cu")
	)
	(gr_line
		(start 186.749182 -6.21411)
		(end 186.967114 -5.996178)
		(stroke
			(width 0.0762)
			(type default)
		)
		(layer "In2.Cu")
	)
	(gr_arc
		(start 1.54686 -67.178682)
		(mid 1.9304 -67.562222)
		(end 2.31394 -67.178682)
		(stroke
			(width 0.2)
			(type default)
		)
		(layer "In3.Cu")
	)
	(gr_line
		(start 1.54686 -66.221102)
		(end 1.54686 -67.178682)
		(stroke
			(width 0.2)
			(type default)
		)
		(layer "In3.Cu")
	)
	(gr_arc
		(start 1.54686 -64.178434)
		(mid 1.930273 -64.562228)
		(end 2.31394 -64.178688)
		(stroke
			(width 0.2)
			(type default)
		)
		(layer "In3.Cu")
	)
	(gr_line
		(start 1.54686 -63.221108)
		(end 1.54686 -64.178434)
		(stroke
			(width 0.2)
			(type default)
		)
		(layer "In3.Cu")
	)
	(gr_arc
		(start 1.54686 -61.178694)
		(mid 1.9304 -61.562234)
		(end 2.31394 -61.178694)
		(stroke
			(width 0.2)
			(type default)
		)
		(layer "In3.Cu")
	)
	(gr_line
		(start 1.54686 -60.221114)
		(end 1.54686 -61.178694)
		(stroke
			(width 0.2)
			(type default)
		)
		(layer "In3.Cu")
	)
	(gr_line
		(start 2.31394 -67.178682)
		(end 2.31394 -66.221356)
		(stroke
			(width 0.2)
			(type default)
		)
		(layer "In3.Cu")
	)
	(gr_arc
		(start 2.31394 -66.221356)
		(mid 1.930527 -65.837562)
		(end 1.54686 -66.221102)
		(stroke
			(width 0.2)
			(type default)
		)
		(layer "In3.Cu")
	)
	(gr_line
		(start 2.31394 -64.178688)
		(end 2.31394 -63.221108)
		(stroke
			(width 0.2)
			(type default)
		)
		(layer "In3.Cu")
	)
	(gr_arc
		(start 2.31394 -63.221108)
		(mid 1.9304 -62.837568)
		(end 1.54686 -63.221108)
		(stroke
			(width 0.2)
			(type default)
		)
		(layer "In3.Cu")
	)
	(gr_line
		(start 2.31394 -61.178694)
		(end 2.31394 -60.221368)
		(stroke
			(width 0.2)
			(type default)
		)
		(layer "In3.Cu")
	)
	(gr_arc
		(start 2.31394 -60.221368)
		(mid 1.930527 -59.837574)
		(end 1.54686 -60.221114)
		(stroke
			(width 0.2)
			(type default)
		)
		(layer "In3.Cu")
	)
	(gr_arc
		(start 2.94132 -59.664092)
		(mid 3.324733 -60.047886)
		(end 3.7084 -59.664346)
		(stroke
			(width 0.2)
			(type default)
		)
		(layer "In3.Cu")
	)
	(gr_line
		(start 2.94132 -58.706766)
		(end 2.94132 -59.664092)
		(stroke
			(width 0.2)
			(type default)
		)
		(layer "In3.Cu")
	)
	(gr_arc
		(start 3.06832 -65.664334)
		(mid 3.45186 -66.047874)
		(end 3.8354 -65.664334)
		(stroke
			(width 0.2)
			(type default)
		)
		(layer "In3.Cu")
	)
	(gr_line
		(start 3.06832 -64.706754)
		(end 3.06832 -65.664334)
		(stroke
			(width 0.2)
			(type default)
		)
		(layer "In3.Cu")
	)
	(gr_arc
		(start 3.06832 -62.66434)
		(mid 3.45186 -63.04788)
		(end 3.8354 -62.66434)
		(stroke
			(width 0.2)
			(type default)
		)
		(layer "In3.Cu")
	)
	(gr_line
		(start 3.06832 -61.70676)
		(end 3.06832 -62.66434)
		(stroke
			(width 0.2)
			(type default)
		)
		(layer "In3.Cu")
	)
	(gr_line
		(start 3.7084 -59.664346)
		(end 3.7084 -58.706766)
		(stroke
			(width 0.2)
			(type default)
		)
		(layer "In3.Cu")
	)
	(gr_arc
		(start 3.7084 -58.706766)
		(mid 3.32486 -58.323226)
		(end 2.94132 -58.706766)
		(stroke
			(width 0.2)
			(type default)
		)
		(layer "In3.Cu")
	)
	(gr_line
		(start 3.8354 -65.664334)
		(end 3.8354 -64.707008)
		(stroke
			(width 0.2)
			(type default)
		)
		(layer "In3.Cu")
	)
	(gr_arc
		(start 3.8354 -64.707008)
		(mid 3.451987 -64.323214)
		(end 3.06832 -64.706754)
		(stroke
			(width 0.2)
			(type default)
		)
		(layer "In3.Cu")
	)
	(gr_line
		(start 3.8354 -62.66434)
		(end 3.8354 -61.707014)
		(stroke
			(width 0.2)
			(type default)
		)
		(layer "In3.Cu")
	)
	(gr_arc
		(start 3.8354 -61.707014)
		(mid 3.451987 -61.32322)
		(end 3.06832 -61.70676)
		(stroke
			(width 0.2)
			(type default)
		)
		(layer "In3.Cu")
	)
	(gr_arc
		(start 7.747 -51.6128)
		(mid 8.128 -51.9938)
		(end 8.509 -51.6128)
		(stroke
			(width 0.2)
			(type default)
		)
		(layer "In3.Cu")
	)
	(gr_line
		(start 7.747 -50.6222)
		(end 7.747 -51.6128)
		(stroke
			(width 0.2)
			(type default)
		)
		(layer "In3.Cu")
	)
	(gr_arc
		(start 8.4582 -53.8988)
		(mid 8.8392 -54.2798)
		(end 9.2202 -53.8988)
		(stroke
			(width 0.2)
			(type default)
		)
		(layer "In3.Cu")
	)
	(gr_line
		(start 8.4582 -52.9082)
		(end 8.4582 -53.8988)
		(stroke
			(width 0.2)
			(type default)
		)
		(layer "In3.Cu")
	)
	(gr_line
		(start 8.509 -51.6128)
		(end 8.509 -50.622454)
		(stroke
			(width 0.2)
			(type default)
		)
		(layer "In3.Cu")
	)
	(gr_arc
		(start 8.509 -50.622454)
		(mid 8.128127 -50.2412)
		(end 7.747 -50.6222)
		(stroke
			(width 0.2)
			(type default)
		)
		(layer "In3.Cu")
	)
	(gr_line
		(start 9.2202 -53.8988)
		(end 9.2202 -52.908454)
		(stroke
			(width 0.2)
			(type default)
		)
		(layer "In3.Cu")
	)
	(gr_arc
		(start 9.2202 -52.908454)
		(mid 8.839327 -52.5272)
		(end 8.4582 -52.9082)
		(stroke
			(width 0.2)
			(type default)
		)
		(layer "In3.Cu")
	)
	(gr_line
		(start 9.240774 -62.748922)
		(end 9.266174 -63.637668)
		(stroke
			(width 0.2)
			(type default)
		)
		(layer "In3.Cu")
	)
	(gr_line
		(start 9.240774 -59.192922)
		(end 9.266174 -60.081668)
		(stroke
			(width 0.2)
			(type default)
		)
		(layer "In3.Cu")
	)
	(gr_arc
		(start 9.24306 -65.405)
		(mid 9.6266 -65.78854)
		(end 10.01014 -65.405)
		(stroke
			(width 0.2)
			(type default)
		)
		(layer "In3.Cu")
	)
	(gr_line
		(start 9.24306 -64.516)
		(end 9.24306 -65.405)
		(stroke
			(width 0.2)
			(type default)
		)
		(layer "In3.Cu")
	)
	(gr_arc
		(start 9.24306 -61.849)
		(mid 9.6266 -62.23254)
		(end 10.01014 -61.849)
		(stroke
			(width 0.2)
			(type default)
		)
		(layer "In3.Cu")
	)
	(gr_line
		(start 9.24306 -60.96)
		(end 9.24306 -61.849)
		(stroke
			(width 0.2)
			(type default)
		)
		(layer "In3.Cu")
	)
	(gr_arc
		(start 9.24306 -58.293)
		(mid 9.6266 -58.67654)
		(end 10.01014 -58.293)
		(stroke
			(width 0.2)
			(type default)
		)
		(layer "In3.Cu")
	)
	(gr_line
		(start 9.24306 -57.404)
		(end 9.24306 -58.293)
		(stroke
			(width 0.2)
			(type default)
		)
		(layer "In3.Cu")
	)
	(gr_arc
		(start 9.24306 -56.515)
		(mid 9.6266 -56.89854)
		(end 10.01014 -56.515)
		(stroke
			(width 0.2)
			(type default)
		)
		(layer "In3.Cu")
	)
	(gr_line
		(start 9.24306 -55.626)
		(end 9.24306 -56.515)
		(stroke
			(width 0.2)
			(type default)
		)
		(layer "In3.Cu")
	)
	(gr_line
		(start 9.243314 -62.748922)
		(end 9.240774 -62.748922)
		(stroke
			(width 0.2)
			(type default)
		)
		(layer "In3.Cu")
	)
	(gr_line
		(start 9.243314 -59.192922)
		(end 9.240774 -59.192922)
		(stroke
			(width 0.2)
			(type default)
		)
		(layer "In3.Cu")
	)
	(gr_line
		(start 9.266174 -63.637668)
		(end 9.266428 -63.637922)
		(stroke
			(width 0.2)
			(type default)
		)
		(layer "In3.Cu")
	)
	(gr_line
		(start 9.266174 -60.081668)
		(end 9.266428 -60.081922)
		(stroke
			(width 0.2)
			(type default)
		)
		(layer "In3.Cu")
	)
	(gr_line
		(start 9.266428 -63.637922)
		(end 9.268714 -63.637922)
		(stroke
			(width 0.2)
			(type default)
		)
		(layer "In3.Cu")
	)
	(gr_line
		(start 9.266428 -60.081922)
		(end 9.268714 -60.081922)
		(stroke
			(width 0.2)
			(type default)
		)
		(layer "In3.Cu")
	)
	(gr_arc
		(start 9.268714 -63.637922)
		(mid 9.662922 -64.010286)
		(end 10.035286 -63.616078)
		(stroke
			(width 0.2)
			(type default)
		)
		(layer "In3.Cu")
	)
	(gr_arc
		(start 9.268714 -60.081922)
		(mid 9.662922 -60.454286)
		(end 10.035286 -60.060078)
		(stroke
			(width 0.2)
			(type default)
		)
		(layer "In3.Cu")
	)
	(gr_circle
		(center 9.5504 -51.7398)
		(end 9.90854 -51.7398)
		(stroke
			(width 0.2)
			(type default)
		)
		(fill no)
		(layer "In3.Cu")
	)
	(gr_circle
		(center 9.5504 -50.4952)
		(end 9.90854 -50.4952)
		(stroke
			(width 0.2)
			(type default)
		)
		(fill no)
		(layer "In3.Cu")
	)
	(gr_arc
		(start 10.009886 -62.727078)
		(mid 9.615678 -62.354714)
		(end 9.243314 -62.748922)
		(stroke
			(width 0.2)
			(type default)
		)
		(layer "In3.Cu")
	)
	(gr_arc
		(start 10.009886 -59.171078)
		(mid 9.615678 -58.798714)
		(end 9.243314 -59.192922)
		(stroke
			(width 0.2)
			(type default)
		)
		(layer "In3.Cu")
	)
	(gr_line
		(start 10.01014 -65.405)
		(end 10.01014 -64.516254)
		(stroke
			(width 0.2)
			(type default)
		)
		(layer "In3.Cu")
	)
	(gr_arc
		(start 10.01014 -64.516254)
		(mid 9.626727 -64.13246)
		(end 9.24306 -64.516)
		(stroke
			(width 0.2)
			(type default)
		)
		(layer "In3.Cu")
	)
	(gr_line
		(start 10.01014 -61.849)
		(end 10.01014 -60.960254)
		(stroke
			(width 0.2)
			(type default)
		)
		(layer "In3.Cu")
	)
	(gr_arc
		(start 10.01014 -60.960254)
		(mid 9.626727 -60.57646)
		(end 9.24306 -60.96)
		(stroke
			(width 0.2)
			(type default)
		)
		(layer "In3.Cu")
	)
	(gr_line
		(start 10.01014 -58.293)
		(end 10.01014 -57.404254)
		(stroke
			(width 0.2)
			(type default)
		)
		(layer "In3.Cu")
	)
	(gr_arc
		(start 10.01014 -57.404254)
		(mid 9.626727 -57.02046)
		(end 9.24306 -57.404)
		(stroke
			(width 0.2)
			(type default)
		)
		(layer "In3.Cu")
	)
	(gr_line
		(start 10.01014 -56.515)
		(end 10.01014 -55.626254)
		(stroke
			(width 0.2)
			(type default)
		)
		(layer "In3.Cu")
	)
	(gr_arc
		(start 10.01014 -55.626254)
		(mid 9.626727 -55.24246)
		(end 9.24306 -55.626)
		(stroke
			(width 0.2)
			(type default)
		)
		(layer "In3.Cu")
	)
	(gr_line
		(start 10.012426 -62.727078)
		(end 10.009886 -62.727078)
		(stroke
			(width 0.2)
			(type default)
		)
		(layer "In3.Cu")
	)
	(gr_line
		(start 10.012426 -59.171078)
		(end 10.009886 -59.171078)
		(stroke
			(width 0.2)
			(type default)
		)
		(layer "In3.Cu")
	)
	(gr_line
		(start 10.035286 -63.616078)
		(end 10.037826 -63.616078)
		(stroke
			(width 0.2)
			(type default)
		)
		(layer "In3.Cu")
	)
	(gr_line
		(start 10.035286 -60.060078)
		(end 10.037826 -60.060078)
		(stroke
			(width 0.2)
			(type default)
		)
		(layer "In3.Cu")
	)
	(gr_line
		(start 10.037826 -63.616078)
		(end 10.012426 -62.727078)
		(stroke
			(width 0.2)
			(type default)
		)
		(layer "In3.Cu")
	)
	(gr_line
		(start 10.037826 -60.060078)
		(end 10.012426 -59.171078)
		(stroke
			(width 0.2)
			(type default)
		)
		(layer "In3.Cu")
	)
	(gr_circle
		(center 10.2616 -54.0258)
		(end 10.61974 -54.0258)
		(stroke
			(width 0.2)
			(type default)
		)
		(fill no)
		(layer "In3.Cu")
	)
	(gr_circle
		(center 10.2616 -52.7812)
		(end 10.61974 -52.7812)
		(stroke
			(width 0.2)
			(type default)
		)
		(fill no)
		(layer "In3.Cu")
	)
	(gr_arc
		(start 12.7889 -48.617886)
		(mid 13.172313 -49.00168)
		(end 13.55598 -48.61814)
		(stroke
			(width 0.2)
			(type default)
		)
		(layer "In3.Cu")
	)
	(gr_line
		(start 12.7889 -47.66056)
		(end 12.7889 -48.617886)
		(stroke
			(width 0.2)
			(type default)
		)
		(layer "In3.Cu")
	)
	(gr_line
		(start 13.55598 -48.61814)
		(end 13.55598 -47.66056)
		(stroke
			(width 0.2)
			(type default)
		)
		(layer "In3.Cu")
	)
	(gr_arc
		(start 13.55598 -47.66056)
		(mid 13.17244 -47.27702)
		(end 12.7889 -47.66056)
		(stroke
			(width 0.2)
			(type default)
		)
		(layer "In3.Cu")
	)
	(gr_line
		(start 14.15288 -47.21606)
		(end 15.082266 -47.21606)
		(stroke
			(width 0.2)
			(type default)
		)
		(layer "In3.Cu")
	)
	(gr_arc
		(start 14.153134 -46.44898)
		(mid 13.76934 -46.832393)
		(end 14.15288 -47.21606)
		(stroke
			(width 0.2)
			(type default)
		)
		(layer "In3.Cu")
	)
	(gr_arc
		(start 15.082266 -47.21606)
		(mid 15.465806 -46.83252)
		(end 15.082266 -46.44898)
		(stroke
			(width 0.2)
			(type default)
		)
		(layer "In3.Cu")
	)
	(gr_line
		(start 15.082266 -46.44898)
		(end 14.153134 -46.44898)
		(stroke
			(width 0.2)
			(type default)
		)
		(layer "In3.Cu")
	)
	(gr_line
		(start 19.408394 -10.634218)
		(end 20.327874 -10.634218)
		(stroke
			(width 0.2)
			(type default)
		)
		(layer "In3.Cu")
	)
	(gr_arc
		(start 19.408648 -9.867138)
		(mid 19.024854 -10.250551)
		(end 19.408394 -10.634218)
		(stroke
			(width 0.2)
			(type default)
		)
		(layer "In3.Cu")
	)
	(gr_line
		(start 20.09521 -15.872206)
		(end 21.052536 -15.872206)
		(stroke
			(width 0.2)
			(type default)
		)
		(layer "In3.Cu")
	)
	(gr_arc
		(start 20.09521 -15.105126)
		(mid 19.71167 -15.488666)
		(end 20.09521 -15.872206)
		(stroke
			(width 0.2)
			(type default)
		)
		(layer "In3.Cu")
	)
	(gr_arc
		(start 20.327874 -10.634218)
		(mid 20.711414 -10.250678)
		(end 20.327874 -9.867138)
		(stroke
			(width 0.2)
			(type default)
		)
		(layer "In3.Cu")
	)
	(gr_line
		(start 20.327874 -9.867138)
		(end 19.408648 -9.867138)
		(stroke
			(width 0.2)
			(type default)
		)
		(layer "In3.Cu")
	)
	(gr_arc
		(start 21.052536 -15.872206)
		(mid 21.43633 -15.488793)
		(end 21.05279 -15.105126)
		(stroke
			(width 0.2)
			(type default)
		)
		(layer "In3.Cu")
	)
	(gr_line
		(start 21.05279 -15.105126)
		(end 20.09521 -15.105126)
		(stroke
			(width 0.2)
			(type default)
		)
		(layer "In3.Cu")
	)
	(gr_line
		(start 21.6662 -14.20114)
		(end 22.5298 -14.20114)
		(stroke
			(width 0.2)
			(type default)
		)
		(layer "In3.Cu")
	)
	(gr_arc
		(start 21.666454 -13.43406)
		(mid 21.28266 -13.817473)
		(end 21.6662 -14.20114)
		(stroke
			(width 0.2)
			(type default)
		)
		(layer "In3.Cu")
	)
	(gr_arc
		(start 22.5298 -14.20114)
		(mid 22.91334 -13.8176)
		(end 22.5298 -13.43406)
		(stroke
			(width 0.2)
			(type default)
		)
		(layer "In3.Cu")
	)
	(gr_line
		(start 22.5298 -13.43406)
		(end 21.666454 -13.43406)
		(stroke
			(width 0.2)
			(type default)
		)
		(layer "In3.Cu")
	)
	(gr_line
		(start 23.408386 -10.634218)
		(end 24.327866 -10.634218)
		(stroke
			(width 0.2)
			(type default)
		)
		(layer "In3.Cu")
	)
	(gr_arc
		(start 23.40864 -9.867138)
		(mid 23.024846 -10.250551)
		(end 23.408386 -10.634218)
		(stroke
			(width 0.2)
			(type default)
		)
		(layer "In3.Cu")
	)
	(gr_arc
		(start 24.327866 -10.634218)
		(mid 24.711406 -10.250678)
		(end 24.327866 -9.867138)
		(stroke
			(width 0.2)
			(type default)
		)
		(layer "In3.Cu")
	)
	(gr_line
		(start 24.327866 -9.867138)
		(end 23.40864 -9.867138)
		(stroke
			(width 0.2)
			(type default)
		)
		(layer "In3.Cu")
	)
	(gr_line
		(start 25.4127 -14.20114)
		(end 26.276046 -14.20114)
		(stroke
			(width 0.2)
			(type default)
		)
		(layer "In3.Cu")
	)
	(gr_arc
		(start 25.4127 -13.43406)
		(mid 25.02916 -13.8176)
		(end 25.4127 -14.20114)
		(stroke
			(width 0.2)
			(type default)
		)
		(layer "In3.Cu")
	)
	(gr_arc
		(start 26.276046 -14.20114)
		(mid 26.65984 -13.817727)
		(end 26.2763 -13.43406)
		(stroke
			(width 0.2)
			(type default)
		)
		(layer "In3.Cu")
	)
	(gr_line
		(start 26.2763 -13.43406)
		(end 25.4127 -13.43406)
		(stroke
			(width 0.2)
			(type default)
		)
		(layer "In3.Cu")
	)
	(gr_line
		(start 27.408378 -10.634218)
		(end 28.327604 -10.634218)
		(stroke
			(width 0.2)
			(type default)
		)
		(layer "In3.Cu")
	)
	(gr_arc
		(start 27.408378 -9.867138)
		(mid 27.024838 -10.250678)
		(end 27.408378 -10.634218)
		(stroke
			(width 0.2)
			(type default)
		)
		(layer "In3.Cu")
	)
	(gr_arc
		(start 28.327604 -10.634218)
		(mid 28.711398 -10.250805)
		(end 28.327858 -9.867138)
		(stroke
			(width 0.2)
			(type default)
		)
		(layer "In3.Cu")
	)
	(gr_line
		(start 28.327858 -9.867138)
		(end 27.408378 -9.867138)
		(stroke
			(width 0.2)
			(type default)
		)
		(layer "In3.Cu")
	)
	(gr_line
		(start 29.4132 -14.96314)
		(end 30.276546 -14.96314)
		(stroke
			(width 0.2)
			(type default)
		)
		(layer "In3.Cu")
	)
	(gr_arc
		(start 29.4132 -14.19606)
		(mid 29.02966 -14.5796)
		(end 29.4132 -14.96314)
		(stroke
			(width 0.2)
			(type default)
		)
		(layer "In3.Cu")
	)
	(gr_arc
		(start 30.276546 -14.96314)
		(mid 30.66034 -14.579727)
		(end 30.2768 -14.19606)
		(stroke
			(width 0.2)
			(type default)
		)
		(layer "In3.Cu")
	)
	(gr_line
		(start 30.2768 -14.19606)
		(end 29.4132 -14.19606)
		(stroke
			(width 0.2)
			(type default)
		)
		(layer "In3.Cu")
	)
	(gr_line
		(start 31.40837 -10.634218)
		(end 32.327596 -10.634218)
		(stroke
			(width 0.2)
			(type default)
		)
		(layer "In3.Cu")
	)
	(gr_arc
		(start 31.40837 -9.867138)
		(mid 31.02483 -10.250678)
		(end 31.40837 -10.634218)
		(stroke
			(width 0.2)
			(type default)
		)
		(layer "In3.Cu")
	)
	(gr_arc
		(start 32.327596 -10.634218)
		(mid 32.71139 -10.250805)
		(end 32.32785 -9.867138)
		(stroke
			(width 0.2)
			(type default)
		)
		(layer "In3.Cu")
	)
	(gr_line
		(start 32.32785 -9.867138)
		(end 31.40837 -9.867138)
		(stroke
			(width 0.2)
			(type default)
		)
		(layer "In3.Cu")
	)
	(gr_line
		(start 33.4264 -14.96314)
		(end 34.289746 -14.96314)
		(stroke
			(width 0.2)
			(type default)
		)
		(layer "In3.Cu")
	)
	(gr_arc
		(start 33.4264 -14.19606)
		(mid 33.04286 -14.5796)
		(end 33.4264 -14.96314)
		(stroke
			(width 0.2)
			(type default)
		)
		(layer "In3.Cu")
	)
	(gr_arc
		(start 34.289746 -14.96314)
		(mid 34.67354 -14.579727)
		(end 34.29 -14.19606)
		(stroke
			(width 0.2)
			(type default)
		)
		(layer "In3.Cu")
	)
	(gr_line
		(start 34.29 -14.19606)
		(end 33.4264 -14.19606)
		(stroke
			(width 0.2)
			(type default)
		)
		(layer "In3.Cu")
	)
	(gr_line
		(start 35.408362 -10.634218)
		(end 36.327588 -10.634218)
		(stroke
			(width 0.2)
			(type default)
		)
		(layer "In3.Cu")
	)
	(gr_arc
		(start 35.408362 -9.867138)
		(mid 35.024822 -10.250678)
		(end 35.408362 -10.634218)
		(stroke
			(width 0.2)
			(type default)
		)
		(layer "In3.Cu")
	)
	(gr_arc
		(start 36.327588 -10.634218)
		(mid 36.711382 -10.250805)
		(end 36.327842 -9.867138)
		(stroke
			(width 0.2)
			(type default)
		)
		(layer "In3.Cu")
	)
	(gr_line
		(start 36.327842 -9.867138)
		(end 35.408362 -9.867138)
		(stroke
			(width 0.2)
			(type default)
		)
		(layer "In3.Cu")
	)
	(gr_line
		(start 37.41801 -14.20114)
		(end 38.281356 -14.20114)
		(stroke
			(width 0.2)
			(type default)
		)
		(layer "In3.Cu")
	)
	(gr_arc
		(start 37.41801 -13.43406)
		(mid 37.03447 -13.8176)
		(end 37.41801 -14.20114)
		(stroke
			(width 0.2)
			(type default)
		)
		(layer "In3.Cu")
	)
	(gr_arc
		(start 37.88664 -30.2006)
		(mid 38.27018 -30.58414)
		(end 38.65372 -30.2006)
		(stroke
			(width 0.2)
			(type default)
		)
		(layer "In3.Cu")
	)
	(gr_line
		(start 37.88664 -29.337)
		(end 37.88664 -30.2006)
		(stroke
			(width 0.2)
			(type default)
		)
		(layer "In3.Cu")
	)
	(gr_arc
		(start 38.281356 -14.20114)
		(mid 38.66515 -13.817727)
		(end 38.28161 -13.43406)
		(stroke
			(width 0.2)
			(type default)
		)
		(layer "In3.Cu")
	)
	(gr_line
		(start 38.28161 -13.43406)
		(end 37.41801 -13.43406)
		(stroke
			(width 0.2)
			(type default)
		)
		(layer "In3.Cu")
	)
	(gr_line
		(start 38.65372 -30.2006)
		(end 38.65372 -29.337254)
		(stroke
			(width 0.2)
			(type default)
		)
		(layer "In3.Cu")
	)
	(gr_arc
		(start 38.65372 -29.337254)
		(mid 38.270307 -28.95346)
		(end 37.88664 -29.337)
		(stroke
			(width 0.2)
			(type default)
		)
		(layer "In3.Cu")
	)
	(gr_line
		(start 39.408354 -10.634218)
		(end 40.327834 -10.634218)
		(stroke
			(width 0.2)
			(type default)
		)
		(layer "In3.Cu")
	)
	(gr_arc
		(start 39.408608 -9.867138)
		(mid 39.024814 -10.250551)
		(end 39.408354 -10.634218)
		(stroke
			(width 0.2)
			(type default)
		)
		(layer "In3.Cu")
	)
	(gr_line
		(start 39.44366 -12.73048)
		(end 40.40124 -12.73048)
		(stroke
			(width 0.2)
			(type default)
		)
		(layer "In3.Cu")
	)
	(gr_arc
		(start 39.443914 -11.9634)
		(mid 39.06012 -12.346813)
		(end 39.44366 -12.73048)
		(stroke
			(width 0.2)
			(type default)
		)
		(layer "In3.Cu")
	)
	(gr_arc
		(start 40.327834 -10.634218)
		(mid 40.711374 -10.250678)
		(end 40.327834 -9.867138)
		(stroke
			(width 0.2)
			(type default)
		)
		(layer "In3.Cu")
	)
	(gr_line
		(start 40.327834 -9.867138)
		(end 39.408608 -9.867138)
		(stroke
			(width 0.2)
			(type default)
		)
		(layer "In3.Cu")
	)
	(gr_arc
		(start 40.40124 -12.73048)
		(mid 40.78478 -12.34694)
		(end 40.40124 -11.9634)
		(stroke
			(width 0.2)
			(type default)
		)
		(layer "In3.Cu")
	)
	(gr_line
		(start 40.40124 -11.9634)
		(end 39.443914 -11.9634)
		(stroke
			(width 0.2)
			(type default)
		)
		(layer "In3.Cu")
	)
	(gr_line
		(start 41.418002 -14.20114)
		(end 42.281348 -14.20114)
		(stroke
			(width 0.2)
			(type default)
		)
		(layer "In3.Cu")
	)
	(gr_arc
		(start 41.418002 -13.43406)
		(mid 41.034462 -13.8176)
		(end 41.418002 -14.20114)
		(stroke
			(width 0.2)
			(type default)
		)
		(layer "In3.Cu")
	)
	(gr_arc
		(start 42.281348 -14.20114)
		(mid 42.665142 -13.817727)
		(end 42.281602 -13.43406)
		(stroke
			(width 0.2)
			(type default)
		)
		(layer "In3.Cu")
	)
	(gr_line
		(start 42.281602 -13.43406)
		(end 41.418002 -13.43406)
		(stroke
			(width 0.2)
			(type default)
		)
		(layer "In3.Cu")
	)
	(gr_line
		(start 42.45356 -44.5389)
		(end 43.41114 -44.5389)
		(stroke
			(width 0.2)
			(type default)
		)
		(layer "In3.Cu")
	)
	(gr_arc
		(start 42.453814 -43.77182)
		(mid 42.07002 -44.155233)
		(end 42.45356 -44.5389)
		(stroke
			(width 0.2)
			(type default)
		)
		(layer "In3.Cu")
	)
	(gr_line
		(start 43.25366 -12.98194)
		(end 44.210986 -12.98194)
		(stroke
			(width 0.2)
			(type default)
		)
		(layer "In3.Cu")
	)
	(gr_arc
		(start 43.25366 -12.21486)
		(mid 42.87012 -12.5984)
		(end 43.25366 -12.98194)
		(stroke
			(width 0.2)
			(type default)
		)
		(layer "In3.Cu")
	)
	(gr_line
		(start 43.408346 -10.634218)
		(end 44.327826 -10.634218)
		(stroke
			(width 0.2)
			(type default)
		)
		(layer "In3.Cu")
	)
	(gr_arc
		(start 43.4086 -9.867138)
		(mid 43.024806 -10.250551)
		(end 43.408346 -10.634218)
		(stroke
			(width 0.2)
			(type default)
		)
		(layer "In3.Cu")
	)
	(gr_arc
		(start 43.41114 -44.5389)
		(mid 43.79468 -44.15536)
		(end 43.41114 -43.77182)
		(stroke
			(width 0.2)
			(type default)
		)
		(layer "In3.Cu")
	)
	(gr_line
		(start 43.41114 -43.77182)
		(end 42.453814 -43.77182)
		(stroke
			(width 0.2)
			(type default)
		)
		(layer "In3.Cu")
	)
	(gr_arc
		(start 44.210986 -12.98194)
		(mid 44.59478 -12.598527)
		(end 44.21124 -12.21486)
		(stroke
			(width 0.2)
			(type default)
		)
		(layer "In3.Cu")
	)
	(gr_line
		(start 44.21124 -12.21486)
		(end 43.25366 -12.21486)
		(stroke
			(width 0.2)
			(type default)
		)
		(layer "In3.Cu")
	)
	(gr_arc
		(start 44.327826 -10.634218)
		(mid 44.711366 -10.250678)
		(end 44.327826 -9.867138)
		(stroke
			(width 0.2)
			(type default)
		)
		(layer "In3.Cu")
	)
	(gr_line
		(start 44.327826 -9.867138)
		(end 43.4086 -9.867138)
		(stroke
			(width 0.2)
			(type default)
		)
		(layer "In3.Cu")
	)
	(gr_line
		(start 44.98975 -44.30014)
		(end 45.947838 -44.32173)
		(stroke
			(width 0.2)
			(type default)
		)
		(layer "In3.Cu")
	)
	(gr_arc
		(start 45.007276 -43.53306)
		(mid 44.615103 -43.907837)
		(end 44.98975 -44.30014)
		(stroke
			(width 0.2)
			(type default)
		)
		(layer "In3.Cu")
	)
	(gr_line
		(start 45.466 -14.1986)
		(end 46.176946 -14.1986)
		(stroke
			(width 0.2)
			(type default)
		)
		(layer "In3.Cu")
	)
	(gr_arc
		(start 45.466 -13.4366)
		(mid 45.085 -13.8176)
		(end 45.466 -14.1986)
		(stroke
			(width 0.2)
			(type default)
		)
		(layer "In3.Cu")
	)
	(gr_arc
		(start 45.947838 -44.32173)
		(mid 46.340014 -43.946826)
		(end 45.96511 -43.55465)
		(stroke
			(width 0.2)
			(type default)
		)
		(layer "In3.Cu")
	)
	(gr_line
		(start 45.96511 -43.55465)
		(end 45.007276 -43.53306)
		(stroke
			(width 0.2)
			(type default)
		)
		(layer "In3.Cu")
	)
	(gr_arc
		(start 46.176946 -14.1986)
		(mid 46.5582 -13.817727)
		(end 46.1772 -13.4366)
		(stroke
			(width 0.2)
			(type default)
		)
		(layer "In3.Cu")
	)
	(gr_line
		(start 46.1772 -13.4366)
		(end 45.466 -13.4366)
		(stroke
			(width 0.2)
			(type default)
		)
		(layer "In3.Cu")
	)
	(gr_line
		(start 47.408338 -10.634218)
		(end 48.327818 -10.634218)
		(stroke
			(width 0.2)
			(type default)
		)
		(layer "In3.Cu")
	)
	(gr_arc
		(start 47.408592 -9.867138)
		(mid 47.024798 -10.250551)
		(end 47.408338 -10.634218)
		(stroke
			(width 0.2)
			(type default)
		)
		(layer "In3.Cu")
	)
	(gr_line
		(start 47.46371 -14.1732)
		(end 48.183546 -14.1732)
		(stroke
			(width 0.2)
			(type default)
		)
		(layer "In3.Cu")
	)
	(gr_arc
		(start 47.46371 -13.4112)
		(mid 47.08271 -13.7922)
		(end 47.46371 -14.1732)
		(stroke
			(width 0.2)
			(type default)
		)
		(layer "In3.Cu")
	)
	(gr_arc
		(start 48.183546 -14.1732)
		(mid 48.5648 -13.792327)
		(end 48.1838 -13.4112)
		(stroke
			(width 0.2)
			(type default)
		)
		(layer "In3.Cu")
	)
	(gr_line
		(start 48.1838 -13.4112)
		(end 47.46371 -13.4112)
		(stroke
			(width 0.2)
			(type default)
		)
		(layer "In3.Cu")
	)
	(gr_arc
		(start 48.327818 -10.634218)
		(mid 48.711358 -10.250678)
		(end 48.327818 -9.867138)
		(stroke
			(width 0.2)
			(type default)
		)
		(layer "In3.Cu")
	)
	(gr_line
		(start 48.327818 -9.867138)
		(end 47.408592 -9.867138)
		(stroke
			(width 0.2)
			(type default)
		)
		(layer "In3.Cu")
	)
	(gr_line
		(start 49.176432 -38.313614)
		(end 49.81321 -38.892226)
		(stroke
			(width 0.2)
			(type default)
		)
		(layer "In3.Cu")
	)
	(gr_line
		(start 49.29505 -20.79498)
		(end 50.25263 -20.79498)
		(stroke
			(width 0.2)
			(type default)
		)
		(layer "In3.Cu")
	)
	(gr_arc
		(start 49.295304 -20.0279)
		(mid 48.91151 -20.411313)
		(end 49.29505 -20.79498)
		(stroke
			(width 0.2)
			(type default)
		)
		(layer "In3.Cu")
	)
	(gr_line
		(start 49.38903 -10.64387)
		(end 50.310542 -10.64387)
		(stroke
			(width 0.2)
			(type default)
		)
		(layer "In3.Cu")
	)
	(gr_arc
		(start 49.389284 -9.87679)
		(mid 49.00549 -10.260203)
		(end 49.38903 -10.64387)
		(stroke
			(width 0.2)
			(type default)
		)
		(layer "In3.Cu")
	)
	(gr_line
		(start 49.4538 -14.1986)
		(end 50.2158 -14.1986)
		(stroke
			(width 0.2)
			(type default)
		)
		(layer "In3.Cu")
	)
	(gr_arc
		(start 49.454054 -13.4366)
		(mid 49.0728 -13.817473)
		(end 49.4538 -14.1986)
		(stroke
			(width 0.2)
			(type default)
		)
		(layer "In3.Cu")
	)
	(gr_arc
		(start 49.692052 -37.74567)
		(mid 49.15027 -37.771832)
		(end 49.176432 -38.313614)
		(stroke
			(width 0.2)
			(type default)
		)
		(layer "In3.Cu")
	)
	(gr_arc
		(start 49.81321 -38.892226)
		(mid 50.356403 -38.869633)
		(end 50.33137 -38.326568)
		(stroke
			(width 0.2)
			(type default)
		)
		(layer "In3.Cu")
	)
	(gr_arc
		(start 50.2158 -14.1986)
		(mid 50.5968 -13.8176)
		(end 50.2158 -13.4366)
		(stroke
			(width 0.2)
			(type default)
		)
		(layer "In3.Cu")
	)
	(gr_line
		(start 50.2158 -13.4366)
		(end 49.454054 -13.4366)
		(stroke
			(width 0.2)
			(type default)
		)
		(layer "In3.Cu")
	)
	(gr_arc
		(start 50.25263 -20.79498)
		(mid 50.63617 -20.41144)
		(end 50.25263 -20.0279)
		(stroke
			(width 0.2)
			(type default)
		)
		(layer "In3.Cu")
	)
	(gr_line
		(start 50.25263 -20.0279)
		(end 49.295304 -20.0279)
		(stroke
			(width 0.2)
			(type default)
		)
		(layer "In3.Cu")
	)
	(gr_arc
		(start 50.262028 -48.49495)
		(mid 50.63998 -48.884078)
		(end 51.029108 -48.506126)
		(stroke
			(width 0.2)
			(type default)
		)
		(layer "In3.Cu")
	)
	(gr_line
		(start 50.274474 -47.63135)
		(end 50.262028 -48.49495)
		(stroke
			(width 0.2)
			(type default)
		)
		(layer "In3.Cu")
	)
	(gr_arc
		(start 50.310542 -10.64387)
		(mid 50.694082 -10.26033)
		(end 50.310542 -9.87679)
		(stroke
			(width 0.2)
			(type default)
		)
		(layer "In3.Cu")
	)
	(gr_line
		(start 50.310542 -9.87679)
		(end 49.389284 -9.87679)
		(stroke
			(width 0.2)
			(type default)
		)
		(layer "In3.Cu")
	)
	(gr_line
		(start 50.33137 -38.326568)
		(end 49.692052 -37.74567)
		(stroke
			(width 0.2)
			(type default)
		)
		(layer "In3.Cu")
	)
	(gr_line
		(start 51.029108 -48.506126)
		(end 51.041554 -47.64278)
		(stroke
			(width 0.2)
			(type default)
		)
		(layer "In3.Cu")
	)
	(gr_arc
		(start 51.041554 -47.64278)
		(mid 50.663729 -47.253654)
		(end 50.274474 -47.63135)
		(stroke
			(width 0.2)
			(type default)
		)
		(layer "In3.Cu")
	)
	(gr_line
		(start 51.282346 -34.47034)
		(end 52.16652 -34.47034)
		(stroke
			(width 0.2)
			(type default)
		)
		(layer "In3.Cu")
	)
	(gr_arc
		(start 51.2826 -33.70326)
		(mid 50.898806 -34.086673)
		(end 51.282346 -34.47034)
		(stroke
			(width 0.2)
			(type default)
		)
		(layer "In3.Cu")
	)
	(gr_line
		(start 52.1462 -14.32814)
		(end 53.009546 -14.32814)
		(stroke
			(width 0.2)
			(type default)
		)
		(layer "In3.Cu")
	)
	(gr_arc
		(start 52.1462 -13.56106)
		(mid 51.76266 -13.9446)
		(end 52.1462 -14.32814)
		(stroke
			(width 0.2)
			(type default)
		)
		(layer "In3.Cu")
	)
	(gr_arc
		(start 52.16652 -34.47034)
		(mid 52.55006 -34.0868)
		(end 52.16652 -33.70326)
		(stroke
			(width 0.2)
			(type default)
		)
		(layer "In3.Cu")
	)
	(gr_line
		(start 52.16652 -33.70326)
		(end 51.2826 -33.70326)
		(stroke
			(width 0.2)
			(type default)
		)
		(layer "In3.Cu")
	)
	(gr_arc
		(start 52.52339 -34.93262)
		(mid 52.14112 -35.31743)
		(end 52.52593 -35.6997)
		(stroke
			(width 0.2)
			(type default)
		)
		(layer "In3.Cu")
	)
	(gr_line
		(start 52.52593 -35.6997)
		(end 53.479954 -35.696652)
		(stroke
			(width 0.2)
			(type default)
		)
		(layer "In3.Cu")
	)
	(gr_arc
		(start 52.768246 -29.826966)
		(mid 53.151659 -30.21076)
		(end 53.535326 -29.82722)
		(stroke
			(width 0.2)
			(type default)
		)
		(layer "In3.Cu")
	)
	(gr_line
		(start 52.768246 -28.897834)
		(end 52.768246 -29.826966)
		(stroke
			(width 0.2)
			(type default)
		)
		(layer "In3.Cu")
	)
	(gr_arc
		(start 53.009546 -14.32814)
		(mid 53.39334 -13.944727)
		(end 53.0098 -13.56106)
		(stroke
			(width 0.2)
			(type default)
		)
		(layer "In3.Cu")
	)
	(gr_line
		(start 53.0098 -13.56106)
		(end 52.1462 -13.56106)
		(stroke
			(width 0.2)
			(type default)
		)
		(layer "In3.Cu")
	)
	(gr_line
		(start 53.477668 -34.929572)
		(end 52.52339 -34.93262)
		(stroke
			(width 0.2)
			(type default)
		)
		(layer "In3.Cu")
	)
	(gr_arc
		(start 53.479954 -35.696652)
		(mid 53.862478 -35.311969)
		(end 53.477668 -34.929572)
		(stroke
			(width 0.2)
			(type default)
		)
		(layer "In3.Cu")
	)
	(gr_line
		(start 53.535326 -29.82722)
		(end 53.535326 -28.897834)
		(stroke
			(width 0.2)
			(type default)
		)
		(layer "In3.Cu")
	)
	(gr_arc
		(start 53.535326 -28.897834)
		(mid 53.151786 -28.514294)
		(end 52.768246 -28.897834)
		(stroke
			(width 0.2)
			(type default)
		)
		(layer "In3.Cu")
	)
	(gr_line
		(start 59.078114 -11.320018)
		(end 59.997594 -11.320018)
		(stroke
			(width 0.2)
			(type default)
		)
		(layer "In3.Cu")
	)
	(gr_arc
		(start 59.078368 -10.552938)
		(mid 58.694574 -10.936351)
		(end 59.078114 -11.320018)
		(stroke
			(width 0.2)
			(type default)
		)
		(layer "In3.Cu")
	)
	(gr_arc
		(start 59.27471 -36.33724)
		(mid 59.65825 -36.72078)
		(end 60.04179 -36.33724)
		(stroke
			(width 0.2)
			(type default)
		)
		(layer "In3.Cu")
	)
	(gr_line
		(start 59.27471 -35.37966)
		(end 59.27471 -36.33724)
		(stroke
			(width 0.2)
			(type default)
		)
		(layer "In3.Cu")
	)
	(gr_arc
		(start 59.997594 -11.320018)
		(mid 60.381134 -10.936478)
		(end 59.997594 -10.552938)
		(stroke
			(width 0.2)
			(type default)
		)
		(layer "In3.Cu")
	)
	(gr_line
		(start 59.997594 -10.552938)
		(end 59.078368 -10.552938)
		(stroke
			(width 0.2)
			(type default)
		)
		(layer "In3.Cu")
	)
	(gr_line
		(start 60.04179 -36.33724)
		(end 60.04179 -35.379914)
		(stroke
			(width 0.2)
			(type default)
		)
		(layer "In3.Cu")
	)
	(gr_arc
		(start 60.04179 -35.379914)
		(mid 59.658377 -34.99612)
		(end 59.27471 -35.37966)
		(stroke
			(width 0.2)
			(type default)
		)
		(layer "In3.Cu")
	)
	(gr_line
		(start 60.551822 -45.897038)
		(end 60.607448 -46.75886)
		(stroke
			(width 0.2)
			(type default)
		)
		(layer "In3.Cu")
	)
	(gr_arc
		(start 60.607448 -46.75886)
		(mid 61.014864 -47.117)
		(end 61.373004 -46.709584)
		(stroke
			(width 0.2)
			(type default)
		)
		(layer "In3.Cu")
	)
	(gr_arc
		(start 61.317378 -45.848016)
		(mid 60.910088 -45.489868)
		(end 60.551822 -45.897038)
		(stroke
			(width 0.2)
			(type default)
		)
		(layer "In3.Cu")
	)
	(gr_line
		(start 61.373004 -46.709584)
		(end 61.317378 -45.848016)
		(stroke
			(width 0.2)
			(type default)
		)
		(layer "In3.Cu")
	)
	(gr_line
		(start 61.40831 -10.634218)
		(end 62.327536 -10.634218)
		(stroke
			(width 0.2)
			(type default)
		)
		(layer "In3.Cu")
	)
	(gr_arc
		(start 61.40831 -9.867138)
		(mid 61.02477 -10.250678)
		(end 61.40831 -10.634218)
		(stroke
			(width 0.2)
			(type default)
		)
		(layer "In3.Cu")
	)
	(gr_arc
		(start 62.327536 -10.634218)
		(mid 62.71133 -10.250805)
		(end 62.32779 -9.867138)
		(stroke
			(width 0.2)
			(type default)
		)
		(layer "In3.Cu")
	)
	(gr_line
		(start 62.32779 -9.867138)
		(end 61.40831 -9.867138)
		(stroke
			(width 0.2)
			(type default)
		)
		(layer "In3.Cu")
	)
	(gr_line
		(start 63.627 -15.0876)
		(end 64.389 -15.0876)
		(stroke
			(width 0.2)
			(type default)
		)
		(layer "In3.Cu")
	)
	(gr_arc
		(start 63.627254 -14.3256)
		(mid 63.246 -14.706473)
		(end 63.627 -15.0876)
		(stroke
			(width 0.2)
			(type default)
		)
		(layer "In3.Cu")
	)
	(gr_arc
		(start 64.389 -15.0876)
		(mid 64.77 -14.7066)
		(end 64.389 -14.3256)
		(stroke
			(width 0.2)
			(type default)
		)
		(layer "In3.Cu")
	)
	(gr_line
		(start 64.389 -14.3256)
		(end 63.627254 -14.3256)
		(stroke
			(width 0.2)
			(type default)
		)
		(layer "In3.Cu")
	)
	(gr_line
		(start 65.786 -15.0622)
		(end 66.547746 -15.0622)
		(stroke
			(width 0.2)
			(type default)
		)
		(layer "In3.Cu")
	)
	(gr_arc
		(start 65.786 -14.3002)
		(mid 65.405 -14.6812)
		(end 65.786 -15.0622)
		(stroke
			(width 0.2)
			(type default)
		)
		(layer "In3.Cu")
	)
	(gr_arc
		(start 66.547746 -15.0622)
		(mid 66.929 -14.681327)
		(end 66.548 -14.3002)
		(stroke
			(width 0.2)
			(type default)
		)
		(layer "In3.Cu")
	)
	(gr_line
		(start 66.548 -14.3002)
		(end 65.786 -14.3002)
		(stroke
			(width 0.2)
			(type default)
		)
		(layer "In3.Cu")
	)
	(gr_line
		(start 67.34556 -10.668)
		(end 68.302886 -10.668)
		(stroke
			(width 0.2)
			(type default)
		)
		(layer "In3.Cu")
	)
	(gr_arc
		(start 67.34556 -9.90092)
		(mid 66.96202 -10.28446)
		(end 67.34556 -10.668)
		(stroke
			(width 0.2)
			(type default)
		)
		(layer "In3.Cu")
	)
	(gr_line
		(start 68.072 -14.98854)
		(end 68.834 -14.98854)
		(stroke
			(width 0.2)
			(type default)
		)
		(layer "In3.Cu")
	)
	(gr_arc
		(start 68.072254 -14.22146)
		(mid 67.68846 -14.604873)
		(end 68.072 -14.98854)
		(stroke
			(width 0.2)
			(type default)
		)
		(layer "In3.Cu")
	)
	(gr_arc
		(start 68.302886 -10.668)
		(mid 68.68668 -10.284587)
		(end 68.30314 -9.90092)
		(stroke
			(width 0.2)
			(type default)
		)
		(layer "In3.Cu")
	)
	(gr_line
		(start 68.30314 -9.90092)
		(end 67.34556 -9.90092)
		(stroke
			(width 0.2)
			(type default)
		)
		(layer "In3.Cu")
	)
	(gr_arc
		(start 68.75145 -28.403296)
		(mid 69.133212 -28.788614)
		(end 69.51853 -28.406852)
		(stroke
			(width 0.2)
			(type default)
		)
		(layer "In3.Cu")
	)
	(gr_line
		(start 68.75526 -27.51963)
		(end 68.75145 -28.403296)
		(stroke
			(width 0.2)
			(type default)
		)
		(layer "In3.Cu")
	)
	(gr_arc
		(start 68.834 -14.98854)
		(mid 69.21754 -14.605)
		(end 68.834 -14.22146)
		(stroke
			(width 0.2)
			(type default)
		)
		(layer "In3.Cu")
	)
	(gr_line
		(start 68.834 -14.22146)
		(end 68.072254 -14.22146)
		(stroke
			(width 0.2)
			(type default)
		)
		(layer "In3.Cu")
	)
	(gr_line
		(start 69.51853 -28.406852)
		(end 69.52234 -27.52344)
		(stroke
			(width 0.2)
			(type default)
		)
		(layer "In3.Cu")
	)
	(gr_arc
		(start 69.52234 -27.52344)
		(mid 69.140705 -27.138123)
		(end 68.75526 -27.51963)
		(stroke
			(width 0.2)
			(type default)
		)
		(layer "In3.Cu")
	)
	(gr_line
		(start 71.370952 -10.668)
		(end 72.328532 -10.668)
		(stroke
			(width 0.2)
			(type default)
		)
		(layer "In3.Cu")
	)
	(gr_arc
		(start 71.371206 -9.90092)
		(mid 70.987412 -10.284333)
		(end 71.370952 -10.668)
		(stroke
			(width 0.2)
			(type default)
		)
		(layer "In3.Cu")
	)
	(gr_arc
		(start 72.328532 -10.668)
		(mid 72.712072 -10.28446)
		(end 72.328532 -9.90092)
		(stroke
			(width 0.2)
			(type default)
		)
		(layer "In3.Cu")
	)
	(gr_line
		(start 72.328532 -9.90092)
		(end 71.371206 -9.90092)
		(stroke
			(width 0.2)
			(type default)
		)
		(layer "In3.Cu")
	)
	(gr_line
		(start 72.8472 -15.09014)
		(end 73.7108 -15.09014)
		(stroke
			(width 0.2)
			(type default)
		)
		(layer "In3.Cu")
	)
	(gr_arc
		(start 72.847454 -14.32306)
		(mid 72.46366 -14.706473)
		(end 72.8472 -15.09014)
		(stroke
			(width 0.2)
			(type default)
		)
		(layer "In3.Cu")
	)
	(gr_arc
		(start 73.7108 -15.09014)
		(mid 74.09434 -14.7066)
		(end 73.7108 -14.32306)
		(stroke
			(width 0.2)
			(type default)
		)
		(layer "In3.Cu")
	)
	(gr_line
		(start 73.7108 -14.32306)
		(end 72.847454 -14.32306)
		(stroke
			(width 0.2)
			(type default)
		)
		(layer "In3.Cu")
	)
	(gr_line
		(start 75.370944 -10.668)
		(end 76.328524 -10.668)
		(stroke
			(width 0.2)
			(type default)
		)
		(layer "In3.Cu")
	)
	(gr_arc
		(start 75.371198 -9.90092)
		(mid 74.987404 -10.284333)
		(end 75.370944 -10.668)
		(stroke
			(width 0.2)
			(type default)
		)
		(layer "In3.Cu")
	)
	(gr_arc
		(start 76.328524 -10.668)
		(mid 76.712064 -10.28446)
		(end 76.328524 -9.90092)
		(stroke
			(width 0.2)
			(type default)
		)
		(layer "In3.Cu")
	)
	(gr_line
		(start 76.328524 -9.90092)
		(end 75.371198 -9.90092)
		(stroke
			(width 0.2)
			(type default)
		)
		(layer "In3.Cu")
	)
	(gr_line
		(start 77.4192 -14.96314)
		(end 78.2828 -14.96314)
		(stroke
			(width 0.2)
			(type default)
		)
		(layer "In3.Cu")
	)
	(gr_arc
		(start 77.419454 -14.19606)
		(mid 77.03566 -14.579473)
		(end 77.4192 -14.96314)
		(stroke
			(width 0.2)
			(type default)
		)
		(layer "In3.Cu")
	)
	(gr_arc
		(start 77.972666 -29.55925)
		(mid 77.633576 -29.90596)
		(end 77.980286 -30.24505)
		(stroke
			(width 0.2)
			(type default)
		)
		(layer "In3.Cu")
	)
	(gr_line
		(start 77.980286 -30.24505)
		(end 78.538832 -30.2387)
		(stroke
			(width 0.2)
			(type default)
		)
		(layer "In3.Cu")
	)
	(gr_line
		(start 78.090014 -31.508446)
		(end 78.648814 -31.53283)
		(stroke
			(width 0.2)
			(type default)
		)
		(layer "In3.Cu")
	)
	(gr_arc
		(start 78.12024 -30.823154)
		(mid 77.762614 -31.150687)
		(end 78.090014 -31.508446)
		(stroke
			(width 0.2)
			(type default)
		)
		(layer "In3.Cu")
	)
	(gr_arc
		(start 78.2828 -14.96314)
		(mid 78.66634 -14.5796)
		(end 78.2828 -14.19606)
		(stroke
			(width 0.2)
			(type default)
		)
		(layer "In3.Cu")
	)
	(gr_line
		(start 78.2828 -14.19606)
		(end 77.419454 -14.19606)
		(stroke
			(width 0.2)
			(type default)
		)
		(layer "In3.Cu")
	)
	(gr_line
		(start 78.531466 -29.5529)
		(end 77.972666 -29.55925)
		(stroke
			(width 0.2)
			(type default)
		)
		(layer "In3.Cu")
	)
	(gr_arc
		(start 78.538832 -30.2387)
		(mid 78.878175 -29.892117)
		(end 78.531466 -29.5529)
		(stroke
			(width 0.2)
			(type default)
		)
		(layer "In3.Cu")
	)
	(gr_arc
		(start 78.648814 -31.53283)
		(mid 79.006446 -31.20517)
		(end 78.678786 -30.847538)
		(stroke
			(width 0.2)
			(type default)
		)
		(layer "In3.Cu")
	)
	(gr_line
		(start 78.678786 -30.847538)
		(end 78.12024 -30.823154)
		(stroke
			(width 0.2)
			(type default)
		)
		(layer "In3.Cu")
	)
	(gr_line
		(start 79.370936 -10.7188)
		(end 80.328516 -10.7188)
		(stroke
			(width 0.2)
			(type default)
		)
		(layer "In3.Cu")
	)
	(gr_arc
		(start 79.37119 -9.95172)
		(mid 78.987396 -10.335133)
		(end 79.370936 -10.7188)
		(stroke
			(width 0.2)
			(type default)
		)
		(layer "In3.Cu")
	)
	(gr_line
		(start 80.2132 -14.96314)
		(end 81.076546 -14.96314)
		(stroke
			(width 0.2)
			(type default)
		)
		(layer "In3.Cu")
	)
	(gr_arc
		(start 80.2132 -14.19606)
		(mid 79.82966 -14.5796)
		(end 80.2132 -14.96314)
		(stroke
			(width 0.2)
			(type default)
		)
		(layer "In3.Cu")
	)
	(gr_arc
		(start 80.2259 -54.685946)
		(mid 80.568673 -55.0291)
		(end 80.9117 -54.6862)
		(stroke
			(width 0.2)
			(type default)
		)
		(layer "In3.Cu")
	)
	(gr_line
		(start 80.2259 -54.1274)
		(end 80.2259 -54.685946)
		(stroke
			(width 0.2)
			(type default)
		)
		(layer "In3.Cu")
	)
	(gr_line
		(start 80.264 -60.7187)
		(end 81.0514 -60.7187)
		(stroke
			(width 0.2)
			(type default)
		)
		(layer "In3.Cu")
	)
	(gr_arc
		(start 80.264254 -60.0329)
		(mid 79.9211 -60.375673)
		(end 80.264 -60.7187)
		(stroke
			(width 0.2)
			(type default)
		)
		(layer "In3.Cu")
	)
	(gr_arc
		(start 80.328516 -10.7188)
		(mid 80.712056 -10.33526)
		(end 80.328516 -9.95172)
		(stroke
			(width 0.2)
			(type default)
		)
		(layer "In3.Cu")
	)
	(gr_line
		(start 80.328516 -9.95172)
		(end 79.37119 -9.95172)
		(stroke
			(width 0.2)
			(type default)
		)
		(layer "In3.Cu")
	)
	(gr_line
		(start 80.9117 -54.6862)
		(end 80.9117 -54.1274)
		(stroke
			(width 0.2)
			(type default)
		)
		(layer "In3.Cu")
	)
	(gr_arc
		(start 80.9117 -54.1274)
		(mid 80.5688 -53.7845)
		(end 80.2259 -54.1274)
		(stroke
			(width 0.2)
			(type default)
		)
		(layer "In3.Cu")
	)
	(gr_arc
		(start 81.0514 -60.7187)
		(mid 81.3943 -60.3758)
		(end 81.0514 -60.0329)
		(stroke
			(width 0.2)
			(type default)
		)
		(layer "In3.Cu")
	)
	(gr_line
		(start 81.0514 -60.0329)
		(end 80.264254 -60.0329)
		(stroke
			(width 0.2)
			(type default)
		)
		(layer "In3.Cu")
	)
	(gr_arc
		(start 81.076546 -14.96314)
		(mid 81.46034 -14.579727)
		(end 81.0768 -14.19606)
		(stroke
			(width 0.2)
			(type default)
		)
		(layer "In3.Cu")
	)
	(gr_line
		(start 81.0768 -14.19606)
		(end 80.2132 -14.19606)
		(stroke
			(width 0.2)
			(type default)
		)
		(layer "In3.Cu")
	)
	(gr_arc
		(start 81.3435 -53.593746)
		(mid 81.686273 -53.9369)
		(end 82.0293 -53.594)
		(stroke
			(width 0.2)
			(type default)
		)
		(layer "In3.Cu")
	)
	(gr_line
		(start 81.3435 -53.0098)
		(end 81.3435 -53.593746)
		(stroke
			(width 0.2)
			(type default)
		)
		(layer "In3.Cu")
	)
	(gr_line
		(start 82.0293 -53.594)
		(end 82.0293 -53.0098)
		(stroke
			(width 0.2)
			(type default)
		)
		(layer "In3.Cu")
	)
	(gr_arc
		(start 82.0293 -53.0098)
		(mid 81.6864 -52.6669)
		(end 81.3435 -53.0098)
		(stroke
			(width 0.2)
			(type default)
		)
		(layer "In3.Cu")
	)
	(gr_line
		(start 82.296 -14.32814)
		(end 83.1596 -14.32814)
		(stroke
			(width 0.2)
			(type default)
		)
		(layer "In3.Cu")
	)
	(gr_arc
		(start 82.296254 -13.56106)
		(mid 81.91246 -13.944473)
		(end 82.296 -14.32814)
		(stroke
			(width 0.2)
			(type default)
		)
		(layer "In3.Cu")
	)
	(gr_arc
		(start 82.803746 -55.65902)
		(mid 82.83702 -56.146446)
		(end 83.324446 -56.113172)
		(stroke
			(width 0.2)
			(type default)
		)
		(layer "In3.Cu")
	)
	(gr_arc
		(start 83.1596 -14.32814)
		(mid 83.54314 -13.9446)
		(end 83.1596 -13.56106)
		(stroke
			(width 0.2)
			(type default)
		)
		(layer "In3.Cu")
	)
	(gr_line
		(start 83.1596 -13.56106)
		(end 82.296254 -13.56106)
		(stroke
			(width 0.2)
			(type default)
		)
		(layer "In3.Cu")
	)
	(gr_line
		(start 83.18119 -55.226204)
		(end 82.803746 -55.65902)
		(stroke
			(width 0.2)
			(type default)
		)
		(layer "In3.Cu")
	)
	(gr_arc
		(start 83.309968 -59.661806)
		(mid 83.308952 -60.146946)
		(end 83.794092 -60.147962)
		(stroke
			(width 0.2)
			(type default)
		)
		(layer "In3.Cu")
	)
	(gr_line
		(start 83.324446 -56.113172)
		(end 83.701636 -55.68061)
		(stroke
			(width 0.2)
			(type default)
		)
		(layer "In3.Cu")
	)
	(gr_line
		(start 83.388962 -10.79627)
		(end 84.310474 -10.79627)
		(stroke
			(width 0.2)
			(type default)
		)
		(layer "In3.Cu")
	)
	(gr_arc
		(start 83.389216 -10.02919)
		(mid 83.005422 -10.412603)
		(end 83.388962 -10.79627)
		(stroke
			(width 0.2)
			(type default)
		)
		(layer "In3.Cu")
	)
	(gr_arc
		(start 83.701636 -55.68061)
		(mid 83.668625 -55.193446)
		(end 83.18119 -55.226204)
		(stroke
			(width 0.2)
			(type default)
		)
		(layer "In3.Cu")
	)
	(gr_line
		(start 83.794092 -60.147962)
		(end 84.348828 -59.595258)
		(stroke
			(width 0.2)
			(type default)
		)
		(layer "In3.Cu")
	)
	(gr_line
		(start 83.868006 -59.106054)
		(end 83.309968 -59.661806)
		(stroke
			(width 0.2)
			(type default)
		)
		(layer "In3.Cu")
	)
	(gr_arc
		(start 83.885024 -54.567836)
		(mid 84.22386 -54.91988)
		(end 84.575904 -54.581044)
		(stroke
			(width 0.2)
			(type default)
		)
		(layer "In3.Cu")
	)
	(gr_line
		(start 83.895692 -54.009036)
		(end 83.885024 -54.567836)
		(stroke
			(width 0.2)
			(type default)
		)
		(layer "In3.Cu")
	)
	(gr_arc
		(start 84.310474 -10.79627)
		(mid 84.694014 -10.41273)
		(end 84.310474 -10.02919)
		(stroke
			(width 0.2)
			(type default)
		)
		(layer "In3.Cu")
	)
	(gr_line
		(start 84.310474 -10.02919)
		(end 83.389216 -10.02919)
		(stroke
			(width 0.2)
			(type default)
		)
		(layer "In3.Cu")
	)
	(gr_arc
		(start 84.348828 -59.595258)
		(mid 84.354625 -59.108766)
		(end 83.868006 -59.106054)
		(stroke
			(width 0.2)
			(type default)
		)
		(layer "In3.Cu")
	)
	(gr_line
		(start 84.575904 -54.581044)
		(end 84.586572 -54.022498)
		(stroke
			(width 0.2)
			(type default)
		)
		(layer "In3.Cu")
	)
	(gr_arc
		(start 84.586572 -54.022498)
		(mid 84.247863 -53.670456)
		(end 83.895692 -54.009036)
		(stroke
			(width 0.2)
			(type default)
		)
		(layer "In3.Cu")
	)
	(gr_arc
		(start 85.330538 -55.356506)
		(mid 85.670517 -55.707536)
		(end 86.021418 -55.367428)
		(stroke
			(width 0.2)
			(type default)
		)
		(layer "In3.Cu")
	)
	(gr_line
		(start 85.339174 -54.79034)
		(end 85.330538 -55.356506)
		(stroke
			(width 0.2)
			(type default)
		)
		(layer "In3.Cu")
	)
	(gr_arc
		(start 85.741764 -53.758592)
		(mid 86.080727 -54.110638)
		(end 86.432644 -53.771546)
		(stroke
			(width 0.2)
			(type default)
		)
		(layer "In3.Cu")
	)
	(gr_line
		(start 85.752178 -53.19522)
		(end 85.741764 -53.758592)
		(stroke
			(width 0.2)
			(type default)
		)
		(layer "In3.Cu")
	)
	(gr_line
		(start 86.021418 -55.367428)
		(end 86.030054 -54.801008)
		(stroke
			(width 0.2)
			(type default)
		)
		(layer "In3.Cu")
	)
	(gr_arc
		(start 86.030054 -54.801008)
		(mid 85.689948 -54.450234)
		(end 85.339174 -54.79034)
		(stroke
			(width 0.2)
			(type default)
		)
		(layer "In3.Cu")
	)
	(gr_line
		(start 86.432644 -53.771546)
		(end 86.443058 -53.20792)
		(stroke
			(width 0.2)
			(type default)
		)
		(layer "In3.Cu")
	)
	(gr_arc
		(start 86.443058 -53.20792)
		(mid 86.103968 -52.85613)
		(end 85.752178 -53.19522)
		(stroke
			(width 0.2)
			(type default)
		)
		(layer "In3.Cu")
	)
	(gr_arc
		(start 86.826852 -54.834028)
		(mid 87.165307 -55.186583)
		(end 87.517732 -54.847998)
		(stroke
			(width 0.2)
			(type default)
		)
		(layer "In3.Cu")
	)
	(gr_line
		(start 86.838028 -54.270402)
		(end 86.826852 -54.834028)
		(stroke
			(width 0.2)
			(type default)
		)
		(layer "In3.Cu")
	)
	(gr_line
		(start 87.517732 -54.847998)
		(end 87.528908 -54.284118)
		(stroke
			(width 0.2)
			(type default)
		)
		(layer "In3.Cu")
	)
	(gr_arc
		(start 87.528908 -54.284118)
		(mid 87.190326 -53.93182)
		(end 86.838028 -54.270402)
		(stroke
			(width 0.2)
			(type default)
		)
		(layer "In3.Cu")
	)
	(gr_line
		(start 87.940896 -53.421534)
		(end 87.95893 -53.98008)
		(stroke
			(width 0.2)
			(type default)
		)
		(layer "In3.Cu")
	)
	(gr_line
		(start 87.943436 -53.421534)
		(end 87.940896 -53.421534)
		(stroke
			(width 0.2)
			(type default)
		)
		(layer "In3.Cu")
	)
	(gr_line
		(start 87.95893 -53.98008)
		(end 87.96147 -53.98008)
		(stroke
			(width 0.2)
			(type default)
		)
		(layer "In3.Cu")
	)
	(gr_arc
		(start 87.96147 -53.98008)
		(mid 88.317832 -54.31409)
		(end 88.651842 -53.957728)
		(stroke
			(width 0.2)
			(type default)
		)
		(layer "In3.Cu")
	)
	(gr_arc
		(start 88.633808 -53.399182)
		(mid 88.277446 -53.065172)
		(end 87.943436 -53.421534)
		(stroke
			(width 0.2)
			(type default)
		)
		(layer "In3.Cu")
	)
	(gr_line
		(start 88.636094 -53.399182)
		(end 88.633808 -53.399182)
		(stroke
			(width 0.2)
			(type default)
		)
		(layer "In3.Cu")
	)
	(gr_line
		(start 88.636348 -53.399436)
		(end 88.636094 -53.399182)
		(stroke
			(width 0.2)
			(type default)
		)
		(layer "In3.Cu")
	)
	(gr_line
		(start 88.651842 -53.957728)
		(end 88.654382 -53.957728)
		(stroke
			(width 0.2)
			(type default)
		)
		(layer "In3.Cu")
	)
	(gr_line
		(start 88.654382 -53.957728)
		(end 88.636348 -53.399436)
		(stroke
			(width 0.2)
			(type default)
		)
		(layer "In3.Cu")
	)
	(gr_arc
		(start 89.415874 -54.043326)
		(mid 89.727024 -54.420008)
		(end 90.103706 -54.108858)
		(stroke
			(width 0.2)
			(type default)
		)
		(layer "In3.Cu")
	)
	(gr_line
		(start 89.46896 -53.486812)
		(end 89.415874 -54.043326)
		(stroke
			(width 0.2)
			(type default)
		)
		(layer "In3.Cu")
	)
	(gr_line
		(start 89.789 -45.085)
		(end 90.297 -45.593)
		(stroke
			(width 0.381)
			(type default)
		)
		(layer "In3.Cu")
	)
	(gr_line
		(start 89.789 -41.021)
		(end 89.789 -45.085)
		(stroke
			(width 0.381)
			(type default)
		)
		(layer "In3.Cu")
	)
	(gr_line
		(start 90.103706 -54.108858)
		(end 90.156792 -53.552598)
		(stroke
			(width 0.2)
			(type default)
		)
		(layer "In3.Cu")
	)
	(gr_arc
		(start 90.156792 -53.552598)
		(mid 89.845768 -53.175928)
		(end 89.46896 -53.486812)
		(stroke
			(width 0.2)
			(type default)
		)
		(layer "In3.Cu")
	)
	(gr_line
		(start 90.297 -47.625)
		(end 91.059 -48.387)
		(stroke
			(width 0.381)
			(type default)
		)
		(layer "In3.Cu")
	)
	(gr_line
		(start 90.297 -45.593)
		(end 90.297 -47.625)
		(stroke
			(width 0.381)
			(type default)
		)
		(layer "In3.Cu")
	)
	(gr_line
		(start 90.678 -40.132)
		(end 89.789 -41.021)
		(stroke
			(width 0.381)
			(type default)
		)
		(layer "In3.Cu")
	)
	(gr_line
		(start 90.681556 -53.93817)
		(end 90.684096 -53.938424)
		(stroke
			(width 0.2)
			(type default)
		)
		(layer "In3.Cu")
	)
	(gr_arc
		(start 90.684096 -53.938424)
		(mid 91.010994 -54.30139)
		(end 91.37396 -53.974492)
		(stroke
			(width 0.2)
			(type default)
		)
		(layer "In3.Cu")
	)
	(gr_line
		(start 90.71102 -53.377592)
		(end 90.681556 -53.93817)
		(stroke
			(width 0.2)
			(type default)
		)
		(layer "In3.Cu")
	)
	(gr_line
		(start 90.71356 -53.377846)
		(end 90.71102 -53.377592)
		(stroke
			(width 0.2)
			(type default)
		)
		(layer "In3.Cu")
	)
	(gr_line
		(start 90.73769 -54.954932)
		(end 90.73896 -54.956964)
		(stroke
			(width 0.2)
			(type default)
		)
		(layer "In3.Cu")
	)
	(gr_line
		(start 90.73769 -54.954678)
		(end 90.73769 -54.954932)
		(stroke
			(width 0.2)
			(type default)
		)
		(layer "In3.Cu")
	)
	(gr_arc
		(start 90.73896 -54.956964)
		(mid 90.631264 -55.433468)
		(end 91.107768 -55.541164)
		(stroke
			(width 0.2)
			(type default)
		)
		(layer "In3.Cu")
	)
	(gr_line
		(start 90.932 -50.419)
		(end 91.059 -50.546)
		(stroke
			(width 0.381)
			(type default)
		)
		(layer "In3.Cu")
	)
	(gr_line
		(start 90.932 -49.911)
		(end 90.932 -50.419)
		(stroke
			(width 0.381)
			(type default)
		)
		(layer "In3.Cu")
	)
	(gr_line
		(start 91.059 -51.943)
		(end 92.075 -52.959)
		(stroke
			(width 0.381)
			(type default)
		)
		(layer "In3.Cu")
	)
	(gr_line
		(start 91.059 -50.546)
		(end 91.059 -51.943)
		(stroke
			(width 0.381)
			(type default)
		)
		(layer "In3.Cu")
	)
	(gr_line
		(start 91.059 -49.784)
		(end 90.932 -49.911)
		(stroke
			(width 0.381)
			(type default)
		)
		(layer "In3.Cu")
	)
	(gr_line
		(start 91.059 -48.387)
		(end 91.059 -49.784)
		(stroke
			(width 0.381)
			(type default)
		)
		(layer "In3.Cu")
	)
	(gr_line
		(start 91.107768 -55.541164)
		(end 91.109038 -55.543196)
		(stroke
			(width 0.2)
			(type default)
		)
		(layer "In3.Cu")
	)
	(gr_line
		(start 91.109038 -55.543196)
		(end 91.581732 -55.244746)
		(stroke
			(width 0.2)
			(type default)
		)
		(layer "In3.Cu")
	)
	(gr_line
		(start 91.210384 -54.656482)
		(end 90.73769 -54.954678)
		(stroke
			(width 0.2)
			(type default)
		)
		(layer "In3.Cu")
	)
	(gr_line
		(start 91.211654 -54.658514)
		(end 91.210384 -54.656482)
		(stroke
			(width 0.2)
			(type default)
		)
		(layer "In3.Cu")
	)
	(gr_line
		(start 91.37396 -53.974492)
		(end 91.3765 -53.974746)
		(stroke
			(width 0.2)
			(type default)
		)
		(layer "In3.Cu")
	)
	(gr_line
		(start 91.3765 -53.974746)
		(end 91.405964 -53.414422)
		(stroke
			(width 0.2)
			(type default)
		)
		(layer "In3.Cu")
	)
	(gr_arc
		(start 91.403424 -53.414168)
		(mid 91.076653 -53.050941)
		(end 90.71356 -53.377846)
		(stroke
			(width 0.2)
			(type default)
		)
		(layer "In3.Cu")
	)
	(gr_line
		(start 91.40571 -53.414168)
		(end 91.403424 -53.414168)
		(stroke
			(width 0.2)
			(type default)
		)
		(layer "In3.Cu")
	)
	(gr_line
		(start 91.405964 -53.414422)
		(end 91.40571 -53.414168)
		(stroke
			(width 0.2)
			(type default)
		)
		(layer "In3.Cu")
	)
	(gr_arc
		(start 91.580462 -55.242714)
		(mid 91.688158 -54.76621)
		(end 91.211654 -54.658514)
		(stroke
			(width 0.2)
			(type default)
		)
		(layer "In3.Cu")
	)
	(gr_line
		(start 91.581732 -55.244746)
		(end 91.580462 -55.242714)
		(stroke
			(width 0.2)
			(type default)
		)
		(layer "In3.Cu")
	)
	(gr_line
		(start 92.075 -56.642)
		(end 92.583 -57.15)
		(stroke
			(width 0.381)
			(type default)
		)
		(layer "In3.Cu")
	)
	(gr_line
		(start 92.075 -52.959)
		(end 92.075 -56.642)
		(stroke
			(width 0.381)
			(type default)
		)
		(layer "In3.Cu")
	)
	(gr_line
		(start 92.583 -61.468)
		(end 93.599 -62.484)
		(stroke
			(width 0.381)
			(type default)
		)
		(layer "In3.Cu")
	)
	(gr_line
		(start 92.583 -57.15)
		(end 92.583 -61.468)
		(stroke
			(width 0.381)
			(type default)
		)
		(layer "In3.Cu")
	)
	(gr_line
		(start 92.837 -40.132)
		(end 90.678 -40.132)
		(stroke
			(width 0.381)
			(type default)
		)
		(layer "In3.Cu")
	)
	(gr_line
		(start 93.599 -62.484)
		(end 95.123 -62.484)
		(stroke
			(width 0.381)
			(type default)
		)
		(layer "In3.Cu")
	)
	(gr_line
		(start 93.98 -38.989)
		(end 92.837 -40.132)
		(stroke
			(width 0.381)
			(type default)
		)
		(layer "In3.Cu")
	)
	(gr_line
		(start 93.98 -37.719)
		(end 93.98 -38.989)
		(stroke
			(width 0.381)
			(type default)
		)
		(layer "In3.Cu")
	)
	(gr_line
		(start 94.996 -36.703)
		(end 93.98 -37.719)
		(stroke
			(width 0.381)
			(type default)
		)
		(layer "In3.Cu")
	)
	(gr_line
		(start 95.123 -62.484)
		(end 96.393 -61.214)
		(stroke
			(width 0.381)
			(type default)
		)
		(layer "In3.Cu")
	)
	(gr_line
		(start 96.012 -49.276)
		(end 96.012 -45.085)
		(stroke
			(width 0.381)
			(type default)
		)
		(layer "In3.Cu")
	)
	(gr_line
		(start 96.012 -45.085)
		(end 96.52 -44.577)
		(stroke
			(width 0.381)
			(type default)
		)
		(layer "In3.Cu")
	)
	(gr_line
		(start 96.393 -61.214)
		(end 96.393 -56.896)
		(stroke
			(width 0.381)
			(type default)
		)
		(layer "In3.Cu")
	)
	(gr_line
		(start 96.393 -56.896)
		(end 96.901 -56.388)
		(stroke
			(width 0.381)
			(type default)
		)
		(layer "In3.Cu")
	)
	(gr_line
		(start 96.52 -44.577)
		(end 97.155 -44.577)
		(stroke
			(width 0.381)
			(type default)
		)
		(layer "In3.Cu")
	)
	(gr_line
		(start 96.647 -53.975)
		(end 96.647 -49.911)
		(stroke
			(width 0.381)
			(type default)
		)
		(layer "In3.Cu")
	)
	(gr_line
		(start 96.647 -49.911)
		(end 96.012 -49.276)
		(stroke
			(width 0.381)
			(type default)
		)
		(layer "In3.Cu")
	)
	(gr_line
		(start 96.901 -56.388)
		(end 96.901 -54.229)
		(stroke
			(width 0.381)
			(type default)
		)
		(layer "In3.Cu")
	)
	(gr_line
		(start 96.901 -54.229)
		(end 96.647 -53.975)
		(stroke
			(width 0.381)
			(type default)
		)
		(layer "In3.Cu")
	)
	(gr_line
		(start 97.155 -44.577)
		(end 97.282 -44.704)
		(stroke
			(width 0.381)
			(type default)
		)
		(layer "In3.Cu")
	)
	(gr_line
		(start 97.282 -44.704)
		(end 102.616 -44.704)
		(stroke
			(width 0.381)
			(type default)
		)
		(layer "In3.Cu")
	)
	(gr_line
		(start 99.24542 -60.922154)
		(end 99.86518 -61.523372)
		(stroke
			(width 0.2)
			(type default)
		)
		(layer "In3.Cu")
	)
	(gr_line
		(start 99.247198 -60.920376)
		(end 99.24542 -60.922154)
		(stroke
			(width 0.2)
			(type default)
		)
		(layer "In3.Cu")
	)
	(gr_arc
		(start 99.781106 -60.369704)
		(mid 99.238816 -60.378086)
		(end 99.247198 -60.920376)
		(stroke
			(width 0.2)
			(type default)
		)
		(layer "In3.Cu")
	)
	(gr_line
		(start 99.782884 -60.367926)
		(end 99.781106 -60.369704)
		(stroke
			(width 0.2)
			(type default)
		)
		(layer "In3.Cu")
	)
	(gr_line
		(start 99.86518 -61.523372)
		(end 99.865434 -61.523372)
		(stroke
			(width 0.2)
			(type default)
		)
		(layer "In3.Cu")
	)
	(gr_line
		(start 99.865434 -61.523372)
		(end 99.866958 -61.521848)
		(stroke
			(width 0.2)
			(type default)
		)
		(layer "In3.Cu")
	)
	(gr_arc
		(start 99.866958 -61.521848)
		(mid 100.409565 -61.513655)
		(end 100.40112 -60.971176)
		(stroke
			(width 0.2)
			(type default)
		)
		(layer "In3.Cu")
	)
	(gr_line
		(start 100.40112 -60.971176)
		(end 100.402898 -60.969398)
		(stroke
			(width 0.2)
			(type default)
		)
		(layer "In3.Cu")
	)
	(gr_line
		(start 100.402898 -60.969398)
		(end 99.782884 -60.367926)
		(stroke
			(width 0.2)
			(type default)
		)
		(layer "In3.Cu")
	)
	(gr_line
		(start 101.185472 -62.20587)
		(end 101.795072 -62.817756)
		(stroke
			(width 0.2)
			(type default)
		)
		(layer "In3.Cu")
	)
	(gr_arc
		(start 101.734366 -61.66993)
		(mid 101.189299 -61.660676)
		(end 101.185472 -62.20587)
		(stroke
			(width 0.2)
			(type default)
		)
		(layer "In3.Cu")
	)
	(gr_arc
		(start 101.795072 -62.817756)
		(mid 102.337616 -62.818772)
		(end 102.338632 -62.276228)
		(stroke
			(width 0.2)
			(type default)
		)
		(layer "In3.Cu")
	)
	(gr_line
		(start 102.108 -36.703)
		(end 94.996 -36.703)
		(stroke
			(width 0.381)
			(type default)
		)
		(layer "In3.Cu")
	)
	(gr_line
		(start 102.338632 -62.276228)
		(end 101.734366 -61.66993)
		(stroke
			(width 0.2)
			(type default)
		)
		(layer "In3.Cu")
	)
	(gr_line
		(start 102.616 -44.704)
		(end 102.997 -44.323)
		(stroke
			(width 0.381)
			(type default)
		)
		(layer "In3.Cu")
	)
	(gr_line
		(start 102.743 -41.656)
		(end 102.743 -41.148)
		(stroke
			(width 0.381)
			(type default)
		)
		(layer "In3.Cu")
	)
	(gr_line
		(start 102.743 -41.148)
		(end 102.997 -40.894)
		(stroke
			(width 0.381)
			(type default)
		)
		(layer "In3.Cu")
	)
	(gr_line
		(start 102.997 -44.323)
		(end 102.997 -41.91)
		(stroke
			(width 0.381)
			(type default)
		)
		(layer "In3.Cu")
	)
	(gr_line
		(start 102.997 -41.91)
		(end 102.743 -41.656)
		(stroke
			(width 0.381)
			(type default)
		)
		(layer "In3.Cu")
	)
	(gr_line
		(start 102.997 -40.894)
		(end 105.41 -40.894)
		(stroke
			(width 0.381)
			(type default)
		)
		(layer "In3.Cu")
	)
	(gr_line
		(start 103.759 -38.354)
		(end 102.108 -36.703)
		(stroke
			(width 0.381)
			(type default)
		)
		(layer "In3.Cu")
	)
	(gr_line
		(start 104.394 -38.354)
		(end 103.759 -38.354)
		(stroke
			(width 0.381)
			(type default)
		)
		(layer "In3.Cu")
	)
	(gr_line
		(start 104.648 -39.497)
		(end 104.648 -38.608)
		(stroke
			(width 0.381)
			(type default)
		)
		(layer "In3.Cu")
	)
	(gr_line
		(start 104.648 -38.608)
		(end 104.394 -38.354)
		(stroke
			(width 0.381)
			(type default)
		)
		(layer "In3.Cu")
	)
	(gr_line
		(start 104.775 -39.624)
		(end 104.648 -39.497)
		(stroke
			(width 0.381)
			(type default)
		)
		(layer "In3.Cu")
	)
	(gr_line
		(start 105.41 -40.894)
		(end 105.791 -40.513)
		(stroke
			(width 0.381)
			(type default)
		)
		(layer "In3.Cu")
	)
	(gr_line
		(start 105.41 -39.624)
		(end 104.775 -39.624)
		(stroke
			(width 0.381)
			(type default)
		)
		(layer "In3.Cu")
	)
	(gr_line
		(start 105.791 -40.513)
		(end 105.791 -40.005)
		(stroke
			(width 0.381)
			(type default)
		)
		(layer "In3.Cu")
	)
	(gr_line
		(start 105.791 -40.005)
		(end 105.41 -39.624)
		(stroke
			(width 0.381)
			(type default)
		)
		(layer "In3.Cu")
	)
	(gr_line
		(start 9.5504 -51.3969)
		(end 9.5504 -51.7398)
		(stroke
			(width 0.05715)
			(type default)
		)
		(layer "In4.Cu")
	)
	(gr_line
		(start 9.5504 -51.3969)
		(end 9.594596 -51.352704)
		(stroke
			(width 0.05715)
			(type default)
		)
		(layer "In4.Cu")
	)
	(gr_line
		(start 9.5504 -50.8381)
		(end 9.594596 -50.882296)
		(stroke
			(width 0.05715)
			(type default)
		)
		(layer "In4.Cu")
	)
	(gr_line
		(start 9.5504 -50.4952)
		(end 9.5504 -50.8381)
		(stroke
			(width 0.05715)
			(type default)
		)
		(layer "In4.Cu")
	)
	(gr_line
		(start 10.2616 -53.6956)
		(end 10.2616 -54.0258)
		(stroke
			(width 0.05715)
			(type default)
		)
		(layer "In4.Cu")
	)
	(gr_line
		(start 10.2616 -53.6956)
		(end 10.369296 -53.587904)
		(stroke
			(width 0.05715)
			(type default)
		)
		(layer "In4.Cu")
	)
	(gr_line
		(start 10.2616 -53.0098)
		(end 10.369296 -53.117496)
		(stroke
			(width 0.05715)
			(type default)
		)
		(layer "In4.Cu")
	)
	(gr_line
		(start 10.2616 -52.7812)
		(end 10.2616 -53.0098)
		(stroke
			(width 0.05715)
			(type default)
		)
		(layer "In4.Cu")
	)
	(gr_line
		(start 16.28013 -50.94859)
		(end 16.49095 -51.15941)
		(stroke
			(width 0.05715)
			(type default)
		)
		(layer "In4.Cu")
	)
	(gr_line
		(start 16.49095 -51.15941)
		(end 16.83385 -51.15941)
		(stroke
			(width 0.05715)
			(type default)
		)
		(layer "In4.Cu")
	)
	(gr_line
		(start 16.61033 -50.61585)
		(end 16.71447 -50.61585)
		(stroke
			(width 0.05715)
			(type default)
		)
		(layer "In4.Cu")
	)
	(gr_line
		(start 16.83385 -51.15941)
		(end 17.04467 -50.94859)
		(stroke
			(width 0.05715)
			(type default)
		)
		(layer "In4.Cu")
	)
	(gr_line
		(start 17.39265 -50.94859)
		(end 17.60347 -51.15941)
		(stroke
			(width 0.05715)
			(type default)
		)
		(layer "In4.Cu")
	)
	(gr_line
		(start 17.60347 -51.15941)
		(end 17.94637 -51.15941)
		(stroke
			(width 0.05715)
			(type default)
		)
		(layer "In4.Cu")
	)
	(gr_line
		(start 17.72285 -50.61585)
		(end 17.82699 -50.61585)
		(stroke
			(width 0.05715)
			(type default)
		)
		(layer "In4.Cu")
	)
	(gr_line
		(start 17.94637 -51.15941)
		(end 18.15719 -50.94859)
		(stroke
			(width 0.05715)
			(type default)
		)
		(layer "In4.Cu")
	)
	(gr_line
		(start 21.83384 -49.53254)
		(end 22.04466 -49.74336)
		(stroke
			(width 0.05715)
			(type default)
		)
		(layer "In4.Cu")
	)
	(gr_line
		(start 22.04466 -49.74336)
		(end 22.38756 -49.74336)
		(stroke
			(width 0.05715)
			(type default)
		)
		(layer "In4.Cu")
	)
	(gr_line
		(start 22.16404 -49.1998)
		(end 22.26818 -49.1998)
		(stroke
			(width 0.05715)
			(type default)
		)
		(layer "In4.Cu")
	)
	(gr_line
		(start 22.38756 -49.74336)
		(end 22.59838 -49.53254)
		(stroke
			(width 0.05715)
			(type default)
		)
		(layer "In4.Cu")
	)
	(gr_line
		(start 22.94636 -49.53254)
		(end 23.15718 -49.74336)
		(stroke
			(width 0.05715)
			(type default)
		)
		(layer "In4.Cu")
	)
	(gr_line
		(start 23.114 -30.353)
		(end 24.638 -31.877)
		(stroke
			(width 0.381)
			(type default)
		)
		(layer "In4.Cu")
	)
	(gr_line
		(start 23.114 -19.431)
		(end 23.114 -30.353)
		(stroke
			(width 0.381)
			(type default)
		)
		(layer "In4.Cu")
	)
	(gr_line
		(start 23.15718 -49.74336)
		(end 23.50008 -49.74336)
		(stroke
			(width 0.05715)
			(type default)
		)
		(layer "In4.Cu")
	)
	(gr_line
		(start 23.27656 -49.1998)
		(end 23.3807 -49.1998)
		(stroke
			(width 0.05715)
			(type default)
		)
		(layer "In4.Cu")
	)
	(gr_line
		(start 23.50008 -49.74336)
		(end 23.7109 -49.53254)
		(stroke
			(width 0.05715)
			(type default)
		)
		(layer "In4.Cu")
	)
	(gr_line
		(start 24.638 -31.877)
		(end 28.829 -31.877)
		(stroke
			(width 0.381)
			(type default)
		)
		(layer "In4.Cu")
	)
	(gr_line
		(start 26.924 -15.621)
		(end 23.114 -19.431)
		(stroke
			(width 0.381)
			(type default)
		)
		(layer "In4.Cu")
	)
	(gr_line
		(start 28.829 -31.877)
		(end 29.718 -30.988)
		(stroke
			(width 0.381)
			(type default)
		)
		(layer "In4.Cu")
	)
	(gr_line
		(start 29.718 -30.988)
		(end 29.718 -25.654)
		(stroke
			(width 0.381)
			(type default)
		)
		(layer "In4.Cu")
	)
	(gr_line
		(start 29.718 -25.654)
		(end 34.163 -21.209)
		(stroke
			(width 0.381)
			(type default)
		)
		(layer "In4.Cu")
	)
	(gr_line
		(start 34.163 -21.209)
		(end 93.218 -21.209)
		(stroke
			(width 0.381)
			(type default)
		)
		(layer "In4.Cu")
	)
	(gr_line
		(start 42.45356 -44.15536)
		(end 42.697146 -43.911774)
		(stroke
			(width 0.05715)
			(type default)
		)
		(layer "In4.Cu")
	)
	(gr_line
		(start 43.167554 -43.911774)
		(end 43.41114 -44.15536)
		(stroke
			(width 0.05715)
			(type default)
		)
		(layer "In4.Cu")
	)
	(gr_line
		(start 44.998386 -43.9166)
		(end 45.231304 -43.683682)
		(stroke
			(width 0.05715)
			(type default)
		)
		(layer "In4.Cu")
	)
	(gr_line
		(start 45.701966 -43.683682)
		(end 45.956474 -43.93819)
		(stroke
			(width 0.05715)
			(type default)
		)
		(layer "In4.Cu")
	)
	(gr_line
		(start 49.434242 -38.029642)
		(end 49.74082 -38.029642)
		(stroke
			(width 0.05715)
			(type default)
		)
		(layer "In4.Cu")
	)
	(gr_line
		(start 49.74336 -38.029642)
		(end 49.844452 -38.029642)
		(stroke
			(width 0.05715)
			(type default)
		)
		(layer "In4.Cu")
	)
	(gr_line
		(start 50.07356 -38.362382)
		(end 50.07356 -38.61054)
		(stroke
			(width 0.05715)
			(type default)
		)
		(layer "In4.Cu")
	)
	(gr_line
		(start 50.07356 -38.26764)
		(end 50.07356 -38.359842)
		(stroke
			(width 0.05715)
			(type default)
		)
		(layer "In4.Cu")
	)
	(gr_line
		(start 50.429414 -46.7487)
		(end 50.497486 -46.680628)
		(stroke
			(width 0.05715)
			(type default)
		)
		(layer "In4.Cu")
	)
	(gr_line
		(start 50.467006 -46.244002)
		(end 50.747168 -45.96384)
		(stroke
			(width 0.05715)
			(type default)
		)
		(layer "In4.Cu")
	)
	(gr_line
		(start 50.67554 -46.50613)
		(end 50.973736 -46.50613)
		(stroke
			(width 0.05715)
			(type default)
		)
		(layer "In4.Cu")
	)
	(gr_line
		(start 50.973736 -46.50613)
		(end 51.216052 -46.263814)
		(stroke
			(width 0.05715)
			(type default)
		)
		(layer "In4.Cu")
	)
	(gr_line
		(start 51.216052 -45.965364)
		(end 51.216052 -46.263814)
		(stroke
			(width 0.05715)
			(type default)
		)
		(layer "In4.Cu")
	)
	(gr_line
		(start 51.253644 -45.457364)
		(end 51.741578 -44.969176)
		(stroke
			(width 0.05715)
			(type default)
		)
		(layer "In4.Cu")
	)
	(gr_line
		(start 51.282346 -34.0868)
		(end 51.489102 -33.880044)
		(stroke
			(width 0.05715)
			(type default)
		)
		(layer "In4.Cu")
	)
	(gr_line
		(start 51.461924 -45.719492)
		(end 51.760374 -45.719492)
		(stroke
			(width 0.05715)
			(type default)
		)
		(layer "In4.Cu")
	)
	(gr_line
		(start 51.760374 -45.719492)
		(end 52.00269 -45.477176)
		(stroke
			(width 0.05715)
			(type default)
		)
		(layer "In4.Cu")
	)
	(gr_line
		(start 51.76901 -44.941744)
		(end 51.76901 -44.941998)
		(stroke
			(width 0.05715)
			(type default)
		)
		(layer "In4.Cu")
	)
	(gr_line
		(start 51.959764 -33.880044)
		(end 52.16652 -34.0868)
		(stroke
			(width 0.05715)
			(type default)
		)
		(layer "In4.Cu")
	)
	(gr_line
		(start 52.00269 -45.274738)
		(end 52.00269 -45.477176)
		(stroke
			(width 0.05715)
			(type default)
		)
		(layer "In4.Cu")
	)
	(gr_line
		(start 52.00269 -45.175424)
		(end 52.00269 -45.272198)
		(stroke
			(width 0.05715)
			(type default)
		)
		(layer "In4.Cu")
	)
	(gr_line
		(start 52.247038 -44.46397)
		(end 52.320444 -44.390564)
		(stroke
			(width 0.05715)
			(type default)
		)
		(layer "In4.Cu")
	)
	(gr_line
		(start 52.248816 -44.932854)
		(end 52.547012 -44.932854)
		(stroke
			(width 0.05715)
			(type default)
		)
		(layer "In4.Cu")
	)
	(gr_line
		(start 52.547012 -44.932854)
		(end 52.789328 -44.690538)
		(stroke
			(width 0.05715)
			(type default)
		)
		(layer "In4.Cu")
	)
	(gr_line
		(start 52.789328 -44.392342)
		(end 52.789328 -44.690538)
		(stroke
			(width 0.05715)
			(type default)
		)
		(layer "In4.Cu")
	)
	(gr_line
		(start 58.3565 -32.97174)
		(end 58.56732 -33.18256)
		(stroke
			(width 0.05715)
			(type default)
		)
		(layer "In4.Cu")
	)
	(gr_line
		(start 58.56732 -33.18256)
		(end 58.91022 -33.18256)
		(stroke
			(width 0.05715)
			(type default)
		)
		(layer "In4.Cu")
	)
	(gr_line
		(start 58.6867 -32.639)
		(end 58.79084 -32.639)
		(stroke
			(width 0.05715)
			(type default)
		)
		(layer "In4.Cu")
	)
	(gr_line
		(start 58.91022 -33.18256)
		(end 59.12104 -32.97174)
		(stroke
			(width 0.05715)
			(type default)
		)
		(layer "In4.Cu")
	)
	(gr_line
		(start 59.46902 -32.97174)
		(end 59.67984 -33.18256)
		(stroke
			(width 0.05715)
			(type default)
		)
		(layer "In4.Cu")
	)
	(gr_line
		(start 59.65825 -36.33724)
		(end 59.901836 -36.093654)
		(stroke
			(width 0.05715)
			(type default)
		)
		(layer "In4.Cu")
	)
	(gr_line
		(start 59.65825 -35.37966)
		(end 59.901836 -35.623246)
		(stroke
			(width 0.05715)
			(type default)
		)
		(layer "In4.Cu")
	)
	(gr_line
		(start 59.67984 -33.18256)
		(end 60.02274 -33.18256)
		(stroke
			(width 0.05715)
			(type default)
		)
		(layer "In4.Cu")
	)
	(gr_line
		(start 59.79922 -32.639)
		(end 59.90336 -32.639)
		(stroke
			(width 0.05715)
			(type default)
		)
		(layer "In4.Cu")
	)
	(gr_line
		(start 60.02274 -33.18256)
		(end 60.23356 -32.97174)
		(stroke
			(width 0.05715)
			(type default)
		)
		(layer "In4.Cu")
	)
	(gr_line
		(start 60.71997 -34.914078)
		(end 60.71997 -35.212274)
		(stroke
			(width 0.05715)
			(type default)
		)
		(layer "In4.Cu")
	)
	(gr_line
		(start 60.71997 -34.914078)
		(end 60.962286 -34.671762)
		(stroke
			(width 0.05715)
			(type default)
		)
		(layer "In4.Cu")
	)
	(gr_line
		(start 60.962286 -34.671762)
		(end 61.260482 -34.671762)
		(stroke
			(width 0.05715)
			(type default)
		)
		(layer "In4.Cu")
	)
	(gr_line
		(start 61.188854 -35.214052)
		(end 61.26226 -35.140646)
		(stroke
			(width 0.05715)
			(type default)
		)
		(layer "In4.Cu")
	)
	(gr_line
		(start 61.506608 -34.12744)
		(end 61.506608 -34.425636)
		(stroke
			(width 0.05715)
			(type default)
		)
		(layer "In4.Cu")
	)
	(gr_line
		(start 61.506608 -34.12744)
		(end 61.748924 -33.885124)
		(stroke
			(width 0.05715)
			(type default)
		)
		(layer "In4.Cu")
	)
	(gr_line
		(start 61.748924 -33.885124)
		(end 62.04712 -33.885124)
		(stroke
			(width 0.05715)
			(type default)
		)
		(layer "In4.Cu")
	)
	(gr_line
		(start 61.975492 -34.427414)
		(end 62.048898 -34.354008)
		(stroke
			(width 0.05715)
			(type default)
		)
		(layer "In4.Cu")
	)
	(gr_line
		(start 67.253104 -33.61436)
		(end 67.463924 -33.40354)
		(stroke
			(width 0.05715)
			(type default)
		)
		(layer "In4.Cu")
	)
	(gr_line
		(start 67.463924 -33.40354)
		(end 67.806824 -33.40354)
		(stroke
			(width 0.05715)
			(type default)
		)
		(layer "In4.Cu")
	)
	(gr_line
		(start 67.583304 -33.9471)
		(end 67.687444 -33.9471)
		(stroke
			(width 0.05715)
			(type default)
		)
		(layer "In4.Cu")
	)
	(gr_line
		(start 67.806824 -33.40354)
		(end 68.017644 -33.61436)
		(stroke
			(width 0.05715)
			(type default)
		)
		(layer "In4.Cu")
	)
	(gr_line
		(start 68.365624 -33.61436)
		(end 68.576444 -33.40354)
		(stroke
			(width 0.05715)
			(type default)
		)
		(layer "In4.Cu")
	)
	(gr_line
		(start 68.576444 -33.40354)
		(end 68.919344 -33.40354)
		(stroke
			(width 0.05715)
			(type default)
		)
		(layer "In4.Cu")
	)
	(gr_line
		(start 68.695824 -33.9471)
		(end 68.799964 -33.9471)
		(stroke
			(width 0.05715)
			(type default)
		)
		(layer "In4.Cu")
	)
	(gr_line
		(start 68.919344 -33.40354)
		(end 69.130164 -33.61436)
		(stroke
			(width 0.05715)
			(type default)
		)
		(layer "In4.Cu")
	)
	(gr_line
		(start 69.812154 -29.4005)
		(end 69.879972 -29.332682)
		(stroke
			(width 0.05715)
			(type default)
		)
		(layer "In4.Cu")
	)
	(gr_line
		(start 70.076822 -28.668218)
		(end 70.14464 -28.6004)
		(stroke
			(width 0.05715)
			(type default)
		)
		(layer "In4.Cu")
	)
	(gr_line
		(start 72.100694 -33.61436)
		(end 72.311514 -33.40354)
		(stroke
			(width 0.05715)
			(type default)
		)
		(layer "In4.Cu")
	)
	(gr_line
		(start 72.311514 -33.40354)
		(end 72.654414 -33.40354)
		(stroke
			(width 0.05715)
			(type default)
		)
		(layer "In4.Cu")
	)
	(gr_line
		(start 72.430894 -33.9471)
		(end 72.535034 -33.9471)
		(stroke
			(width 0.05715)
			(type default)
		)
		(layer "In4.Cu")
	)
	(gr_line
		(start 72.654414 -33.40354)
		(end 72.865234 -33.61436)
		(stroke
			(width 0.05715)
			(type default)
		)
		(layer "In4.Cu")
	)
	(gr_line
		(start 73.213214 -33.61436)
		(end 73.424034 -33.40354)
		(stroke
			(width 0.05715)
			(type default)
		)
		(layer "In4.Cu")
	)
	(gr_line
		(start 73.424034 -33.40354)
		(end 73.766934 -33.40354)
		(stroke
			(width 0.05715)
			(type default)
		)
		(layer "In4.Cu")
	)
	(gr_line
		(start 73.543414 -33.9471)
		(end 73.647554 -33.9471)
		(stroke
			(width 0.05715)
			(type default)
		)
		(layer "In4.Cu")
	)
	(gr_line
		(start 73.766934 -33.40354)
		(end 73.977754 -33.61436)
		(stroke
			(width 0.05715)
			(type default)
		)
		(layer "In4.Cu")
	)
	(gr_line
		(start 76.637134 -29.005022)
		(end 76.654914 -28.987242)
		(stroke
			(width 0.0508)
			(type default)
		)
		(layer "In4.Cu")
	)
	(gr_line
		(start 76.654914 -28.987242)
		(end 76.74483 -28.987242)
		(stroke
			(width 0.0508)
			(type default)
		)
		(layer "In4.Cu")
	)
	(gr_line
		(start 76.87056 -29.238702)
		(end 76.870814 -29.238702)
		(stroke
			(width 0.05715)
			(type default)
		)
		(layer "In4.Cu")
	)
	(gr_line
		(start 76.870814 -29.238702)
		(end 76.888594 -29.220922)
		(stroke
			(width 0.0508)
			(type default)
		)
		(layer "In4.Cu")
	)
	(gr_line
		(start 76.888594 -29.192982)
		(end 76.888594 -29.220922)
		(stroke
			(width 0.0508)
			(type default)
		)
		(layer "In4.Cu")
	)
	(gr_line
		(start 76.888594 -29.131006)
		(end 76.888594 -29.190442)
		(stroke
			(width 0.0508)
			(type default)
		)
		(layer "In4.Cu")
	)
	(gr_line
		(start 76.962 -33.3502)
		(end 76.9874 -33.3502)
		(stroke
			(width 0.0508)
			(type default)
		)
		(layer "In4.Cu")
	)
	(gr_line
		(start 76.962 -33.02)
		(end 76.9874 -33.02)
		(stroke
			(width 0.0508)
			(type default)
		)
		(layer "In4.Cu")
	)
	(gr_line
		(start 76.9874 -33.3502)
		(end 77.006958 -33.330642)
		(stroke
			(width 0.0508)
			(type default)
		)
		(layer "In4.Cu")
	)
	(gr_line
		(start 76.9874 -33.02)
		(end 77.006958 -33.039558)
		(stroke
			(width 0.0508)
			(type default)
		)
		(layer "In4.Cu")
	)
	(gr_line
		(start 77.008736 -33.328864)
		(end 77.0509 -33.2867)
		(stroke
			(width 0.0508)
			(type default)
		)
		(layer "In4.Cu")
	)
	(gr_line
		(start 77.008736 -33.041336)
		(end 77.0509 -33.0835)
		(stroke
			(width 0.0508)
			(type default)
		)
		(layer "In4.Cu")
	)
	(gr_line
		(start 77.089 -31.720028)
		(end 77.1144 -31.720028)
		(stroke
			(width 0.0508)
			(type default)
		)
		(layer "In4.Cu")
	)
	(gr_line
		(start 77.089 -31.389828)
		(end 77.1144 -31.389828)
		(stroke
			(width 0.0508)
			(type default)
		)
		(layer "In4.Cu")
	)
	(gr_line
		(start 77.1144 -31.720028)
		(end 77.133958 -31.70047)
		(stroke
			(width 0.0508)
			(type default)
		)
		(layer "In4.Cu")
	)
	(gr_line
		(start 77.1144 -31.389828)
		(end 77.133958 -31.409386)
		(stroke
			(width 0.0508)
			(type default)
		)
		(layer "In4.Cu")
	)
	(gr_line
		(start 77.135736 -31.698692)
		(end 77.1779 -31.656528)
		(stroke
			(width 0.0508)
			(type default)
		)
		(layer "In4.Cu")
	)
	(gr_line
		(start 77.135736 -31.411164)
		(end 77.1779 -31.453328)
		(stroke
			(width 0.0508)
			(type default)
		)
		(layer "In4.Cu")
	)
	(gr_line
		(start 77.976476 -29.90215)
		(end 78.245462 -30.171136)
		(stroke
			(width 0.0508)
			(type default)
		)
		(layer "In4.Cu")
	)
	(gr_line
		(start 78.105 -31.1658)
		(end 78.25105 -31.31185)
		(stroke
			(width 0.0508)
			(type default)
		)
		(layer "In4.Cu")
	)
	(gr_line
		(start 78.252828 -31.313628)
		(end 78.304136 -31.364936)
		(stroke
			(width 0.0508)
			(type default)
		)
		(layer "In4.Cu")
	)
	(gr_line
		(start 78.507336 -31.346648)
		(end 78.540356 -31.313628)
		(stroke
			(width 0.0508)
			(type default)
		)
		(layer "In4.Cu")
	)
	(gr_line
		(start 78.534768 -29.896308)
		(end 78.534768 -30.169358)
		(stroke
			(width 0.0508)
			(type default)
		)
		(layer "In4.Cu")
	)
	(gr_line
		(start 78.534768 -29.896308)
		(end 78.535276 -29.8958)
		(stroke
			(width 0.0508)
			(type default)
		)
		(layer "In4.Cu")
	)
	(gr_line
		(start 78.542134 -31.31185)
		(end 78.6638 -31.190184)
		(stroke
			(width 0.0508)
			(type default)
		)
		(layer "In4.Cu")
	)
	(gr_line
		(start 79.676752 -29.054552)
		(end 79.741268 -29.119068)
		(stroke
			(width 0.0508)
			(type default)
		)
		(layer "In4.Cu")
	)
	(gr_line
		(start 79.67853 -28.765246)
		(end 79.814928 -28.765246)
		(stroke
			(width 0.0508)
			(type default)
		)
		(layer "In4.Cu")
	)
	(gr_line
		(start 79.814928 -28.765246)
		(end 80.030574 -28.980638)
		(stroke
			(width 0.0508)
			(type default)
		)
		(layer "In4.Cu")
	)
	(gr_line
		(start 80.030574 -28.980638)
		(end 80.030574 -29.11729)
		(stroke
			(width 0.0508)
			(type default)
		)
		(layer "In4.Cu")
	)
	(gr_line
		(start 80.363314 -27.77109)
		(end 80.574134 -27.98191)
		(stroke
			(width 0.05715)
			(type default)
		)
		(layer "In4.Cu")
	)
	(gr_line
		(start 80.574134 -27.98191)
		(end 80.917034 -27.98191)
		(stroke
			(width 0.05715)
			(type default)
		)
		(layer "In4.Cu")
	)
	(gr_line
		(start 80.693514 -27.43835)
		(end 80.797654 -27.43835)
		(stroke
			(width 0.05715)
			(type default)
		)
		(layer "In4.Cu")
	)
	(gr_line
		(start 80.917034 -27.98191)
		(end 81.127854 -27.77109)
		(stroke
			(width 0.05715)
			(type default)
		)
		(layer "In4.Cu")
	)
	(gr_line
		(start 81.240884 -29.43606)
		(end 81.337404 -29.33954)
		(stroke
			(width 0.0508)
			(type default)
		)
		(layer "In4.Cu")
	)
	(gr_line
		(start 81.337404 -29.33954)
		(end 81.642204 -29.33954)
		(stroke
			(width 0.0508)
			(type default)
		)
		(layer "In4.Cu")
	)
	(gr_line
		(start 81.444084 -29.6418)
		(end 81.535524 -29.6418)
		(stroke
			(width 0.0508)
			(type default)
		)
		(layer "In4.Cu")
	)
	(gr_line
		(start 81.475834 -27.77109)
		(end 81.686654 -27.98191)
		(stroke
			(width 0.05715)
			(type default)
		)
		(layer "In4.Cu")
	)
	(gr_line
		(start 81.642204 -29.33954)
		(end 81.738724 -29.43606)
		(stroke
			(width 0.0508)
			(type default)
		)
		(layer "In4.Cu")
	)
	(gr_line
		(start 81.686654 -27.98191)
		(end 82.029554 -27.98191)
		(stroke
			(width 0.05715)
			(type default)
		)
		(layer "In4.Cu")
	)
	(gr_line
		(start 81.806034 -27.43835)
		(end 81.910174 -27.43835)
		(stroke
			(width 0.05715)
			(type default)
		)
		(layer "In4.Cu")
	)
	(gr_line
		(start 82.029554 -27.98191)
		(end 82.240374 -27.77109)
		(stroke
			(width 0.05715)
			(type default)
		)
		(layer "In4.Cu")
	)
	(gr_line
		(start 82.042 -15.621)
		(end 26.924 -15.621)
		(stroke
			(width 0.381)
			(type default)
		)
		(layer "In4.Cu")
	)
	(gr_line
		(start 82.263488 -29.943552)
		(end 82.328004 -30.008068)
		(stroke
			(width 0.0508)
			(type default)
		)
		(layer "In4.Cu")
	)
	(gr_line
		(start 82.265266 -29.654246)
		(end 82.401664 -29.654246)
		(stroke
			(width 0.0508)
			(type default)
		)
		(layer "In4.Cu")
	)
	(gr_line
		(start 82.401664 -29.654246)
		(end 82.61731 -29.869638)
		(stroke
			(width 0.0508)
			(type default)
		)
		(layer "In4.Cu")
	)
	(gr_line
		(start 82.61731 -29.869638)
		(end 82.61731 -30.00629)
		(stroke
			(width 0.0508)
			(type default)
		)
		(layer "In4.Cu")
	)
	(gr_line
		(start 83.058 -28.575)
		(end 83.077558 -28.594558)
		(stroke
			(width 0.0508)
			(type default)
		)
		(layer "In4.Cu")
	)
	(gr_line
		(start 83.058 -28.5496)
		(end 83.058 -28.575)
		(stroke
			(width 0.0508)
			(type default)
		)
		(layer "In4.Cu")
	)
	(gr_line
		(start 83.079336 -28.596336)
		(end 83.1215 -28.6385)
		(stroke
			(width 0.0508)
			(type default)
		)
		(layer "In4.Cu")
	)
	(gr_line
		(start 83.312 -14.351)
		(end 82.042 -15.621)
		(stroke
			(width 0.381)
			(type default)
		)
		(layer "In4.Cu")
	)
	(gr_line
		(start 83.3247 -28.6385)
		(end 83.366864 -28.596336)
		(stroke
			(width 0.0508)
			(type default)
		)
		(layer "In4.Cu")
	)
	(gr_line
		(start 83.368642 -28.594558)
		(end 83.3882 -28.575)
		(stroke
			(width 0.0508)
			(type default)
		)
		(layer "In4.Cu")
	)
	(gr_line
		(start 83.3882 -28.5496)
		(end 83.3882 -28.575)
		(stroke
			(width 0.0508)
			(type default)
		)
		(layer "In4.Cu")
	)
	(gr_line
		(start 83.419188 -30.861)
		(end 83.488784 -30.930596)
		(stroke
			(width 0.0508)
			(type default)
		)
		(layer "In4.Cu")
	)
	(gr_line
		(start 83.462368 -27.432254)
		(end 83.535774 -27.50566)
		(stroke
			(width 0.05715)
			(type default)
		)
		(layer "In4.Cu")
	)
	(gr_line
		(start 83.464146 -26.96337)
		(end 83.762342 -26.96337)
		(stroke
			(width 0.05715)
			(type default)
		)
		(layer "In4.Cu")
	)
	(gr_line
		(start 83.474052 -30.6578)
		(end 83.488784 -30.643068)
		(stroke
			(width 0.0508)
			(type default)
		)
		(layer "In4.Cu")
	)
	(gr_line
		(start 83.490562 -30.932374)
		(end 83.644232 -31.086044)
		(stroke
			(width 0.0508)
			(type default)
		)
		(layer "In4.Cu")
	)
	(gr_line
		(start 83.490562 -30.64129)
		(end 83.67141 -30.460442)
		(stroke
			(width 0.0508)
			(type default)
		)
		(layer "In4.Cu")
	)
	(gr_line
		(start 83.562952 -24.2824)
		(end 83.610196 -24.2824)
		(stroke
			(width 0.05715)
			(type default)
		)
		(layer "In4.Cu")
	)
	(gr_line
		(start 83.762342 -26.96337)
		(end 84.004658 -27.205686)
		(stroke
			(width 0.05715)
			(type default)
		)
		(layer "In4.Cu")
	)
	(gr_line
		(start 83.801204 -25.406604)
		(end 83.8454 -25.4508)
		(stroke
			(width 0.05715)
			(type default)
		)
		(layer "In4.Cu")
	)
	(gr_line
		(start 83.801204 -24.936196)
		(end 83.8454 -24.892)
		(stroke
			(width 0.05715)
			(type default)
		)
		(layer "In4.Cu")
	)
	(gr_line
		(start 83.893152 -24.09825)
		(end 83.940396 -24.09825)
		(stroke
			(width 0.05715)
			(type default)
		)
		(layer "In4.Cu")
	)
	(gr_line
		(start 84.004658 -27.205686)
		(end 84.004658 -27.503882)
		(stroke
			(width 0.05715)
			(type default)
		)
		(layer "In4.Cu")
	)
	(gr_line
		(start 84.506054 -30.3784)
		(end 84.557362 -30.429708)
		(stroke
			(width 0.0508)
			(type default)
		)
		(layer "In4.Cu")
	)
	(gr_line
		(start 84.524596 -30.1752)
		(end 84.557362 -30.142434)
		(stroke
			(width 0.0508)
			(type default)
		)
		(layer "In4.Cu")
	)
	(gr_line
		(start 84.55914 -30.431486)
		(end 84.734654 -30.607)
		(stroke
			(width 0.0508)
			(type default)
		)
		(layer "In4.Cu")
	)
	(gr_line
		(start 84.55914 -30.140656)
		(end 84.717636 -29.98216)
		(stroke
			(width 0.0508)
			(type default)
		)
		(layer "In4.Cu")
	)
	(gr_line
		(start 84.79917 -28.034996)
		(end 84.843112 -28.034996)
		(stroke
			(width 0.05715)
			(type default)
		)
		(layer "In4.Cu")
	)
	(gr_line
		(start 85.12937 -28.215844)
		(end 85.173312 -28.215844)
		(stroke
			(width 0.05715)
			(type default)
		)
		(layer "In4.Cu")
	)
	(gr_line
		(start 85.337904 -27.883104)
		(end 85.548724 -27.672284)
		(stroke
			(width 0.05715)
			(type default)
		)
		(layer "In4.Cu")
	)
	(gr_line
		(start 85.548724 -27.672284)
		(end 85.891624 -27.672284)
		(stroke
			(width 0.05715)
			(type default)
		)
		(layer "In4.Cu")
	)
	(gr_line
		(start 85.668104 -28.215844)
		(end 85.772244 -28.215844)
		(stroke
			(width 0.05715)
			(type default)
		)
		(layer "In4.Cu")
	)
	(gr_line
		(start 85.891624 -27.672284)
		(end 86.102444 -27.883104)
		(stroke
			(width 0.05715)
			(type default)
		)
		(layer "In4.Cu")
	)
	(gr_line
		(start 86.450424 -27.883104)
		(end 86.661244 -27.672284)
		(stroke
			(width 0.05715)
			(type default)
		)
		(layer "In4.Cu")
	)
	(gr_line
		(start 86.661244 -27.672284)
		(end 87.004144 -27.672284)
		(stroke
			(width 0.05715)
			(type default)
		)
		(layer "In4.Cu")
	)
	(gr_line
		(start 86.780624 -28.215844)
		(end 86.884764 -28.215844)
		(stroke
			(width 0.05715)
			(type default)
		)
		(layer "In4.Cu")
	)
	(gr_line
		(start 87.004144 -27.672284)
		(end 87.214964 -27.883104)
		(stroke
			(width 0.05715)
			(type default)
		)
		(layer "In4.Cu")
	)
	(gr_line
		(start 89.54389 -29.70911)
		(end 89.75471 -29.49829)
		(stroke
			(width 0.05715)
			(type default)
		)
		(layer "In4.Cu")
	)
	(gr_line
		(start 89.75471 -29.49829)
		(end 90.09761 -29.49829)
		(stroke
			(width 0.05715)
			(type default)
		)
		(layer "In4.Cu")
	)
	(gr_line
		(start 89.87409 -30.04185)
		(end 89.97823 -30.04185)
		(stroke
			(width 0.05715)
			(type default)
		)
		(layer "In4.Cu")
	)
	(gr_line
		(start 90.09761 -29.49829)
		(end 90.30843 -29.70911)
		(stroke
			(width 0.05715)
			(type default)
		)
		(layer "In4.Cu")
	)
	(gr_line
		(start 92.964 -14.351)
		(end 83.312 -14.351)
		(stroke
			(width 0.381)
			(type default)
		)
		(layer "In4.Cu")
	)
	(gr_line
		(start 93.218 -21.209)
		(end 94.488 -19.939)
		(stroke
			(width 0.381)
			(type default)
		)
		(layer "In4.Cu")
	)
	(gr_line
		(start 93.96349 -30.410912)
		(end 94.0054 -30.369002)
		(stroke
			(width 0.05715)
			(type default)
		)
		(layer "In4.Cu")
	)
	(gr_line
		(start 94.29369 -30.743652)
		(end 94.31655 -30.743652)
		(stroke
			(width 0.05715)
			(type default)
		)
		(layer "In4.Cu")
	)
	(gr_line
		(start 94.31655 -30.743652)
		(end 94.6658 -30.394402)
		(stroke
			(width 0.05715)
			(type default)
		)
		(layer "In4.Cu")
	)
	(gr_line
		(start 94.488 -19.939)
		(end 94.488 -16.764)
		(stroke
			(width 0.381)
			(type default)
		)
		(layer "In4.Cu")
	)
	(gr_line
		(start 94.488 -16.764)
		(end 94.488 -15.875)
		(stroke
			(width 0.381)
			(type default)
		)
		(layer "In4.Cu")
	)
	(gr_line
		(start 94.488 -15.875)
		(end 92.964 -14.351)
		(stroke
			(width 0.381)
			(type default)
		)
		(layer "In4.Cu")
	)
	(gr_line
		(start 96.4184 -33.6931)
		(end 96.4311 -33.6931)
		(stroke
			(width 0.0508)
			(type default)
		)
		(layer "In4.Cu")
	)
	(gr_line
		(start 96.4184 -33.3629)
		(end 96.444308 -33.388808)
		(stroke
			(width 0.0508)
			(type default)
		)
		(layer "In4.Cu")
	)
	(gr_line
		(start 96.4311 -33.6931)
		(end 96.444308 -33.679892)
		(stroke
			(width 0.0508)
			(type default)
		)
		(layer "In4.Cu")
	)
	(gr_line
		(start 96.446086 -33.678114)
		(end 96.4946 -33.6296)
		(stroke
			(width 0.0508)
			(type default)
		)
		(layer "In4.Cu")
	)
	(gr_line
		(start 96.446086 -33.390586)
		(end 96.4819 -33.4264)
		(stroke
			(width 0.0508)
			(type default)
		)
		(layer "In4.Cu")
	)
	(gr_line
		(start 97.6884 -47.278798)
		(end 97.882202 -47.4726)
		(stroke
			(width 0.0508)
			(type default)
		)
		(layer "In4.Cu")
	)
	(gr_line
		(start 97.6884 -47.2694)
		(end 97.6884 -47.278798)
		(stroke
			(width 0.0508)
			(type default)
		)
		(layer "In4.Cu")
	)
	(gr_line
		(start 97.715832 -47.98314)
		(end 98.020632 -47.67834)
		(stroke
			(width 0.0508)
			(type default)
		)
		(layer "In4.Cu")
	)
	(gr_line
		(start 97.922842 -30.997144)
		(end 97.922842 -31.123128)
		(stroke
			(width 0.0508)
			(type default)
		)
		(layer "In4.Cu")
	)
	(gr_line
		(start 97.922842 -30.997144)
		(end 98.270568 -30.649418)
		(stroke
			(width 0.0508)
			(type default)
		)
		(layer "In4.Cu")
	)
	(gr_line
		(start 97.973134 -30.360112)
		(end 98.26879 -30.360112)
		(stroke
			(width 0.0508)
			(type default)
		)
		(layer "In4.Cu")
	)
	(gr_line
		(start 99.0854 -56.4134)
		(end 99.5299 -56.8579)
		(stroke
			(width 0.0508)
			(type default)
		)
		(layer "In4.Cu")
	)
	(gr_line
		(start 99.0854 -54.7878)
		(end 99.0854 -56.4134)
		(stroke
			(width 0.0508)
			(type default)
		)
		(layer "In4.Cu")
	)
	(gr_line
		(start 99.0854 -54.7878)
		(end 99.5934 -54.2798)
		(stroke
			(width 0.0508)
			(type default)
		)
		(layer "In4.Cu")
	)
	(gr_line
		(start 99.313492 -49.96942)
		(end 99.457002 -50.11293)
		(stroke
			(width 0.0508)
			(type default)
		)
		(layer "In4.Cu")
	)
	(gr_line
		(start 99.457002 -50.11293)
		(end 99.457002 -50.167286)
		(stroke
			(width 0.0508)
			(type default)
		)
		(layer "In4.Cu")
	)
	(gr_line
		(start 99.5553 -56.437276)
		(end 99.8093 -56.691276)
		(stroke
			(width 0.0508)
			(type default)
		)
		(layer "In4.Cu")
	)
	(gr_line
		(start 99.5553 -56.0832)
		(end 99.5553 -56.437276)
		(stroke
			(width 0.0508)
			(type default)
		)
		(layer "In4.Cu")
	)
	(gr_line
		(start 99.601274 -49.969674)
		(end 99.654614 -49.969674)
		(stroke
			(width 0.0508)
			(type default)
		)
		(layer "In4.Cu")
	)
	(gr_line
		(start 99.654614 -49.969674)
		(end 99.798124 -50.113184)
		(stroke
			(width 0.0762)
			(type default)
		)
		(layer "In4.Cu")
	)
	(gr_line
		(start 100.296726 -59.225434)
		(end 100.620068 -59.548776)
		(stroke
			(width 0.0762)
			(type default)
		)
		(layer "In4.Cu")
	)
	(gr_line
		(start 100.296726 -59.052968)
		(end 100.296726 -59.225434)
		(stroke
			(width 0.0762)
			(type default)
		)
		(layer "In4.Cu")
	)
	(gr_line
		(start 100.51669 -24.18969)
		(end 100.8634 -24.5364)
		(stroke
			(width 0.0508)
			(type default)
		)
		(layer "In4.Cu")
	)
	(gr_line
		(start 100.51669 -22.65934)
		(end 100.51669 -24.18969)
		(stroke
			(width 0.0508)
			(type default)
		)
		(layer "In4.Cu")
	)
	(gr_line
		(start 100.620068 -59.548776)
		(end 100.792534 -59.548776)
		(stroke
			(width 0.0762)
			(type default)
		)
		(layer "In4.Cu")
	)
	(gr_line
		(start 100.693728 -59.05119)
		(end 100.794312 -59.151774)
		(stroke
			(width 0.0762)
			(type default)
		)
		(layer "In4.Cu")
	)
	(gr_line
		(start 100.72243 -22.45614)
		(end 100.9142 -22.64791)
		(stroke
			(width 0.0508)
			(type default)
		)
		(layer "In4.Cu")
	)
	(gr_line
		(start 100.9142 -22.64791)
		(end 100.9142 -22.648672)
		(stroke
			(width 0.0508)
			(type default)
		)
		(layer "In4.Cu")
	)
	(gr_line
		(start 101.119432 -60.04814)
		(end 101.44252 -60.371228)
		(stroke
			(width 0.0762)
			(type default)
		)
		(layer "In4.Cu")
	)
	(gr_line
		(start 101.119432 -59.875674)
		(end 101.119432 -60.04814)
		(stroke
			(width 0.0762)
			(type default)
		)
		(layer "In4.Cu")
	)
	(gr_line
		(start 101.44252 -60.371228)
		(end 101.614986 -60.371228)
		(stroke
			(width 0.0762)
			(type default)
		)
		(layer "In4.Cu")
	)
	(gr_line
		(start 101.516434 -59.873896)
		(end 101.616764 -59.974226)
		(stroke
			(width 0.0762)
			(type default)
		)
		(layer "In4.Cu")
	)
	(gr_line
		(start 101.941884 -60.870592)
		(end 102.265226 -61.193934)
		(stroke
			(width 0.0762)
			(type default)
		)
		(layer "In4.Cu")
	)
	(gr_line
		(start 101.941884 -60.698126)
		(end 101.941884 -60.870592)
		(stroke
			(width 0.0762)
			(type default)
		)
		(layer "In4.Cu")
	)
	(gr_line
		(start 102.265226 -61.193934)
		(end 102.437692 -61.193934)
		(stroke
			(width 0.0762)
			(type default)
		)
		(layer "In4.Cu")
	)
	(gr_line
		(start 102.338886 -60.696348)
		(end 102.43947 -60.796932)
		(stroke
			(width 0.0762)
			(type default)
		)
		(layer "In4.Cu")
	)
	(gr_line
		(start 103.496364 -63.410592)
		(end 103.618284 -63.532512)
		(stroke
			(width 0.0762)
			(type default)
		)
		(layer "In4.Cu")
	)
	(gr_line
		(start 103.496364 -62.953392)
		(end 103.496364 -63.410592)
		(stroke
			(width 0.0762)
			(type default)
		)
		(layer "In4.Cu")
	)
	(gr_line
		(start 103.496364 -62.953392)
		(end 103.618284 -62.831472)
		(stroke
			(width 0.0762)
			(type default)
		)
		(layer "In4.Cu")
	)
	(gr_line
		(start 103.900224 -63.110872)
		(end 103.900224 -63.253112)
		(stroke
			(width 0.0762)
			(type default)
		)
		(layer "In4.Cu")
	)
	(gr_line
		(start 104.151684 -17.5006)
		(end 104.3432 -17.5006)
		(stroke
			(width 0.0508)
			(type default)
		)
		(layer "In4.Cu")
	)
	(gr_line
		(start 104.25176 -32.657288)
		(end 104.25176 -32.718248)
		(stroke
			(width 0.0508)
			(type default)
		)
		(layer "In4.Cu")
	)
	(gr_line
		(start 104.316276 -30.905196)
		(end 104.3178 -30.903672)
		(stroke
			(width 0.0508)
			(type default)
		)
		(layer "In4.Cu")
	)
	(gr_line
		(start 104.397048 -32.454088)
		(end 104.397048 -32.515048)
		(stroke
			(width 0.0508)
			(type default)
		)
		(layer "In4.Cu")
	)
	(gr_line
		(start 104.521 -30.822646)
		(end 104.522524 -30.821122)
		(stroke
			(width 0.0508)
			(type default)
		)
		(layer "In4.Cu")
	)
	(gr_line
		(start 104.948736 -27.119072)
		(end 104.98582 -27.081988)
		(stroke
			(width 0.0508)
			(type default)
		)
		(layer "In4.Cu")
	)
	(gr_line
		(start 105.426764 -64.87414)
		(end 105.548684 -64.99606)
		(stroke
			(width 0.0762)
			(type default)
		)
		(layer "In4.Cu")
	)
	(gr_line
		(start 105.548684 -64.99606)
		(end 106.005884 -64.99606)
		(stroke
			(width 0.0762)
			(type default)
		)
		(layer "In4.Cu")
	)
	(gr_line
		(start 105.599484 -30.85973)
		(end 105.648506 -30.908752)
		(stroke
			(width 0.0508)
			(type default)
		)
		(layer "In4.Cu")
	)
	(gr_line
		(start 105.6132 -30.65653)
		(end 105.648506 -30.621224)
		(stroke
			(width 0.0508)
			(type default)
		)
		(layer "In4.Cu")
	)
	(gr_line
		(start 105.650284 -30.91053)
		(end 105.880154 -31.1404)
		(stroke
			(width 0.0508)
			(type default)
		)
		(layer "In4.Cu")
	)
	(gr_line
		(start 105.650284 -30.619446)
		(end 105.893616 -30.376114)
		(stroke
			(width 0.0508)
			(type default)
		)
		(layer "In4.Cu")
	)
	(gr_line
		(start 105.706164 -64.5922)
		(end 105.848404 -64.5922)
		(stroke
			(width 0.0762)
			(type default)
		)
		(layer "In4.Cu")
	)
	(gr_line
		(start 105.835958 -25.945084)
		(end 105.873042 -25.908)
		(stroke
			(width 0.0508)
			(type default)
		)
		(layer "In4.Cu")
	)
	(gr_line
		(start 106.005884 -64.99606)
		(end 106.127804 -64.87414)
		(stroke
			(width 0.0762)
			(type default)
		)
		(layer "In4.Cu")
	)
	(gr_line
		(start 106.590084 -64.87414)
		(end 106.712004 -64.99606)
		(stroke
			(width 0.0762)
			(type default)
		)
		(layer "In4.Cu")
	)
	(gr_line
		(start 106.712004 -64.99606)
		(end 107.169204 -64.99606)
		(stroke
			(width 0.0762)
			(type default)
		)
		(layer "In4.Cu")
	)
	(gr_line
		(start 106.869484 -64.5922)
		(end 107.011724 -64.5922)
		(stroke
			(width 0.0762)
			(type default)
		)
		(layer "In4.Cu")
	)
	(gr_line
		(start 106.908092 -25.82418)
		(end 107.033822 -25.69845)
		(stroke
			(width 0.0508)
			(type default)
		)
		(layer "In4.Cu")
	)
	(gr_line
		(start 106.914188 -45.241718)
		(end 107.010454 -45.241718)
		(stroke
			(width 0.0508)
			(type default)
		)
		(layer "In4.Cu")
	)
	(gr_line
		(start 106.919268 -33.356296)
		(end 107.0356 -33.356296)
		(stroke
			(width 0.0508)
			(type default)
		)
		(layer "In4.Cu")
	)
	(gr_line
		(start 107.010454 -45.241718)
		(end 107.133136 -45.3644)
		(stroke
			(width 0.0508)
			(type default)
		)
		(layer "In4.Cu")
	)
	(gr_line
		(start 107.033822 -25.644094)
		(end 107.033822 -25.69845)
		(stroke
			(width 0.0508)
			(type default)
		)
		(layer "In4.Cu")
	)
	(gr_line
		(start 107.033822 -25.644094)
		(end 107.051602 -25.626314)
		(stroke
			(width 0.0508)
			(type default)
		)
		(layer "In4.Cu")
	)
	(gr_line
		(start 107.0356 -33.356296)
		(end 107.185206 -33.20669)
		(stroke
			(width 0.0508)
			(type default)
		)
		(layer "In4.Cu")
	)
	(gr_line
		(start 107.110276 -45.662596)
		(end 107.133136 -45.639736)
		(stroke
			(width 0.0508)
			(type default)
		)
		(layer "In4.Cu")
	)
	(gr_line
		(start 107.133136 -45.3644)
		(end 107.133136 -45.395388)
		(stroke
			(width 0.0508)
			(type default)
		)
		(layer "In4.Cu")
	)
	(gr_line
		(start 107.169204 -64.99606)
		(end 107.291124 -64.87414)
		(stroke
			(width 0.0762)
			(type default)
		)
		(layer "In4.Cu")
	)
	(gr_line
		(start 107.178094 -25.841706)
		(end 107.231434 -25.841706)
		(stroke
			(width 0.0508)
			(type default)
		)
		(layer "In4.Cu")
	)
	(gr_line
		(start 107.179872 -33.0454)
		(end 107.188 -33.053528)
		(stroke
			(width 0.0508)
			(type default)
		)
		(layer "In4.Cu")
	)
	(gr_line
		(start 107.186984 -33.204912)
		(end 107.188 -33.203896)
		(stroke
			(width 0.0508)
			(type default)
		)
		(layer "In4.Cu")
	)
	(gr_line
		(start 107.231434 -25.841706)
		(end 107.249214 -25.823926)
		(stroke
			(width 0.0508)
			(type default)
		)
		(layer "In4.Cu")
	)
	(gr_line
		(start 107.249214 -25.823926)
		(end 107.374944 -25.698196)
		(stroke
			(width 0.0762)
			(type default)
		)
		(layer "In4.Cu")
	)
	(gr_line
		(start 107.336336 -45.601128)
		(end 107.359196 -45.578268)
		(stroke
			(width 0.0508)
			(type default)
		)
		(layer "In4.Cu")
	)
	(gr_line
		(start 107.360974 -45.57649)
		(end 107.655868 -45.281596)
		(stroke
			(width 0.0508)
			(type default)
		)
		(layer "In4.Cu")
	)
	(gr_line
		(start 107.3912 -33.1216)
		(end 107.474512 -33.204912)
		(stroke
			(width 0.0508)
			(type default)
		)
		(layer "In4.Cu")
	)
	(gr_line
		(start 107.47629 -33.20669)
		(end 107.6706 -33.401)
		(stroke
			(width 0.0508)
			(type default)
		)
		(layer "In4.Cu")
	)
	(gr_line
		(start 108.772452 -42.598086)
		(end 108.7755 -42.598086)
		(stroke
			(width 0.0508)
			(type default)
		)
		(layer "In4.Cu")
	)
	(gr_line
		(start 108.7755 -42.598086)
		(end 109.083856 -42.906442)
		(stroke
			(width 0.0508)
			(type default)
		)
		(layer "In4.Cu")
	)
	(gr_line
		(start 108.821474 -43.247056)
		(end 108.956348 -43.112182)
		(stroke
			(width 0.0508)
			(type default)
		)
		(layer "In4.Cu")
	)
	(gr_line
		(start 109.5756 -43.112182)
		(end 109.626654 -43.112182)
		(stroke
			(width 0.0508)
			(type default)
		)
		(layer "In4.Cu")
	)
	(gr_line
		(start 109.7788 -42.9768)
		(end 109.829854 -42.9768)
		(stroke
			(width 0.0508)
			(type default)
		)
		(layer "In4.Cu")
	)
	(gr_line
		(start 110.781338 -47.662338)
		(end 110.873286 -47.754286)
		(stroke
			(width 0.0508)
			(type default)
		)
		(layer "In4.Cu")
	)
	(gr_line
		(start 110.873286 -47.808642)
		(end 110.891066 -47.826422)
		(stroke
			(width 0.0508)
			(type default)
		)
		(layer "In4.Cu")
	)
	(gr_line
		(start 110.873286 -47.754286)
		(end 110.873286 -47.808642)
		(stroke
			(width 0.0508)
			(type default)
		)
		(layer "In4.Cu")
	)
	(gr_line
		(start 111.017558 -47.61103)
		(end 111.070898 -47.61103)
		(stroke
			(width 0.0508)
			(type default)
		)
		(layer "In4.Cu")
	)
	(gr_line
		(start 111.070898 -47.61103)
		(end 111.088678 -47.62881)
		(stroke
			(width 0.0508)
			(type default)
		)
		(layer "In4.Cu")
	)
	(gr_line
		(start 111.088678 -47.62881)
		(end 111.214408 -47.75454)
		(stroke
			(width 0.0762)
			(type default)
		)
		(layer "In4.Cu")
	)
	(gr_line
		(start 111.5187 -27.982926)
		(end 111.717074 -27.982926)
		(stroke
			(width 0.0508)
			(type default)
		)
		(layer "In4.Cu")
	)
	(gr_line
		(start 111.717074 -27.982926)
		(end 111.76 -27.94)
		(stroke
			(width 0.0508)
			(type default)
		)
		(layer "In4.Cu")
	)
	(gr_line
		(start 111.726726 -28.186126)
		(end 111.76 -28.2194)
		(stroke
			(width 0.0508)
			(type default)
		)
		(layer "In4.Cu")
	)
	(gr_line
		(start 111.76 -28.2194)
		(end 111.958374 -28.2194)
		(stroke
			(width 0.0762)
			(type default)
		)
		(layer "In4.Cu")
	)
	(gr_line
		(start 111.8743 -49.250346)
		(end 111.8743 -49.286922)
		(stroke
			(width 0.0762)
			(type default)
		)
		(layer "In4.Cu")
	)
	(gr_line
		(start 112.0267 -48.970946)
		(end 112.0267 -49.007522)
		(stroke
			(width 0.0762)
			(type default)
		)
		(layer "In4.Cu")
	)
	(gr_line
		(start 116.48694 -13.48994)
		(end 116.6114 -13.6144)
		(stroke
			(width 0.0762)
			(type default)
		)
		(layer "In4.Cu")
	)
	(gr_line
		(start 116.6114 -13.6144)
		(end 117.0686 -13.6144)
		(stroke
			(width 0.0762)
			(type default)
		)
		(layer "In4.Cu")
	)
	(gr_line
		(start 116.76634 -13.208)
		(end 116.91366 -13.208)
		(stroke
			(width 0.0762)
			(type default)
		)
		(layer "In4.Cu")
	)
	(gr_line
		(start 117.0686 -13.6144)
		(end 117.19306 -13.48994)
		(stroke
			(width 0.0762)
			(type default)
		)
		(layer "In4.Cu")
	)
	(gr_line
		(start 117.658388 -13.48994)
		(end 117.780308 -13.61186)
		(stroke
			(width 0.0762)
			(type default)
		)
		(layer "In4.Cu")
	)
	(gr_line
		(start 117.780308 -13.61186)
		(end 118.237508 -13.61186)
		(stroke
			(width 0.0762)
			(type default)
		)
		(layer "In4.Cu")
	)
	(gr_line
		(start 117.937788 -13.208)
		(end 118.080028 -13.208)
		(stroke
			(width 0.0762)
			(type default)
		)
		(layer "In4.Cu")
	)
	(gr_line
		(start 118.059962 -42.069258)
		(end 118.145814 -42.15511)
		(stroke
			(width 0.0508)
			(type default)
		)
		(layer "In4.Cu")
	)
	(gr_line
		(start 118.086886 -42.38371)
		(end 118.172738 -42.469562)
		(stroke
			(width 0.0762)
			(type default)
		)
		(layer "In4.Cu")
	)
	(gr_line
		(start 118.145814 -42.15511)
		(end 118.164102 -42.15511)
		(stroke
			(width 0.0508)
			(type default)
		)
		(layer "In4.Cu")
	)
	(gr_line
		(start 118.171722 -42.15511)
		(end 118.25351 -42.15511)
		(stroke
			(width 0.0508)
			(type default)
		)
		(layer "In4.Cu")
	)
	(gr_line
		(start 118.237508 -13.61186)
		(end 118.359428 -13.48994)
		(stroke
			(width 0.0762)
			(type default)
		)
		(layer "In4.Cu")
	)
	(gr_line
		(start 118.821708 -13.48994)
		(end 118.943628 -13.61186)
		(stroke
			(width 0.0762)
			(type default)
		)
		(layer "In4.Cu")
	)
	(gr_line
		(start 118.943628 -13.61186)
		(end 119.400828 -13.61186)
		(stroke
			(width 0.0762)
			(type default)
		)
		(layer "In4.Cu")
	)
	(gr_line
		(start 119.101108 -13.208)
		(end 119.243348 -13.208)
		(stroke
			(width 0.0762)
			(type default)
		)
		(layer "In4.Cu")
	)
	(gr_line
		(start 119.400828 -13.61186)
		(end 119.522748 -13.48994)
		(stroke
			(width 0.0762)
			(type default)
		)
		(layer "In4.Cu")
	)
	(gr_line
		(start 119.985028 -13.48994)
		(end 120.106948 -13.61186)
		(stroke
			(width 0.0762)
			(type default)
		)
		(layer "In4.Cu")
	)
	(gr_line
		(start 120.106948 -13.61186)
		(end 120.564148 -13.61186)
		(stroke
			(width 0.0762)
			(type default)
		)
		(layer "In4.Cu")
	)
	(gr_line
		(start 120.264428 -13.208)
		(end 120.406668 -13.208)
		(stroke
			(width 0.0762)
			(type default)
		)
		(layer "In4.Cu")
	)
	(gr_line
		(start 120.564148 -13.61186)
		(end 120.686068 -13.48994)
		(stroke
			(width 0.0762)
			(type default)
		)
		(layer "In4.Cu")
	)
	(gr_line
		(start 121.985278 -62.56274)
		(end 122.107198 -62.68466)
		(stroke
			(width 0.0762)
			(type default)
		)
		(layer "In4.Cu")
	)
	(gr_line
		(start 122.107198 -62.68466)
		(end 122.564398 -62.68466)
		(stroke
			(width 0.0762)
			(type default)
		)
		(layer "In4.Cu")
	)
	(gr_line
		(start 122.264678 -62.2808)
		(end 122.406918 -62.2808)
		(stroke
			(width 0.0762)
			(type default)
		)
		(layer "In4.Cu")
	)
	(gr_line
		(start 122.46737 -13.48994)
		(end 122.58929 -13.61186)
		(stroke
			(width 0.0762)
			(type default)
		)
		(layer "In4.Cu")
	)
	(gr_line
		(start 122.564398 -62.68466)
		(end 122.686318 -62.56274)
		(stroke
			(width 0.0762)
			(type default)
		)
		(layer "In4.Cu")
	)
	(gr_line
		(start 122.58929 -13.61186)
		(end 123.04649 -13.61186)
		(stroke
			(width 0.0762)
			(type default)
		)
		(layer "In4.Cu")
	)
	(gr_line
		(start 122.74677 -13.208)
		(end 122.88901 -13.208)
		(stroke
			(width 0.0762)
			(type default)
		)
		(layer "In4.Cu")
	)
	(gr_line
		(start 123.04649 -13.61186)
		(end 123.16841 -13.48994)
		(stroke
			(width 0.0762)
			(type default)
		)
		(layer "In4.Cu")
	)
	(gr_line
		(start 123.148598 -62.56274)
		(end 123.270518 -62.68466)
		(stroke
			(width 0.0762)
			(type default)
		)
		(layer "In4.Cu")
	)
	(gr_line
		(start 123.270518 -62.68466)
		(end 123.727718 -62.68466)
		(stroke
			(width 0.0762)
			(type default)
		)
		(layer "In4.Cu")
	)
	(gr_line
		(start 123.427998 -62.2808)
		(end 123.570238 -62.2808)
		(stroke
			(width 0.0762)
			(type default)
		)
		(layer "In4.Cu")
	)
	(gr_line
		(start 123.63069 -13.48994)
		(end 123.75261 -13.61186)
		(stroke
			(width 0.0762)
			(type default)
		)
		(layer "In4.Cu")
	)
	(gr_line
		(start 123.727718 -62.68466)
		(end 123.849638 -62.56274)
		(stroke
			(width 0.0762)
			(type default)
		)
		(layer "In4.Cu")
	)
	(gr_line
		(start 123.75261 -13.61186)
		(end 124.20981 -13.61186)
		(stroke
			(width 0.0762)
			(type default)
		)
		(layer "In4.Cu")
	)
	(gr_line
		(start 123.91009 -13.208)
		(end 124.05233 -13.208)
		(stroke
			(width 0.0762)
			(type default)
		)
		(layer "In4.Cu")
	)
	(gr_line
		(start 124.20981 -13.61186)
		(end 124.33173 -13.48994)
		(stroke
			(width 0.0762)
			(type default)
		)
		(layer "In4.Cu")
	)
	(gr_line
		(start 124.457206 -62.56274)
		(end 124.579126 -62.68466)
		(stroke
			(width 0.0762)
			(type default)
		)
		(layer "In4.Cu")
	)
	(gr_line
		(start 124.473462 -20.54606)
		(end 124.595382 -20.42414)
		(stroke
			(width 0.0762)
			(type default)
		)
		(layer "In4.Cu")
	)
	(gr_line
		(start 124.579126 -62.68466)
		(end 125.036326 -62.68466)
		(stroke
			(width 0.0762)
			(type default)
		)
		(layer "In4.Cu")
	)
	(gr_line
		(start 124.595382 -20.42414)
		(end 125.052582 -20.42414)
		(stroke
			(width 0.0762)
			(type default)
		)
		(layer "In4.Cu")
	)
	(gr_line
		(start 124.736606 -62.2808)
		(end 124.878846 -62.2808)
		(stroke
			(width 0.0762)
			(type default)
		)
		(layer "In4.Cu")
	)
	(gr_line
		(start 124.752862 -20.828)
		(end 124.895102 -20.828)
		(stroke
			(width 0.0762)
			(type default)
		)
		(layer "In4.Cu")
	)
	(gr_line
		(start 124.79401 -13.48994)
		(end 124.91593 -13.61186)
		(stroke
			(width 0.0762)
			(type default)
		)
		(layer "In4.Cu")
	)
	(gr_line
		(start 124.91593 -13.61186)
		(end 125.37313 -13.61186)
		(stroke
			(width 0.0762)
			(type default)
		)
		(layer "In4.Cu")
	)
	(gr_line
		(start 125.036326 -62.68466)
		(end 125.158246 -62.56274)
		(stroke
			(width 0.0762)
			(type default)
		)
		(layer "In4.Cu")
	)
	(gr_line
		(start 125.052582 -20.42414)
		(end 125.174502 -20.54606)
		(stroke
			(width 0.0762)
			(type default)
		)
		(layer "In4.Cu")
	)
	(gr_line
		(start 125.07341 -13.208)
		(end 125.21565 -13.208)
		(stroke
			(width 0.0762)
			(type default)
		)
		(layer "In4.Cu")
	)
	(gr_line
		(start 125.37313 -13.61186)
		(end 125.49505 -13.48994)
		(stroke
			(width 0.0762)
			(type default)
		)
		(layer "In4.Cu")
	)
	(gr_line
		(start 125.68682 -20.54606)
		(end 125.80874 -20.42414)
		(stroke
			(width 0.0762)
			(type default)
		)
		(layer "In4.Cu")
	)
	(gr_line
		(start 125.80874 -20.42414)
		(end 126.26594 -20.42414)
		(stroke
			(width 0.0762)
			(type default)
		)
		(layer "In4.Cu")
	)
	(gr_line
		(start 125.96622 -20.828)
		(end 126.10846 -20.828)
		(stroke
			(width 0.0762)
			(type default)
		)
		(layer "In4.Cu")
	)
	(gr_line
		(start 126.26594 -20.42414)
		(end 126.38786 -20.54606)
		(stroke
			(width 0.0762)
			(type default)
		)
		(layer "In4.Cu")
	)
	(gr_line
		(start 126.85014 -20.54606)
		(end 126.97206 -20.42414)
		(stroke
			(width 0.0762)
			(type default)
		)
		(layer "In4.Cu")
	)
	(gr_line
		(start 126.97206 -20.42414)
		(end 127.42926 -20.42414)
		(stroke
			(width 0.0762)
			(type default)
		)
		(layer "In4.Cu")
	)
	(gr_line
		(start 127.12954 -20.828)
		(end 127.27178 -20.828)
		(stroke
			(width 0.0762)
			(type default)
		)
		(layer "In4.Cu")
	)
	(gr_line
		(start 127.42926 -20.42414)
		(end 127.55118 -20.54606)
		(stroke
			(width 0.0762)
			(type default)
		)
		(layer "In4.Cu")
	)
	(gr_line
		(start 127.855472 -13.48994)
		(end 127.977392 -13.61186)
		(stroke
			(width 0.0762)
			(type default)
		)
		(layer "In4.Cu")
	)
	(gr_line
		(start 127.977392 -13.61186)
		(end 128.434592 -13.61186)
		(stroke
			(width 0.0762)
			(type default)
		)
		(layer "In4.Cu")
	)
	(gr_line
		(start 128.01346 -20.54606)
		(end 128.13538 -20.42414)
		(stroke
			(width 0.0762)
			(type default)
		)
		(layer "In4.Cu")
	)
	(gr_line
		(start 128.134872 -13.208)
		(end 128.277112 -13.208)
		(stroke
			(width 0.0762)
			(type default)
		)
		(layer "In4.Cu")
	)
	(gr_line
		(start 128.13538 -20.42414)
		(end 128.59258 -20.42414)
		(stroke
			(width 0.0762)
			(type default)
		)
		(layer "In4.Cu")
	)
	(gr_line
		(start 128.29286 -20.828)
		(end 128.4351 -20.828)
		(stroke
			(width 0.0762)
			(type default)
		)
		(layer "In4.Cu")
	)
	(gr_line
		(start 128.434592 -13.61186)
		(end 128.556512 -13.48994)
		(stroke
			(width 0.0762)
			(type default)
		)
		(layer "In4.Cu")
	)
	(gr_line
		(start 128.59258 -20.42414)
		(end 128.7145 -20.54606)
		(stroke
			(width 0.0762)
			(type default)
		)
		(layer "In4.Cu")
	)
	(gr_line
		(start 129.018792 -13.48994)
		(end 129.140712 -13.61186)
		(stroke
			(width 0.0762)
			(type default)
		)
		(layer "In4.Cu")
	)
	(gr_line
		(start 129.140712 -13.61186)
		(end 129.597912 -13.61186)
		(stroke
			(width 0.0762)
			(type default)
		)
		(layer "In4.Cu")
	)
	(gr_line
		(start 129.298192 -13.208)
		(end 129.440432 -13.208)
		(stroke
			(width 0.0762)
			(type default)
		)
		(layer "In4.Cu")
	)
	(gr_line
		(start 129.597912 -13.61186)
		(end 129.719832 -13.48994)
		(stroke
			(width 0.0762)
			(type default)
		)
		(layer "In4.Cu")
	)
	(gr_line
		(start 130.182112 -13.48994)
		(end 130.304032 -13.61186)
		(stroke
			(width 0.0762)
			(type default)
		)
		(layer "In4.Cu")
	)
	(gr_line
		(start 130.19278 -20.54606)
		(end 130.3147 -20.42414)
		(stroke
			(width 0.0762)
			(type default)
		)
		(layer "In4.Cu")
	)
	(gr_line
		(start 130.304032 -13.61186)
		(end 130.761232 -13.61186)
		(stroke
			(width 0.0762)
			(type default)
		)
		(layer "In4.Cu")
	)
	(gr_line
		(start 130.3147 -20.42414)
		(end 130.7719 -20.42414)
		(stroke
			(width 0.0762)
			(type default)
		)
		(layer "In4.Cu")
	)
	(gr_line
		(start 130.461512 -13.208)
		(end 130.603752 -13.208)
		(stroke
			(width 0.0762)
			(type default)
		)
		(layer "In4.Cu")
	)
	(gr_line
		(start 130.47218 -20.828)
		(end 130.61442 -20.828)
		(stroke
			(width 0.0762)
			(type default)
		)
		(layer "In4.Cu")
	)
	(gr_line
		(start 130.761232 -13.61186)
		(end 130.883152 -13.48994)
		(stroke
			(width 0.0762)
			(type default)
		)
		(layer "In4.Cu")
	)
	(gr_line
		(start 130.7719 -20.42414)
		(end 130.89382 -20.54606)
		(stroke
			(width 0.0762)
			(type default)
		)
		(layer "In4.Cu")
	)
	(gr_line
		(start 131.3561 -20.54606)
		(end 131.47802 -20.42414)
		(stroke
			(width 0.0762)
			(type default)
		)
		(layer "In4.Cu")
	)
	(gr_line
		(start 131.47802 -20.42414)
		(end 131.93522 -20.42414)
		(stroke
			(width 0.0762)
			(type default)
		)
		(layer "In4.Cu")
	)
	(gr_line
		(start 131.6355 -20.828)
		(end 131.77774 -20.828)
		(stroke
			(width 0.0762)
			(type default)
		)
		(layer "In4.Cu")
	)
	(gr_line
		(start 131.93522 -20.42414)
		(end 132.05714 -20.54606)
		(stroke
			(width 0.0762)
			(type default)
		)
		(layer "In4.Cu")
	)
	(gr_line
		(start 132.51942 -20.54606)
		(end 132.64134 -20.42414)
		(stroke
			(width 0.0762)
			(type default)
		)
		(layer "In4.Cu")
	)
	(gr_line
		(start 132.64134 -20.42414)
		(end 133.09854 -20.42414)
		(stroke
			(width 0.0762)
			(type default)
		)
		(layer "In4.Cu")
	)
	(gr_line
		(start 132.79882 -20.828)
		(end 132.94106 -20.828)
		(stroke
			(width 0.0762)
			(type default)
		)
		(layer "In4.Cu")
	)
	(gr_line
		(start 133.09854 -20.42414)
		(end 133.22046 -20.54606)
		(stroke
			(width 0.0762)
			(type default)
		)
		(layer "In4.Cu")
	)
	(gr_line
		(start 136.032748 -66.672206)
		(end 136.31926 -66.385694)
		(stroke
			(width 0.0762)
			(type default)
		)
		(layer "In4.Cu")
	)
	(gr_line
		(start 136.602724 -66.408046)
		(end 136.867138 -66.672206)
		(stroke
			(width 0.0762)
			(type default)
		)
		(layer "In4.Cu")
	)
	(gr_line
		(start 140.83284 -5.818378)
		(end 141.0462 -5.818378)
		(stroke
			(width 0.0762)
			(type default)
		)
		(layer "In4.Cu")
	)
	(gr_line
		(start 141.0462 -5.818378)
		(end 141.13891 -5.911088)
		(stroke
			(width 0.0762)
			(type default)
		)
		(layer "In4.Cu")
	)
	(gr_line
		(start 141.53769 -5.911088)
		(end 141.6304 -5.818378)
		(stroke
			(width 0.0762)
			(type default)
		)
		(layer "In4.Cu")
	)
	(gr_line
		(start 141.6304 -5.818378)
		(end 141.66723 -5.818378)
		(stroke
			(width 0.0762)
			(type default)
		)
		(layer "In4.Cu")
	)
	(gr_line
		(start 142.696946 -60.4266)
		(end 142.6972 -60.4266)
		(stroke
			(width 0.0762)
			(type default)
		)
		(layer "In4.Cu")
	)
	(gr_line
		(start 142.940024 -60.2742)
		(end 142.9766 -60.2742)
		(stroke
			(width 0.0762)
			(type default)
		)
		(layer "In4.Cu")
	)
	(gr_line
		(start 144.720056 -60.734702)
		(end 145.043398 -61.058044)
		(stroke
			(width 0.0762)
			(type default)
		)
		(layer "In4.Cu")
	)
	(gr_line
		(start 144.720056 -60.562236)
		(end 144.720056 -60.734702)
		(stroke
			(width 0.0762)
			(type default)
		)
		(layer "In4.Cu")
	)
	(gr_line
		(start 145.043398 -61.058044)
		(end 145.215864 -61.058044)
		(stroke
			(width 0.0762)
			(type default)
		)
		(layer "In4.Cu")
	)
	(gr_line
		(start 145.117058 -60.560458)
		(end 145.217642 -60.661042)
		(stroke
			(width 0.0762)
			(type default)
		)
		(layer "In4.Cu")
	)
	(gr_line
		(start 145.5166 -62.7888)
		(end 145.641822 -62.914022)
		(stroke
			(width 0.0762)
			(type default)
		)
		(layer "In4.Cu")
	)
	(gr_line
		(start 145.5166 -62.357762)
		(end 145.5166 -62.7888)
		(stroke
			(width 0.0762)
			(type default)
		)
		(layer "In4.Cu")
	)
	(gr_line
		(start 145.5166 -62.357762)
		(end 145.641822 -62.23254)
		(stroke
			(width 0.0762)
			(type default)
		)
		(layer "In4.Cu")
	)
	(gr_line
		(start 145.632678 -66.672206)
		(end 145.85061 -66.454274)
		(stroke
			(width 0.0762)
			(type default)
		)
		(layer "In4.Cu")
	)
	(gr_line
		(start 145.923762 -62.51194)
		(end 145.923762 -62.634622)
		(stroke
			(width 0.0762)
			(type default)
		)
		(layer "In4.Cu")
	)
	(gr_line
		(start 145.932906 -5.818378)
		(end 146.150838 -6.03631)
		(stroke
			(width 0.0762)
			(type default)
		)
		(layer "In4.Cu")
	)
	(gr_line
		(start 146.0246 -8.526018)
		(end 146.0246 -8.562848)
		(stroke
			(width 0.0762)
			(type default)
		)
		(layer "In4.Cu")
	)
	(gr_line
		(start 146.177254 -8.805418)
		(end 146.177254 -8.842248)
		(stroke
			(width 0.0762)
			(type default)
		)
		(layer "In4.Cu")
	)
	(gr_line
		(start 146.249136 -66.454274)
		(end 146.467068 -66.672206)
		(stroke
			(width 0.0762)
			(type default)
		)
		(layer "In4.Cu")
	)
	(gr_line
		(start 146.549364 -6.03631)
		(end 146.767296 -5.818378)
		(stroke
			(width 0.0762)
			(type default)
		)
		(layer "In4.Cu")
	)
	(gr_line
		(start 153.352246 -44.98594)
		(end 153.474166 -45.10786)
		(stroke
			(width 0.0762)
			(type default)
		)
		(layer "In4.Cu")
	)
	(gr_line
		(start 153.474166 -45.10786)
		(end 153.931366 -45.10786)
		(stroke
			(width 0.0762)
			(type default)
		)
		(layer "In4.Cu")
	)
	(gr_line
		(start 153.631646 -44.704)
		(end 153.773886 -44.704)
		(stroke
			(width 0.0762)
			(type default)
		)
		(layer "In4.Cu")
	)
	(gr_line
		(start 153.931366 -45.10786)
		(end 154.053286 -44.98594)
		(stroke
			(width 0.0762)
			(type default)
		)
		(layer "In4.Cu")
	)
	(gr_line
		(start 154.515566 -44.98594)
		(end 154.637486 -45.10786)
		(stroke
			(width 0.0762)
			(type default)
		)
		(layer "In4.Cu")
	)
	(gr_line
		(start 154.637486 -45.10786)
		(end 155.094686 -45.10786)
		(stroke
			(width 0.0762)
			(type default)
		)
		(layer "In4.Cu")
	)
	(gr_line
		(start 154.794966 -44.704)
		(end 154.937206 -44.704)
		(stroke
			(width 0.0762)
			(type default)
		)
		(layer "In4.Cu")
	)
	(gr_line
		(start 155.094686 -45.10786)
		(end 155.216606 -44.98594)
		(stroke
			(width 0.0762)
			(type default)
		)
		(layer "In4.Cu")
	)
	(gr_line
		(start 172.03293 -5.792978)
		(end 172.250862 -6.01091)
		(stroke
			(width 0.0762)
			(type default)
		)
		(layer "In4.Cu")
	)
	(gr_line
		(start 172.649388 -6.01091)
		(end 172.86732 -5.792978)
		(stroke
			(width 0.0762)
			(type default)
		)
		(layer "In4.Cu")
	)
	(gr_line
		(start 176.832768 -66.672206)
		(end 177.03419 -66.470784)
		(stroke
			(width 0.0762)
			(type default)
		)
		(layer "In4.Cu")
	)
	(gr_line
		(start 177.31613 -66.321178)
		(end 177.667158 -66.672206)
		(stroke
			(width 0.0762)
			(type default)
		)
		(layer "In4.Cu")
	)
	(gr_line
		(start 180.409342 -59.884564)
		(end 180.732684 -60.207906)
		(stroke
			(width 0.0762)
			(type default)
		)
		(layer "In4.Cu")
	)
	(gr_line
		(start 180.409342 -59.712098)
		(end 180.409342 -59.884564)
		(stroke
			(width 0.0762)
			(type default)
		)
		(layer "In4.Cu")
	)
	(gr_line
		(start 180.732684 -60.207906)
		(end 180.90515 -60.207906)
		(stroke
			(width 0.0762)
			(type default)
		)
		(layer "In4.Cu")
	)
	(gr_line
		(start 180.806344 -59.71032)
		(end 180.906928 -59.810904)
		(stroke
			(width 0.0762)
			(type default)
		)
		(layer "In4.Cu")
	)
	(gr_line
		(start 181.231794 -60.707016)
		(end 181.555136 -61.030358)
		(stroke
			(width 0.0762)
			(type default)
		)
		(layer "In4.Cu")
	)
	(gr_line
		(start 181.231794 -60.53455)
		(end 181.231794 -60.707016)
		(stroke
			(width 0.0762)
			(type default)
		)
		(layer "In4.Cu")
	)
	(gr_line
		(start 181.555136 -61.030358)
		(end 181.727602 -61.030358)
		(stroke
			(width 0.0762)
			(type default)
		)
		(layer "In4.Cu")
	)
	(gr_line
		(start 181.628796 -60.532772)
		(end 181.72938 -60.633356)
		(stroke
			(width 0.0762)
			(type default)
		)
		(layer "In4.Cu")
	)
	(gr_line
		(start 182.232808 -66.672206)
		(end 182.45074 -66.454274)
		(stroke
			(width 0.0762)
			(type default)
		)
		(layer "In4.Cu")
	)
	(gr_line
		(start 182.39994 -64.951356)
		(end 182.52186 -65.073276)
		(stroke
			(width 0.0762)
			(type default)
		)
		(layer "In4.Cu")
	)
	(gr_line
		(start 182.39994 -64.494156)
		(end 182.39994 -64.951356)
		(stroke
			(width 0.0762)
			(type default)
		)
		(layer "In4.Cu")
	)
	(gr_line
		(start 182.39994 -64.494156)
		(end 182.52186 -64.372236)
		(stroke
			(width 0.0762)
			(type default)
		)
		(layer "In4.Cu")
	)
	(gr_line
		(start 182.39994 -63.788036)
		(end 182.52186 -63.909956)
		(stroke
			(width 0.0762)
			(type default)
		)
		(layer "In4.Cu")
	)
	(gr_line
		(start 182.39994 -63.330836)
		(end 182.39994 -63.788036)
		(stroke
			(width 0.0762)
			(type default)
		)
		(layer "In4.Cu")
	)
	(gr_line
		(start 182.39994 -63.330836)
		(end 182.52186 -63.208916)
		(stroke
			(width 0.0762)
			(type default)
		)
		(layer "In4.Cu")
	)
	(gr_line
		(start 182.8038 -64.651636)
		(end 182.8038 -64.793876)
		(stroke
			(width 0.0762)
			(type default)
		)
		(layer "In4.Cu")
	)
	(gr_line
		(start 182.8038 -63.488316)
		(end 182.8038 -63.630556)
		(stroke
			(width 0.0762)
			(type default)
		)
		(layer "In4.Cu")
	)
	(gr_line
		(start 182.849266 -66.454274)
		(end 183.067198 -66.672206)
		(stroke
			(width 0.0762)
			(type default)
		)
		(layer "In4.Cu")
	)
	(gr_arc
		(start 1.54686 -67.178682)
		(mid 1.9304 -67.562222)
		(end 2.31394 -67.178682)
		(stroke
			(width 0.2)
			(type default)
		)
		(layer "In5.Cu")
	)
	(gr_line
		(start 1.54686 -66.221102)
		(end 1.54686 -67.178682)
		(stroke
			(width 0.2)
			(type default)
		)
		(layer "In5.Cu")
	)
	(gr_arc
		(start 1.54686 -64.178434)
		(mid 1.930273 -64.562228)
		(end 2.31394 -64.178688)
		(stroke
			(width 0.2)
			(type default)
		)
		(layer "In5.Cu")
	)
	(gr_line
		(start 1.54686 -63.221108)
		(end 1.54686 -64.178434)
		(stroke
			(width 0.2)
			(type default)
		)
		(layer "In5.Cu")
	)
	(gr_arc
		(start 1.54686 -61.178694)
		(mid 1.9304 -61.562234)
		(end 2.31394 -61.178694)
		(stroke
			(width 0.2)
			(type default)
		)
		(layer "In5.Cu")
	)
	(gr_line
		(start 1.54686 -60.221114)
		(end 1.54686 -61.178694)
		(stroke
			(width 0.2)
			(type default)
		)
		(layer "In5.Cu")
	)
	(gr_line
		(start 2.31394 -67.178682)
		(end 2.31394 -66.221356)
		(stroke
			(width 0.2)
			(type default)
		)
		(layer "In5.Cu")
	)
	(gr_arc
		(start 2.31394 -66.221356)
		(mid 1.930527 -65.837562)
		(end 1.54686 -66.221102)
		(stroke
			(width 0.2)
			(type default)
		)
		(layer "In5.Cu")
	)
	(gr_line
		(start 2.31394 -64.178688)
		(end 2.31394 -63.221108)
		(stroke
			(width 0.2)
			(type default)
		)
		(layer "In5.Cu")
	)
	(gr_arc
		(start 2.31394 -63.221108)
		(mid 1.9304 -62.837568)
		(end 1.54686 -63.221108)
		(stroke
			(width 0.2)
			(type default)
		)
		(layer "In5.Cu")
	)
	(gr_line
		(start 2.31394 -61.178694)
		(end 2.31394 -60.221368)
		(stroke
			(width 0.2)
			(type default)
		)
		(layer "In5.Cu")
	)
	(gr_arc
		(start 2.31394 -60.221368)
		(mid 1.930527 -59.837574)
		(end 1.54686 -60.221114)
		(stroke
			(width 0.2)
			(type default)
		)
		(layer "In5.Cu")
	)
	(gr_arc
		(start 2.94132 -59.664092)
		(mid 3.324733 -60.047886)
		(end 3.7084 -59.664346)
		(stroke
			(width 0.2)
			(type default)
		)
		(layer "In5.Cu")
	)
	(gr_line
		(start 2.94132 -58.706766)
		(end 2.94132 -59.664092)
		(stroke
			(width 0.2)
			(type default)
		)
		(layer "In5.Cu")
	)
	(gr_arc
		(start 3.06832 -65.664334)
		(mid 3.45186 -66.047874)
		(end 3.8354 -65.664334)
		(stroke
			(width 0.2)
			(type default)
		)
		(layer "In5.Cu")
	)
	(gr_line
		(start 3.06832 -64.706754)
		(end 3.06832 -65.664334)
		(stroke
			(width 0.2)
			(type default)
		)
		(layer "In5.Cu")
	)
	(gr_arc
		(start 3.06832 -62.66434)
		(mid 3.45186 -63.04788)
		(end 3.8354 -62.66434)
		(stroke
			(width 0.2)
			(type default)
		)
		(layer "In5.Cu")
	)
	(gr_line
		(start 3.06832 -61.70676)
		(end 3.06832 -62.66434)
		(stroke
			(width 0.2)
			(type default)
		)
		(layer "In5.Cu")
	)
	(gr_line
		(start 3.7084 -59.664346)
		(end 3.7084 -58.706766)
		(stroke
			(width 0.2)
			(type default)
		)
		(layer "In5.Cu")
	)
	(gr_arc
		(start 3.7084 -58.706766)
		(mid 3.32486 -58.323226)
		(end 2.94132 -58.706766)
		(stroke
			(width 0.2)
			(type default)
		)
		(layer "In5.Cu")
	)
	(gr_line
		(start 3.8354 -65.664334)
		(end 3.8354 -64.707008)
		(stroke
			(width 0.2)
			(type default)
		)
		(layer "In5.Cu")
	)
	(gr_arc
		(start 3.8354 -64.707008)
		(mid 3.451987 -64.323214)
		(end 3.06832 -64.706754)
		(stroke
			(width 0.2)
			(type default)
		)
		(layer "In5.Cu")
	)
	(gr_line
		(start 3.8354 -62.66434)
		(end 3.8354 -61.707014)
		(stroke
			(width 0.2)
			(type default)
		)
		(layer "In5.Cu")
	)
	(gr_arc
		(start 3.8354 -61.707014)
		(mid 3.451987 -61.32322)
		(end 3.06832 -61.70676)
		(stroke
			(width 0.2)
			(type default)
		)
		(layer "In5.Cu")
	)
	(gr_line
		(start 5.114798 -49.276)
		(end 5.114798 -43.688)
		(stroke
			(width 0.2)
			(type default)
		)
		(layer "In5.Cu")
	)
	(gr_line
		(start 5.114798 -43.688)
		(end 8.543798 -43.688)
		(stroke
			(width 0.2)
			(type default)
		)
		(layer "In5.Cu")
	)
	(gr_line
		(start 5.588 -33.147)
		(end 0.762 -33.147)
		(stroke
			(width 0.381)
			(type default)
		)
		(layer "In5.Cu")
	)
	(gr_line
		(start 6.223 -32.512)
		(end 5.588 -33.147)
		(stroke
			(width 0.381)
			(type default)
		)
		(layer "In5.Cu")
	)
	(gr_line
		(start 6.223 -23.876)
		(end 6.223 -32.512)
		(stroke
			(width 0.381)
			(type default)
		)
		(layer "In5.Cu")
	)
	(gr_line
		(start 6.985 -23.114)
		(end 6.223 -23.876)
		(stroke
			(width 0.381)
			(type default)
		)
		(layer "In5.Cu")
	)
	(gr_arc
		(start 7.747 -51.6128)
		(mid 8.128 -51.9938)
		(end 8.509 -51.6128)
		(stroke
			(width 0.2)
			(type default)
		)
		(layer "In5.Cu")
	)
	(gr_line
		(start 7.747 -50.6222)
		(end 7.747 -51.6128)
		(stroke
			(width 0.2)
			(type default)
		)
		(layer "In5.Cu")
	)
	(gr_line
		(start 8.382 -23.114)
		(end 6.985 -23.114)
		(stroke
			(width 0.381)
			(type default)
		)
		(layer "In5.Cu")
	)
	(gr_arc
		(start 8.4582 -53.8988)
		(mid 8.8392 -54.2798)
		(end 9.2202 -53.8988)
		(stroke
			(width 0.2)
			(type default)
		)
		(layer "In5.Cu")
	)
	(gr_line
		(start 8.4582 -52.9082)
		(end 8.4582 -53.8988)
		(stroke
			(width 0.2)
			(type default)
		)
		(layer "In5.Cu")
	)
	(gr_line
		(start 8.509 -51.6128)
		(end 8.509 -50.622454)
		(stroke
			(width 0.2)
			(type default)
		)
		(layer "In5.Cu")
	)
	(gr_arc
		(start 8.509 -50.622454)
		(mid 8.128127 -50.2412)
		(end 7.747 -50.6222)
		(stroke
			(width 0.2)
			(type default)
		)
		(layer "In5.Cu")
	)
	(gr_line
		(start 8.543798 -49.276)
		(end 5.114798 -49.276)
		(stroke
			(width 0.2)
			(type default)
		)
		(layer "In5.Cu")
	)
	(gr_line
		(start 8.543798 -43.688)
		(end 8.543798 -49.276)
		(stroke
			(width 0.2)
			(type default)
		)
		(layer "In5.Cu")
	)
	(gr_line
		(start 9.017 -23.749)
		(end 8.382 -23.114)
		(stroke
			(width 0.381)
			(type default)
		)
		(layer "In5.Cu")
	)
	(gr_line
		(start 9.2202 -53.8988)
		(end 9.2202 -52.908454)
		(stroke
			(width 0.2)
			(type default)
		)
		(layer "In5.Cu")
	)
	(gr_arc
		(start 9.2202 -52.908454)
		(mid 8.839327 -52.5272)
		(end 8.4582 -52.9082)
		(stroke
			(width 0.2)
			(type default)
		)
		(layer "In5.Cu")
	)
	(gr_line
		(start 9.240774 -62.748922)
		(end 9.266174 -63.637668)
		(stroke
			(width 0.2)
			(type default)
		)
		(layer "In5.Cu")
	)
	(gr_line
		(start 9.240774 -59.192922)
		(end 9.266174 -60.081668)
		(stroke
			(width 0.2)
			(type default)
		)
		(layer "In5.Cu")
	)
	(gr_arc
		(start 9.24306 -65.405)
		(mid 9.6266 -65.78854)
		(end 10.01014 -65.405)
		(stroke
			(width 0.2)
			(type default)
		)
		(layer "In5.Cu")
	)
	(gr_line
		(start 9.24306 -64.516)
		(end 9.24306 -65.405)
		(stroke
			(width 0.2)
			(type default)
		)
		(layer "In5.Cu")
	)
	(gr_arc
		(start 9.24306 -61.849)
		(mid 9.6266 -62.23254)
		(end 10.01014 -61.849)
		(stroke
			(width 0.2)
			(type default)
		)
		(layer "In5.Cu")
	)
	(gr_line
		(start 9.24306 -60.96)
		(end 9.24306 -61.849)
		(stroke
			(width 0.2)
			(type default)
		)
		(layer "In5.Cu")
	)
	(gr_arc
		(start 9.24306 -58.293)
		(mid 9.6266 -58.67654)
		(end 10.01014 -58.293)
		(stroke
			(width 0.2)
			(type default)
		)
		(layer "In5.Cu")
	)
	(gr_line
		(start 9.24306 -57.404)
		(end 9.24306 -58.293)
		(stroke
			(width 0.2)
			(type default)
		)
		(layer "In5.Cu")
	)
	(gr_arc
		(start 9.24306 -56.515)
		(mid 9.6266 -56.89854)
		(end 10.01014 -56.515)
		(stroke
			(width 0.2)
			(type default)
		)
		(layer "In5.Cu")
	)
	(gr_line
		(start 9.24306 -55.626)
		(end 9.24306 -56.515)
		(stroke
			(width 0.2)
			(type default)
		)
		(layer "In5.Cu")
	)
	(gr_line
		(start 9.243314 -62.748922)
		(end 9.240774 -62.748922)
		(stroke
			(width 0.2)
			(type default)
		)
		(layer "In5.Cu")
	)
	(gr_line
		(start 9.243314 -59.192922)
		(end 9.240774 -59.192922)
		(stroke
			(width 0.2)
			(type default)
		)
		(layer "In5.Cu")
	)
	(gr_line
		(start 9.266174 -63.637668)
		(end 9.266428 -63.637922)
		(stroke
			(width 0.2)
			(type default)
		)
		(layer "In5.Cu")
	)
	(gr_line
		(start 9.266174 -60.081668)
		(end 9.266428 -60.081922)
		(stroke
			(width 0.2)
			(type default)
		)
		(layer "In5.Cu")
	)
	(gr_line
		(start 9.266428 -63.637922)
		(end 9.268714 -63.637922)
		(stroke
			(width 0.2)
			(type default)
		)
		(layer "In5.Cu")
	)
	(gr_line
		(start 9.266428 -60.081922)
		(end 9.268714 -60.081922)
		(stroke
			(width 0.2)
			(type default)
		)
		(layer "In5.Cu")
	)
	(gr_arc
		(start 9.268714 -63.637922)
		(mid 9.662922 -64.010286)
		(end 10.035286 -63.616078)
		(stroke
			(width 0.2)
			(type default)
		)
		(layer "In5.Cu")
	)
	(gr_arc
		(start 9.268714 -60.081922)
		(mid 9.662922 -60.454286)
		(end 10.035286 -60.060078)
		(stroke
			(width 0.2)
			(type default)
		)
		(layer "In5.Cu")
	)
	(gr_circle
		(center 9.5504 -51.7398)
		(end 9.90854 -51.7398)
		(stroke
			(width 0.2)
			(type default)
		)
		(fill no)
		(layer "In5.Cu")
	)
	(gr_circle
		(center 9.5504 -50.4952)
		(end 9.90854 -50.4952)
		(stroke
			(width 0.2)
			(type default)
		)
		(fill no)
		(layer "In5.Cu")
	)
	(gr_arc
		(start 10.009886 -62.727078)
		(mid 9.615678 -62.354714)
		(end 9.243314 -62.748922)
		(stroke
			(width 0.2)
			(type default)
		)
		(layer "In5.Cu")
	)
	(gr_arc
		(start 10.009886 -59.171078)
		(mid 9.615678 -58.798714)
		(end 9.243314 -59.192922)
		(stroke
			(width 0.2)
			(type default)
		)
		(layer "In5.Cu")
	)
	(gr_line
		(start 10.01014 -65.405)
		(end 10.01014 -64.516254)
		(stroke
			(width 0.2)
			(type default)
		)
		(layer "In5.Cu")
	)
	(gr_arc
		(start 10.01014 -64.516254)
		(mid 9.626727 -64.13246)
		(end 9.24306 -64.516)
		(stroke
			(width 0.2)
			(type default)
		)
		(layer "In5.Cu")
	)
	(gr_line
		(start 10.01014 -61.849)
		(end 10.01014 -60.960254)
		(stroke
			(width 0.2)
			(type default)
		)
		(layer "In5.Cu")
	)
	(gr_arc
		(start 10.01014 -60.960254)
		(mid 9.626727 -60.57646)
		(end 9.24306 -60.96)
		(stroke
			(width 0.2)
			(type default)
		)
		(layer "In5.Cu")
	)
	(gr_line
		(start 10.01014 -58.293)
		(end 10.01014 -57.404254)
		(stroke
			(width 0.2)
			(type default)
		)
		(layer "In5.Cu")
	)
	(gr_arc
		(start 10.01014 -57.404254)
		(mid 9.626727 -57.02046)
		(end 9.24306 -57.404)
		(stroke
			(width 0.2)
			(type default)
		)
		(layer "In5.Cu")
	)
	(gr_line
		(start 10.01014 -56.515)
		(end 10.01014 -55.626254)
		(stroke
			(width 0.2)
			(type default)
		)
		(layer "In5.Cu")
	)
	(gr_arc
		(start 10.01014 -55.626254)
		(mid 9.626727 -55.24246)
		(end 9.24306 -55.626)
		(stroke
			(width 0.2)
			(type default)
		)
		(layer "In5.Cu")
	)
	(gr_line
		(start 10.012426 -62.727078)
		(end 10.009886 -62.727078)
		(stroke
			(width 0.2)
			(type default)
		)
		(layer "In5.Cu")
	)
	(gr_line
		(start 10.012426 -59.171078)
		(end 10.009886 -59.171078)
		(stroke
			(width 0.2)
			(type default)
		)
		(layer "In5.Cu")
	)
	(gr_line
		(start 10.035286 -63.616078)
		(end 10.037826 -63.616078)
		(stroke
			(width 0.2)
			(type default)
		)
		(layer "In5.Cu")
	)
	(gr_line
		(start 10.035286 -60.060078)
		(end 10.037826 -60.060078)
		(stroke
			(width 0.2)
			(type default)
		)
		(layer "In5.Cu")
	)
	(gr_line
		(start 10.037826 -63.616078)
		(end 10.012426 -62.727078)
		(stroke
			(width 0.2)
			(type default)
		)
		(layer "In5.Cu")
	)
	(gr_line
		(start 10.037826 -60.060078)
		(end 10.012426 -59.171078)
		(stroke
			(width 0.2)
			(type default)
		)
		(layer "In5.Cu")
	)
	(gr_circle
		(center 10.2616 -54.0258)
		(end 10.61974 -54.0258)
		(stroke
			(width 0.2)
			(type default)
		)
		(fill no)
		(layer "In5.Cu")
	)
	(gr_circle
		(center 10.2616 -52.7812)
		(end 10.61974 -52.7812)
		(stroke
			(width 0.2)
			(type default)
		)
		(fill no)
		(layer "In5.Cu")
	)
	(gr_arc
		(start 12.7889 -48.617886)
		(mid 13.172313 -49.00168)
		(end 13.55598 -48.61814)
		(stroke
			(width 0.2)
			(type default)
		)
		(layer "In5.Cu")
	)
	(gr_line
		(start 12.7889 -47.66056)
		(end 12.7889 -48.617886)
		(stroke
			(width 0.2)
			(type default)
		)
		(layer "In5.Cu")
	)
	(gr_line
		(start 13.55598 -48.61814)
		(end 13.55598 -47.66056)
		(stroke
			(width 0.2)
			(type default)
		)
		(layer "In5.Cu")
	)
	(gr_arc
		(start 13.55598 -47.66056)
		(mid 13.17244 -47.27702)
		(end 12.7889 -47.66056)
		(stroke
			(width 0.2)
			(type default)
		)
		(layer "In5.Cu")
	)
	(gr_line
		(start 14.15288 -47.21606)
		(end 15.082266 -47.21606)
		(stroke
			(width 0.2)
			(type default)
		)
		(layer "In5.Cu")
	)
	(gr_arc
		(start 14.153134 -46.44898)
		(mid 13.76934 -46.832393)
		(end 14.15288 -47.21606)
		(stroke
			(width 0.2)
			(type default)
		)
		(layer "In5.Cu")
	)
	(gr_line
		(start 14.986 -49.784)
		(end 15.367 -50.165)
		(stroke
			(width 0.381)
			(type default)
		)
		(layer "In5.Cu")
	)
	(gr_line
		(start 14.986 -48.641)
		(end 14.986 -49.784)
		(stroke
			(width 0.381)
			(type default)
		)
		(layer "In5.Cu")
	)
	(gr_arc
		(start 15.082266 -47.21606)
		(mid 15.465806 -46.83252)
		(end 15.082266 -46.44898)
		(stroke
			(width 0.2)
			(type default)
		)
		(layer "In5.Cu")
	)
	(gr_line
		(start 15.082266 -46.44898)
		(end 14.153134 -46.44898)
		(stroke
			(width 0.2)
			(type default)
		)
		(layer "In5.Cu")
	)
	(gr_line
		(start 15.367 -50.165)
		(end 19.177 -50.165)
		(stroke
			(width 0.381)
			(type default)
		)
		(layer "In5.Cu")
	)
	(gr_line
		(start 15.494 -10.287)
		(end 16.764 -10.287)
		(stroke
			(width 0.381)
			(type default)
		)
		(layer "In5.Cu")
	)
	(gr_line
		(start 16.002 -23.749)
		(end 9.017 -23.749)
		(stroke
			(width 0.381)
			(type default)
		)
		(layer "In5.Cu")
	)
	(gr_line
		(start 16.764 -10.287)
		(end 17.399 -10.922)
		(stroke
			(width 0.381)
			(type default)
		)
		(layer "In5.Cu")
	)
	(gr_line
		(start 17.399 -10.922)
		(end 57.404 -10.922)
		(stroke
			(width 0.381)
			(type default)
		)
		(layer "In5.Cu")
	)
	(gr_line
		(start 19.177 -50.165)
		(end 21.209 -48.133)
		(stroke
			(width 0.381)
			(type default)
		)
		(layer "In5.Cu")
	)
	(gr_line
		(start 19.408394 -10.634218)
		(end 20.327874 -10.634218)
		(stroke
			(width 0.2)
			(type default)
		)
		(layer "In5.Cu")
	)
	(gr_arc
		(start 19.408648 -9.867138)
		(mid 19.024854 -10.250551)
		(end 19.408394 -10.634218)
		(stroke
			(width 0.2)
			(type default)
		)
		(layer "In5.Cu")
	)
	(gr_line
		(start 20.09521 -15.872206)
		(end 21.052536 -15.872206)
		(stroke
			(width 0.2)
			(type default)
		)
		(layer "In5.Cu")
	)
	(gr_arc
		(start 20.09521 -15.105126)
		(mid 19.71167 -15.488666)
		(end 20.09521 -15.872206)
		(stroke
			(width 0.2)
			(type default)
		)
		(layer "In5.Cu")
	)
	(gr_arc
		(start 20.327874 -10.634218)
		(mid 20.711414 -10.250678)
		(end 20.327874 -9.867138)
		(stroke
			(width 0.2)
			(type default)
		)
		(layer "In5.Cu")
	)
	(gr_line
		(start 20.327874 -9.867138)
		(end 19.408648 -9.867138)
		(stroke
			(width 0.2)
			(type default)
		)
		(layer "In5.Cu")
	)
	(gr_line
		(start 20.701 -42.926)
		(end 14.986 -48.641)
		(stroke
			(width 0.381)
			(type default)
		)
		(layer "In5.Cu")
	)
	(gr_arc
		(start 21.052536 -15.872206)
		(mid 21.43633 -15.488793)
		(end 21.05279 -15.105126)
		(stroke
			(width 0.2)
			(type default)
		)
		(layer "In5.Cu")
	)
	(gr_line
		(start 21.05279 -15.105126)
		(end 20.09521 -15.105126)
		(stroke
			(width 0.2)
			(type default)
		)
		(layer "In5.Cu")
	)
	(gr_line
		(start 21.209 -48.133)
		(end 23.749 -48.133)
		(stroke
			(width 0.381)
			(type default)
		)
		(layer "In5.Cu")
	)
	(gr_line
		(start 21.463 -18.288)
		(end 16.002 -23.749)
		(stroke
			(width 0.381)
			(type default)
		)
		(layer "In5.Cu")
	)
	(gr_line
		(start 21.6662 -14.20114)
		(end 22.5298 -14.20114)
		(stroke
			(width 0.2)
			(type default)
		)
		(layer "In5.Cu")
	)
	(gr_arc
		(start 21.666454 -13.43406)
		(mid 21.28266 -13.817473)
		(end 21.6662 -14.20114)
		(stroke
			(width 0.2)
			(type default)
		)
		(layer "In5.Cu")
	)
	(gr_line
		(start 22.479 -42.926)
		(end 20.701 -42.926)
		(stroke
			(width 0.381)
			(type default)
		)
		(layer "In5.Cu")
	)
	(gr_arc
		(start 22.5298 -14.20114)
		(mid 22.91334 -13.8176)
		(end 22.5298 -13.43406)
		(stroke
			(width 0.2)
			(type default)
		)
		(layer "In5.Cu")
	)
	(gr_line
		(start 22.5298 -13.43406)
		(end 21.666454 -13.43406)
		(stroke
			(width 0.2)
			(type default)
		)
		(layer "In5.Cu")
	)
	(gr_line
		(start 23.408386 -10.634218)
		(end 24.327866 -10.634218)
		(stroke
			(width 0.2)
			(type default)
		)
		(layer "In5.Cu")
	)
	(gr_arc
		(start 23.40864 -9.867138)
		(mid 23.024846 -10.250551)
		(end 23.408386 -10.634218)
		(stroke
			(width 0.2)
			(type default)
		)
		(layer "In5.Cu")
	)
	(gr_line
		(start 23.749 -48.133)
		(end 28.448 -43.434)
		(stroke
			(width 0.381)
			(type default)
		)
		(layer "In5.Cu")
	)
	(gr_arc
		(start 24.327866 -10.634218)
		(mid 24.711406 -10.250678)
		(end 24.327866 -9.867138)
		(stroke
			(width 0.2)
			(type default)
		)
		(layer "In5.Cu")
	)
	(gr_line
		(start 24.327866 -9.867138)
		(end 23.40864 -9.867138)
		(stroke
			(width 0.2)
			(type default)
		)
		(layer "In5.Cu")
	)
	(gr_line
		(start 25.4127 -14.20114)
		(end 26.276046 -14.20114)
		(stroke
			(width 0.2)
			(type default)
		)
		(layer "In5.Cu")
	)
	(gr_arc
		(start 25.4127 -13.43406)
		(mid 25.02916 -13.8176)
		(end 25.4127 -14.20114)
		(stroke
			(width 0.2)
			(type default)
		)
		(layer "In5.Cu")
	)
	(gr_line
		(start 25.781 -29.718)
		(end 25.781 -26.797)
		(stroke
			(width 0.381)
			(type default)
		)
		(layer "In5.Cu")
	)
	(gr_line
		(start 25.781 -26.797)
		(end 27.813 -24.765)
		(stroke
			(width 0.381)
			(type default)
		)
		(layer "In5.Cu")
	)
	(gr_arc
		(start 26.276046 -14.20114)
		(mid 26.65984 -13.817727)
		(end 26.2763 -13.43406)
		(stroke
			(width 0.2)
			(type default)
		)
		(layer "In5.Cu")
	)
	(gr_line
		(start 26.2763 -13.43406)
		(end 25.4127 -13.43406)
		(stroke
			(width 0.2)
			(type default)
		)
		(layer "In5.Cu")
	)
	(gr_line
		(start 26.289 -30.226)
		(end 25.781 -29.718)
		(stroke
			(width 0.381)
			(type default)
		)
		(layer "In5.Cu")
	)
	(gr_line
		(start 26.543 -38.862)
		(end 22.479 -42.926)
		(stroke
			(width 0.381)
			(type default)
		)
		(layer "In5.Cu")
	)
	(gr_line
		(start 27.178 -20.828)
		(end 27.178 -18.288)
		(stroke
			(width 0.381)
			(type default)
		)
		(layer "In5.Cu")
	)
	(gr_line
		(start 27.408378 -10.634218)
		(end 28.327604 -10.634218)
		(stroke
			(width 0.2)
			(type default)
		)
		(layer "In5.Cu")
	)
	(gr_arc
		(start 27.408378 -9.867138)
		(mid 27.024838 -10.250678)
		(end 27.408378 -10.634218)
		(stroke
			(width 0.2)
			(type default)
		)
		(layer "In5.Cu")
	)
	(gr_line
		(start 27.813 -24.765)
		(end 27.813 -21.463)
		(stroke
			(width 0.381)
			(type default)
		)
		(layer "In5.Cu")
	)
	(gr_line
		(start 27.813 -21.463)
		(end 27.178 -20.828)
		(stroke
			(width 0.381)
			(type default)
		)
		(layer "In5.Cu")
	)
	(gr_arc
		(start 28.327604 -10.634218)
		(mid 28.711398 -10.250805)
		(end 28.327858 -9.867138)
		(stroke
			(width 0.2)
			(type default)
		)
		(layer "In5.Cu")
	)
	(gr_line
		(start 28.327858 -9.867138)
		(end 27.408378 -9.867138)
		(stroke
			(width 0.2)
			(type default)
		)
		(layer "In5.Cu")
	)
	(gr_line
		(start 28.448 -43.434)
		(end 32.258 -43.434)
		(stroke
			(width 0.381)
			(type default)
		)
		(layer "In5.Cu")
	)
	(gr_line
		(start 29.4132 -14.96314)
		(end 30.276546 -14.96314)
		(stroke
			(width 0.2)
			(type default)
		)
		(layer "In5.Cu")
	)
	(gr_arc
		(start 29.4132 -14.19606)
		(mid 29.02966 -14.5796)
		(end 29.4132 -14.96314)
		(stroke
			(width 0.2)
			(type default)
		)
		(layer "In5.Cu")
	)
	(gr_line
		(start 30.226 -38.862)
		(end 26.543 -38.862)
		(stroke
			(width 0.381)
			(type default)
		)
		(layer "In5.Cu")
	)
	(gr_arc
		(start 30.276546 -14.96314)
		(mid 30.66034 -14.579727)
		(end 30.2768 -14.19606)
		(stroke
			(width 0.2)
			(type default)
		)
		(layer "In5.Cu")
	)
	(gr_line
		(start 30.2768 -14.19606)
		(end 29.4132 -14.19606)
		(stroke
			(width 0.2)
			(type default)
		)
		(layer "In5.Cu")
	)
	(gr_line
		(start 30.861 -38.227)
		(end 30.226 -38.862)
		(stroke
			(width 0.381)
			(type default)
		)
		(layer "In5.Cu")
	)
	(gr_line
		(start 31.40837 -10.634218)
		(end 32.327596 -10.634218)
		(stroke
			(width 0.2)
			(type default)
		)
		(layer "In5.Cu")
	)
	(gr_arc
		(start 31.40837 -9.867138)
		(mid 31.02483 -10.250678)
		(end 31.40837 -10.634218)
		(stroke
			(width 0.2)
			(type default)
		)
		(layer "In5.Cu")
	)
	(gr_line
		(start 31.496 -30.226)
		(end 26.289 -30.226)
		(stroke
			(width 0.381)
			(type default)
		)
		(layer "In5.Cu")
	)
	(gr_line
		(start 32.258 -43.434)
		(end 34.163 -41.529)
		(stroke
			(width 0.381)
			(type default)
		)
		(layer "In5.Cu")
	)
	(gr_arc
		(start 32.327596 -10.634218)
		(mid 32.71139 -10.250805)
		(end 32.32785 -9.867138)
		(stroke
			(width 0.2)
			(type default)
		)
		(layer "In5.Cu")
	)
	(gr_line
		(start 32.32785 -9.867138)
		(end 31.40837 -9.867138)
		(stroke
			(width 0.2)
			(type default)
		)
		(layer "In5.Cu")
	)
	(gr_line
		(start 33.4264 -14.96314)
		(end 34.289746 -14.96314)
		(stroke
			(width 0.2)
			(type default)
		)
		(layer "In5.Cu")
	)
	(gr_arc
		(start 33.4264 -14.19606)
		(mid 33.04286 -14.5796)
		(end 33.4264 -14.96314)
		(stroke
			(width 0.2)
			(type default)
		)
		(layer "In5.Cu")
	)
	(gr_line
		(start 33.528 -28.194)
		(end 31.496 -30.226)
		(stroke
			(width 0.381)
			(type default)
		)
		(layer "In5.Cu")
	)
	(gr_line
		(start 34.163 -41.529)
		(end 37.084 -41.529)
		(stroke
			(width 0.381)
			(type default)
		)
		(layer "In5.Cu")
	)
	(gr_arc
		(start 34.289746 -14.96314)
		(mid 34.67354 -14.579727)
		(end 34.29 -14.19606)
		(stroke
			(width 0.2)
			(type default)
		)
		(layer "In5.Cu")
	)
	(gr_line
		(start 34.29 -14.19606)
		(end 33.4264 -14.19606)
		(stroke
			(width 0.2)
			(type default)
		)
		(layer "In5.Cu")
	)
	(gr_line
		(start 34.671 -28.194)
		(end 33.528 -28.194)
		(stroke
			(width 0.381)
			(type default)
		)
		(layer "In5.Cu")
	)
	(gr_line
		(start 35.408362 -10.634218)
		(end 36.327588 -10.634218)
		(stroke
			(width 0.2)
			(type default)
		)
		(layer "In5.Cu")
	)
	(gr_arc
		(start 35.408362 -9.867138)
		(mid 35.024822 -10.250678)
		(end 35.408362 -10.634218)
		(stroke
			(width 0.2)
			(type default)
		)
		(layer "In5.Cu")
	)
	(gr_arc
		(start 36.327588 -10.634218)
		(mid 36.711382 -10.250805)
		(end 36.327842 -9.867138)
		(stroke
			(width 0.2)
			(type default)
		)
		(layer "In5.Cu")
	)
	(gr_line
		(start 36.327842 -9.867138)
		(end 35.408362 -9.867138)
		(stroke
			(width 0.2)
			(type default)
		)
		(layer "In5.Cu")
	)
	(gr_line
		(start 37.084 -41.529)
		(end 38.1 -42.545)
		(stroke
			(width 0.381)
			(type default)
		)
		(layer "In5.Cu")
	)
	(gr_line
		(start 37.41801 -14.20114)
		(end 38.281356 -14.20114)
		(stroke
			(width 0.2)
			(type default)
		)
		(layer "In5.Cu")
	)
	(gr_arc
		(start 37.41801 -13.43406)
		(mid 37.03447 -13.8176)
		(end 37.41801 -14.20114)
		(stroke
			(width 0.2)
			(type default)
		)
		(layer "In5.Cu")
	)
	(gr_arc
		(start 37.88664 -30.2006)
		(mid 38.27018 -30.58414)
		(end 38.65372 -30.2006)
		(stroke
			(width 0.2)
			(type default)
		)
		(layer "In5.Cu")
	)
	(gr_line
		(start 37.88664 -29.337)
		(end 37.88664 -30.2006)
		(stroke
			(width 0.2)
			(type default)
		)
		(layer "In5.Cu")
	)
	(gr_line
		(start 38.1 -44.831)
		(end 41.021 -47.752)
		(stroke
			(width 0.381)
			(type default)
		)
		(layer "In5.Cu")
	)
	(gr_line
		(start 38.1 -42.545)
		(end 38.1 -44.831)
		(stroke
			(width 0.381)
			(type default)
		)
		(layer "In5.Cu")
	)
	(gr_arc
		(start 38.281356 -14.20114)
		(mid 38.66515 -13.817727)
		(end 38.28161 -13.43406)
		(stroke
			(width 0.2)
			(type default)
		)
		(layer "In5.Cu")
	)
	(gr_line
		(start 38.28161 -13.43406)
		(end 37.41801 -13.43406)
		(stroke
			(width 0.2)
			(type default)
		)
		(layer "In5.Cu")
	)
	(gr_line
		(start 38.481 -38.227)
		(end 30.861 -38.227)
		(stroke
			(width 0.381)
			(type default)
		)
		(layer "In5.Cu")
	)
	(gr_line
		(start 38.65372 -30.2006)
		(end 38.65372 -29.337254)
		(stroke
			(width 0.2)
			(type default)
		)
		(layer "In5.Cu")
	)
	(gr_arc
		(start 38.65372 -29.337254)
		(mid 38.270307 -28.95346)
		(end 37.88664 -29.337)
		(stroke
			(width 0.2)
			(type default)
		)
		(layer "In5.Cu")
	)
	(gr_line
		(start 38.862 -38.608)
		(end 38.481 -38.227)
		(stroke
			(width 0.381)
			(type default)
		)
		(layer "In5.Cu")
	)
	(gr_line
		(start 38.862 -24.003)
		(end 34.671 -28.194)
		(stroke
			(width 0.381)
			(type default)
		)
		(layer "In5.Cu")
	)
	(gr_line
		(start 39.408354 -10.634218)
		(end 40.327834 -10.634218)
		(stroke
			(width 0.2)
			(type default)
		)
		(layer "In5.Cu")
	)
	(gr_arc
		(start 39.408608 -9.867138)
		(mid 39.024814 -10.250551)
		(end 39.408354 -10.634218)
		(stroke
			(width 0.2)
			(type default)
		)
		(layer "In5.Cu")
	)
	(gr_line
		(start 39.44366 -12.73048)
		(end 40.40124 -12.73048)
		(stroke
			(width 0.2)
			(type default)
		)
		(layer "In5.Cu")
	)
	(gr_arc
		(start 39.443914 -11.9634)
		(mid 39.06012 -12.346813)
		(end 39.44366 -12.73048)
		(stroke
			(width 0.2)
			(type default)
		)
		(layer "In5.Cu")
	)
	(gr_line
		(start 40.132 -38.608)
		(end 38.862 -38.608)
		(stroke
			(width 0.381)
			(type default)
		)
		(layer "In5.Cu")
	)
	(gr_arc
		(start 40.327834 -10.634218)
		(mid 40.711374 -10.250678)
		(end 40.327834 -9.867138)
		(stroke
			(width 0.2)
			(type default)
		)
		(layer "In5.Cu")
	)
	(gr_line
		(start 40.327834 -9.867138)
		(end 39.408608 -9.867138)
		(stroke
			(width 0.2)
			(type default)
		)
		(layer "In5.Cu")
	)
	(gr_arc
		(start 40.40124 -12.73048)
		(mid 40.78478 -12.34694)
		(end 40.40124 -11.9634)
		(stroke
			(width 0.2)
			(type default)
		)
		(layer "In5.Cu")
	)
	(gr_line
		(start 40.40124 -11.9634)
		(end 39.443914 -11.9634)
		(stroke
			(width 0.2)
			(type default)
		)
		(layer "In5.Cu")
	)
	(gr_line
		(start 41.021 -47.752)
		(end 47.752 -47.752)
		(stroke
			(width 0.381)
			(type default)
		)
		(layer "In5.Cu")
	)
	(gr_line
		(start 41.418002 -14.20114)
		(end 42.281348 -14.20114)
		(stroke
			(width 0.2)
			(type default)
		)
		(layer "In5.Cu")
	)
	(gr_arc
		(start 41.418002 -13.43406)
		(mid 41.034462 -13.8176)
		(end 41.418002 -14.20114)
		(stroke
			(width 0.2)
			(type default)
		)
		(layer "In5.Cu")
	)
	(gr_line
		(start 41.783 -44.45)
		(end 41.783 -40.259)
		(stroke
			(width 0.381)
			(type default)
		)
		(layer "In5.Cu")
	)
	(gr_line
		(start 41.783 -40.259)
		(end 40.132 -38.608)
		(stroke
			(width 0.381)
			(type default)
		)
		(layer "In5.Cu")
	)
	(gr_line
		(start 42.164 -44.831)
		(end 41.783 -44.45)
		(stroke
			(width 0.381)
			(type default)
		)
		(layer "In5.Cu")
	)
	(gr_arc
		(start 42.281348 -14.20114)
		(mid 42.665142 -13.817727)
		(end 42.281602 -13.43406)
		(stroke
			(width 0.2)
			(type default)
		)
		(layer "In5.Cu")
	)
	(gr_line
		(start 42.281602 -13.43406)
		(end 41.418002 -13.43406)
		(stroke
			(width 0.2)
			(type default)
		)
		(layer "In5.Cu")
	)
	(gr_line
		(start 42.45356 -44.5389)
		(end 43.41114 -44.5389)
		(stroke
			(width 0.2)
			(type default)
		)
		(layer "In5.Cu")
	)
	(gr_arc
		(start 42.453814 -43.77182)
		(mid 42.07002 -44.155233)
		(end 42.45356 -44.5389)
		(stroke
			(width 0.2)
			(type default)
		)
		(layer "In5.Cu")
	)
	(gr_line
		(start 43.25366 -12.98194)
		(end 44.210986 -12.98194)
		(stroke
			(width 0.2)
			(type default)
		)
		(layer "In5.Cu")
	)
	(gr_arc
		(start 43.25366 -12.21486)
		(mid 42.87012 -12.5984)
		(end 43.25366 -12.98194)
		(stroke
			(width 0.2)
			(type default)
		)
		(layer "In5.Cu")
	)
	(gr_line
		(start 43.408346 -10.634218)
		(end 44.327826 -10.634218)
		(stroke
			(width 0.2)
			(type default)
		)
		(layer "In5.Cu")
	)
	(gr_arc
		(start 43.4086 -9.867138)
		(mid 43.024806 -10.250551)
		(end 43.408346 -10.634218)
		(stroke
			(width 0.2)
			(type default)
		)
		(layer "In5.Cu")
	)
	(gr_arc
		(start 43.41114 -44.5389)
		(mid 43.79468 -44.15536)
		(end 43.41114 -43.77182)
		(stroke
			(width 0.2)
			(type default)
		)
		(layer "In5.Cu")
	)
	(gr_line
		(start 43.41114 -43.77182)
		(end 42.453814 -43.77182)
		(stroke
			(width 0.2)
			(type default)
		)
		(layer "In5.Cu")
	)
	(gr_line
		(start 43.561 -44.831)
		(end 42.164 -44.831)
		(stroke
			(width 0.381)
			(type default)
		)
		(layer "In5.Cu")
	)
	(gr_line
		(start 43.815 -45.085)
		(end 43.561 -44.831)
		(stroke
			(width 0.381)
			(type default)
		)
		(layer "In5.Cu")
	)
	(gr_line
		(start 44.069 -24.003)
		(end 38.862 -24.003)
		(stroke
			(width 0.381)
			(type default)
		)
		(layer "In5.Cu")
	)
	(gr_arc
		(start 44.210986 -12.98194)
		(mid 44.59478 -12.598527)
		(end 44.21124 -12.21486)
		(stroke
			(width 0.2)
			(type default)
		)
		(layer "In5.Cu")
	)
	(gr_line
		(start 44.21124 -12.21486)
		(end 43.25366 -12.21486)
		(stroke
			(width 0.2)
			(type default)
		)
		(layer "In5.Cu")
	)
	(gr_arc
		(start 44.327826 -10.634218)
		(mid 44.711366 -10.250678)
		(end 44.327826 -9.867138)
		(stroke
			(width 0.2)
			(type default)
		)
		(layer "In5.Cu")
	)
	(gr_line
		(start 44.327826 -9.867138)
		(end 43.4086 -9.867138)
		(stroke
			(width 0.2)
			(type default)
		)
		(layer "In5.Cu")
	)
	(gr_line
		(start 44.577 -23.495)
		(end 44.069 -24.003)
		(stroke
			(width 0.381)
			(type default)
		)
		(layer "In5.Cu")
	)
	(gr_line
		(start 44.98975 -44.30014)
		(end 45.947838 -44.32173)
		(stroke
			(width 0.2)
			(type default)
		)
		(layer "In5.Cu")
	)
	(gr_arc
		(start 45.007276 -43.53306)
		(mid 44.615103 -43.907837)
		(end 44.98975 -44.30014)
		(stroke
			(width 0.2)
			(type default)
		)
		(layer "In5.Cu")
	)
	(gr_line
		(start 45.466 -14.1986)
		(end 46.176946 -14.1986)
		(stroke
			(width 0.2)
			(type default)
		)
		(layer "In5.Cu")
	)
	(gr_arc
		(start 45.466 -13.4366)
		(mid 45.085 -13.8176)
		(end 45.466 -14.1986)
		(stroke
			(width 0.2)
			(type default)
		)
		(layer "In5.Cu")
	)
	(gr_line
		(start 45.72 -45.085)
		(end 43.815 -45.085)
		(stroke
			(width 0.381)
			(type default)
		)
		(layer "In5.Cu")
	)
	(gr_arc
		(start 45.947838 -44.32173)
		(mid 46.340014 -43.946826)
		(end 45.96511 -43.55465)
		(stroke
			(width 0.2)
			(type default)
		)
		(layer "In5.Cu")
	)
	(gr_line
		(start 45.96511 -43.55465)
		(end 45.007276 -43.53306)
		(stroke
			(width 0.2)
			(type default)
		)
		(layer "In5.Cu")
	)
	(gr_arc
		(start 46.176946 -14.1986)
		(mid 46.5582 -13.817727)
		(end 46.1772 -13.4366)
		(stroke
			(width 0.2)
			(type default)
		)
		(layer "In5.Cu")
	)
	(gr_line
		(start 46.1772 -13.4366)
		(end 45.466 -13.4366)
		(stroke
			(width 0.2)
			(type default)
		)
		(layer "In5.Cu")
	)
	(gr_line
		(start 46.863 -43.942)
		(end 45.72 -45.085)
		(stroke
			(width 0.381)
			(type default)
		)
		(layer "In5.Cu")
	)
	(gr_line
		(start 46.863 -42.037)
		(end 46.863 -43.942)
		(stroke
			(width 0.381)
			(type default)
		)
		(layer "In5.Cu")
	)
	(gr_line
		(start 47.408338 -10.634218)
		(end 48.327818 -10.634218)
		(stroke
			(width 0.2)
			(type default)
		)
		(layer "In5.Cu")
	)
	(gr_arc
		(start 47.408592 -9.867138)
		(mid 47.024798 -10.250551)
		(end 47.408338 -10.634218)
		(stroke
			(width 0.2)
			(type default)
		)
		(layer "In5.Cu")
	)
	(gr_line
		(start 47.46371 -14.1732)
		(end 48.183546 -14.1732)
		(stroke
			(width 0.2)
			(type default)
		)
		(layer "In5.Cu")
	)
	(gr_arc
		(start 47.46371 -13.4112)
		(mid 47.08271 -13.7922)
		(end 47.46371 -14.1732)
		(stroke
			(width 0.2)
			(type default)
		)
		(layer "In5.Cu")
	)
	(gr_line
		(start 47.752 -47.752)
		(end 52.324 -43.18)
		(stroke
			(width 0.381)
			(type default)
		)
		(layer "In5.Cu")
	)
	(gr_arc
		(start 48.183546 -14.1732)
		(mid 48.5648 -13.792327)
		(end 48.1838 -13.4112)
		(stroke
			(width 0.2)
			(type default)
		)
		(layer "In5.Cu")
	)
	(gr_line
		(start 48.1838 -13.4112)
		(end 47.46371 -13.4112)
		(stroke
			(width 0.2)
			(type default)
		)
		(layer "In5.Cu")
	)
	(gr_arc
		(start 48.327818 -10.634218)
		(mid 48.711358 -10.250678)
		(end 48.327818 -9.867138)
		(stroke
			(width 0.2)
			(type default)
		)
		(layer "In5.Cu")
	)
	(gr_line
		(start 48.327818 -9.867138)
		(end 47.408592 -9.867138)
		(stroke
			(width 0.2)
			(type default)
		)
		(layer "In5.Cu")
	)
	(gr_line
		(start 48.641 -40.259)
		(end 46.863 -42.037)
		(stroke
			(width 0.381)
			(type default)
		)
		(layer "In5.Cu")
	)
	(gr_line
		(start 49.176432 -38.313614)
		(end 49.81321 -38.892226)
		(stroke
			(width 0.2)
			(type default)
		)
		(layer "In5.Cu")
	)
	(gr_line
		(start 49.29505 -20.79498)
		(end 50.25263 -20.79498)
		(stroke
			(width 0.2)
			(type default)
		)
		(layer "In5.Cu")
	)
	(gr_arc
		(start 49.295304 -20.0279)
		(mid 48.91151 -20.411313)
		(end 49.29505 -20.79498)
		(stroke
			(width 0.2)
			(type default)
		)
		(layer "In5.Cu")
	)
	(gr_line
		(start 49.38903 -10.64387)
		(end 50.310542 -10.64387)
		(stroke
			(width 0.2)
			(type default)
		)
		(layer "In5.Cu")
	)
	(gr_arc
		(start 49.389284 -9.87679)
		(mid 49.00549 -10.260203)
		(end 49.38903 -10.64387)
		(stroke
			(width 0.2)
			(type default)
		)
		(layer "In5.Cu")
	)
	(gr_line
		(start 49.4538 -14.1986)
		(end 50.2158 -14.1986)
		(stroke
			(width 0.2)
			(type default)
		)
		(layer "In5.Cu")
	)
	(gr_arc
		(start 49.454054 -13.4366)
		(mid 49.0728 -13.817473)
		(end 49.4538 -14.1986)
		(stroke
			(width 0.2)
			(type default)
		)
		(layer "In5.Cu")
	)
	(gr_arc
		(start 49.692052 -37.74567)
		(mid 49.15027 -37.771832)
		(end 49.176432 -38.313614)
		(stroke
			(width 0.2)
			(type default)
		)
		(layer "In5.Cu")
	)
	(gr_arc
		(start 49.81321 -38.892226)
		(mid 50.356403 -38.869633)
		(end 50.33137 -38.326568)
		(stroke
			(width 0.2)
			(type default)
		)
		(layer "In5.Cu")
	)
	(gr_arc
		(start 50.2158 -14.1986)
		(mid 50.5968 -13.8176)
		(end 50.2158 -13.4366)
		(stroke
			(width 0.2)
			(type default)
		)
		(layer "In5.Cu")
	)
	(gr_line
		(start 50.2158 -13.4366)
		(end 49.454054 -13.4366)
		(stroke
			(width 0.2)
			(type default)
		)
		(layer "In5.Cu")
	)
	(gr_arc
		(start 50.25263 -20.79498)
		(mid 50.63617 -20.41144)
		(end 50.25263 -20.0279)
		(stroke
			(width 0.2)
			(type default)
		)
		(layer "In5.Cu")
	)
	(gr_line
		(start 50.25263 -20.0279)
		(end 49.295304 -20.0279)
		(stroke
			(width 0.2)
			(type default)
		)
		(layer "In5.Cu")
	)
	(gr_arc
		(start 50.262028 -48.49495)
		(mid 50.63998 -48.884078)
		(end 51.029108 -48.506126)
		(stroke
			(width 0.2)
			(type default)
		)
		(layer "In5.Cu")
	)
	(gr_line
		(start 50.274474 -47.63135)
		(end 50.262028 -48.49495)
		(stroke
			(width 0.2)
			(type default)
		)
		(layer "In5.Cu")
	)
	(gr_arc
		(start 50.310542 -10.64387)
		(mid 50.694082 -10.26033)
		(end 50.310542 -9.87679)
		(stroke
			(width 0.2)
			(type default)
		)
		(layer "In5.Cu")
	)
	(gr_line
		(start 50.310542 -9.87679)
		(end 49.389284 -9.87679)
		(stroke
			(width 0.2)
			(type default)
		)
		(layer "In5.Cu")
	)
	(gr_line
		(start 50.33137 -38.326568)
		(end 49.692052 -37.74567)
		(stroke
			(width 0.2)
			(type default)
		)
		(layer "In5.Cu")
	)
	(gr_line
		(start 51.029108 -48.506126)
		(end 51.041554 -47.64278)
		(stroke
			(width 0.2)
			(type default)
		)
		(layer "In5.Cu")
	)
	(gr_arc
		(start 51.041554 -47.64278)
		(mid 50.663729 -47.253654)
		(end 50.274474 -47.63135)
		(stroke
			(width 0.2)
			(type default)
		)
		(layer "In5.Cu")
	)
	(gr_line
		(start 51.282346 -34.47034)
		(end 52.16652 -34.47034)
		(stroke
			(width 0.2)
			(type default)
		)
		(layer "In5.Cu")
	)
	(gr_arc
		(start 51.2826 -33.70326)
		(mid 50.898806 -34.086673)
		(end 51.282346 -34.47034)
		(stroke
			(width 0.2)
			(type default)
		)
		(layer "In5.Cu")
	)
	(gr_line
		(start 52.1462 -14.32814)
		(end 53.009546 -14.32814)
		(stroke
			(width 0.2)
			(type default)
		)
		(layer "In5.Cu")
	)
	(gr_arc
		(start 52.1462 -13.56106)
		(mid 51.76266 -13.9446)
		(end 52.1462 -14.32814)
		(stroke
			(width 0.2)
			(type default)
		)
		(layer "In5.Cu")
	)
	(gr_arc
		(start 52.16652 -34.47034)
		(mid 52.55006 -34.0868)
		(end 52.16652 -33.70326)
		(stroke
			(width 0.2)
			(type default)
		)
		(layer "In5.Cu")
	)
	(gr_line
		(start 52.16652 -33.70326)
		(end 51.2826 -33.70326)
		(stroke
			(width 0.2)
			(type default)
		)
		(layer "In5.Cu")
	)
	(gr_line
		(start 52.324 -43.18)
		(end 53.848 -43.18)
		(stroke
			(width 0.381)
			(type default)
		)
		(layer "In5.Cu")
	)
	(gr_arc
		(start 52.52339 -34.93262)
		(mid 52.14112 -35.31743)
		(end 52.52593 -35.6997)
		(stroke
			(width 0.2)
			(type default)
		)
		(layer "In5.Cu")
	)
	(gr_line
		(start 52.52593 -35.6997)
		(end 53.479954 -35.696652)
		(stroke
			(width 0.2)
			(type default)
		)
		(layer "In5.Cu")
	)
	(gr_arc
		(start 52.768246 -29.826966)
		(mid 53.151659 -30.21076)
		(end 53.535326 -29.82722)
		(stroke
			(width 0.2)
			(type default)
		)
		(layer "In5.Cu")
	)
	(gr_line
		(start 52.768246 -28.897834)
		(end 52.768246 -29.826966)
		(stroke
			(width 0.2)
			(type default)
		)
		(layer "In5.Cu")
	)
	(gr_line
		(start 52.832 -40.259)
		(end 48.641 -40.259)
		(stroke
			(width 0.381)
			(type default)
		)
		(layer "In5.Cu")
	)
	(gr_arc
		(start 53.009546 -14.32814)
		(mid 53.39334 -13.944727)
		(end 53.0098 -13.56106)
		(stroke
			(width 0.2)
			(type default)
		)
		(layer "In5.Cu")
	)
	(gr_line
		(start 53.0098 -13.56106)
		(end 52.1462 -13.56106)
		(stroke
			(width 0.2)
			(type default)
		)
		(layer "In5.Cu")
	)
	(gr_line
		(start 53.477668 -34.929572)
		(end 52.52339 -34.93262)
		(stroke
			(width 0.2)
			(type default)
		)
		(layer "In5.Cu")
	)
	(gr_arc
		(start 53.479954 -35.696652)
		(mid 53.862478 -35.311969)
		(end 53.477668 -34.929572)
		(stroke
			(width 0.2)
			(type default)
		)
		(layer "In5.Cu")
	)
	(gr_line
		(start 53.535326 -29.82722)
		(end 53.535326 -28.897834)
		(stroke
			(width 0.2)
			(type default)
		)
		(layer "In5.Cu")
	)
	(gr_arc
		(start 53.535326 -28.897834)
		(mid 53.151786 -28.514294)
		(end 52.768246 -28.897834)
		(stroke
			(width 0.2)
			(type default)
		)
		(layer "In5.Cu")
	)
	(gr_line
		(start 53.848 -43.18)
		(end 55.118 -41.91)
		(stroke
			(width 0.381)
			(type default)
		)
		(layer "In5.Cu")
	)
	(gr_line
		(start 53.848 -39.243)
		(end 52.832 -40.259)
		(stroke
			(width 0.381)
			(type default)
		)
		(layer "In5.Cu")
	)
	(gr_line
		(start 54.61 -39.243)
		(end 53.848 -39.243)
		(stroke
			(width 0.381)
			(type default)
		)
		(layer "In5.Cu")
	)
	(gr_line
		(start 55.118 -41.91)
		(end 55.118 -39.751)
		(stroke
			(width 0.381)
			(type default)
		)
		(layer "In5.Cu")
	)
	(gr_line
		(start 55.118 -39.751)
		(end 54.61 -39.243)
		(stroke
			(width 0.381)
			(type default)
		)
		(layer "In5.Cu")
	)
	(gr_line
		(start 56.642 -62.23)
		(end 57.404 -62.992)
		(stroke
			(width 0.381)
			(type default)
		)
		(layer "In5.Cu")
	)
	(gr_line
		(start 56.642 -58.293)
		(end 56.642 -62.23)
		(stroke
			(width 0.381)
			(type default)
		)
		(layer "In5.Cu")
	)
	(gr_line
		(start 57.404 -62.992)
		(end 83.439 -62.992)
		(stroke
			(width 0.381)
			(type default)
		)
		(layer "In5.Cu")
	)
	(gr_line
		(start 57.404 -10.922)
		(end 57.912 -10.414)
		(stroke
			(width 0.381)
			(type default)
		)
		(layer "In5.Cu")
	)
	(gr_line
		(start 57.912 -10.414)
		(end 60.325 -10.414)
		(stroke
			(width 0.381)
			(type default)
		)
		(layer "In5.Cu")
	)
	(gr_line
		(start 59.078114 -11.320018)
		(end 59.997594 -11.320018)
		(stroke
			(width 0.2)
			(type default)
		)
		(layer "In5.Cu")
	)
	(gr_arc
		(start 59.078368 -10.552938)
		(mid 58.694574 -10.936351)
		(end 59.078114 -11.320018)
		(stroke
			(width 0.2)
			(type default)
		)
		(layer "In5.Cu")
	)
	(gr_arc
		(start 59.27471 -36.33724)
		(mid 59.65825 -36.72078)
		(end 60.04179 -36.33724)
		(stroke
			(width 0.2)
			(type default)
		)
		(layer "In5.Cu")
	)
	(gr_line
		(start 59.27471 -35.37966)
		(end 59.27471 -36.33724)
		(stroke
			(width 0.2)
			(type default)
		)
		(layer "In5.Cu")
	)
	(gr_arc
		(start 59.997594 -11.320018)
		(mid 60.381134 -10.936478)
		(end 59.997594 -10.552938)
		(stroke
			(width 0.2)
			(type default)
		)
		(layer "In5.Cu")
	)
	(gr_line
		(start 59.997594 -10.552938)
		(end 59.078368 -10.552938)
		(stroke
			(width 0.2)
			(type default)
		)
		(layer "In5.Cu")
	)
	(gr_line
		(start 60.04179 -36.33724)
		(end 60.04179 -35.379914)
		(stroke
			(width 0.2)
			(type default)
		)
		(layer "In5.Cu")
	)
	(gr_arc
		(start 60.04179 -35.379914)
		(mid 59.658377 -34.99612)
		(end 59.27471 -35.37966)
		(stroke
			(width 0.2)
			(type default)
		)
		(layer "In5.Cu")
	)
	(gr_line
		(start 60.325 -10.414)
		(end 60.833 -10.922)
		(stroke
			(width 0.381)
			(type default)
		)
		(layer "In5.Cu")
	)
	(gr_line
		(start 60.551822 -45.897038)
		(end 60.607448 -46.75886)
		(stroke
			(width 0.2)
			(type default)
		)
		(layer "In5.Cu")
	)
	(gr_arc
		(start 60.607448 -46.75886)
		(mid 61.014864 -47.117)
		(end 61.373004 -46.709584)
		(stroke
			(width 0.2)
			(type default)
		)
		(layer "In5.Cu")
	)
	(gr_line
		(start 60.833 -10.922)
		(end 83.947 -10.922)
		(stroke
			(width 0.381)
			(type default)
		)
		(layer "In5.Cu")
	)
	(gr_arc
		(start 61.317378 -45.848016)
		(mid 60.910088 -45.489868)
		(end 60.551822 -45.897038)
		(stroke
			(width 0.2)
			(type default)
		)
		(layer "In5.Cu")
	)
	(gr_line
		(start 61.373004 -46.709584)
		(end 61.317378 -45.848016)
		(stroke
			(width 0.2)
			(type default)
		)
		(layer "In5.Cu")
	)
	(gr_line
		(start 61.40831 -10.634218)
		(end 62.327536 -10.634218)
		(stroke
			(width 0.2)
			(type default)
		)
		(layer "In5.Cu")
	)
	(gr_arc
		(start 61.40831 -9.867138)
		(mid 61.02477 -10.250678)
		(end 61.40831 -10.634218)
		(stroke
			(width 0.2)
			(type default)
		)
		(layer "In5.Cu")
	)
	(gr_line
		(start 61.468 -18.288)
		(end 21.463 -18.288)
		(stroke
			(width 0.381)
			(type default)
		)
		(layer "In5.Cu")
	)
	(gr_line
		(start 61.722 -18.034)
		(end 61.468 -18.288)
		(stroke
			(width 0.381)
			(type default)
		)
		(layer "In5.Cu")
	)
	(gr_line
		(start 62.103 -52.832)
		(end 56.642 -58.293)
		(stroke
			(width 0.381)
			(type default)
		)
		(layer "In5.Cu")
	)
	(gr_arc
		(start 62.327536 -10.634218)
		(mid 62.71133 -10.250805)
		(end 62.32779 -9.867138)
		(stroke
			(width 0.2)
			(type default)
		)
		(layer "In5.Cu")
	)
	(gr_line
		(start 62.32779 -9.867138)
		(end 61.40831 -9.867138)
		(stroke
			(width 0.2)
			(type default)
		)
		(layer "In5.Cu")
	)
	(gr_line
		(start 63.246 -52.832)
		(end 62.103 -52.832)
		(stroke
			(width 0.381)
			(type default)
		)
		(layer "In5.Cu")
	)
	(gr_line
		(start 63.373 -23.495)
		(end 44.577 -23.495)
		(stroke
			(width 0.381)
			(type default)
		)
		(layer "In5.Cu")
	)
	(gr_line
		(start 63.627 -15.0876)
		(end 64.389 -15.0876)
		(stroke
			(width 0.2)
			(type default)
		)
		(layer "In5.Cu")
	)
	(gr_arc
		(start 63.627254 -14.3256)
		(mid 63.246 -14.706473)
		(end 63.627 -15.0876)
		(stroke
			(width 0.2)
			(type default)
		)
		(layer "In5.Cu")
	)
	(gr_line
		(start 64.135 -51.943)
		(end 63.246 -52.832)
		(stroke
			(width 0.381)
			(type default)
		)
		(layer "In5.Cu")
	)
	(gr_line
		(start 64.262 -22.606)
		(end 63.373 -23.495)
		(stroke
			(width 0.381)
			(type default)
		)
		(layer "In5.Cu")
	)
	(gr_arc
		(start 64.389 -15.0876)
		(mid 64.77 -14.7066)
		(end 64.389 -14.3256)
		(stroke
			(width 0.2)
			(type default)
		)
		(layer "In5.Cu")
	)
	(gr_line
		(start 64.389 -14.3256)
		(end 63.627254 -14.3256)
		(stroke
			(width 0.2)
			(type default)
		)
		(layer "In5.Cu")
	)
	(gr_line
		(start 65.151 -51.943)
		(end 64.135 -51.943)
		(stroke
			(width 0.381)
			(type default)
		)
		(layer "In5.Cu")
	)
	(gr_line
		(start 65.786 -15.0622)
		(end 66.547746 -15.0622)
		(stroke
			(width 0.2)
			(type default)
		)
		(layer "In5.Cu")
	)
	(gr_arc
		(start 65.786 -14.3002)
		(mid 65.405 -14.6812)
		(end 65.786 -15.0622)
		(stroke
			(width 0.2)
			(type default)
		)
		(layer "In5.Cu")
	)
	(gr_arc
		(start 66.547746 -15.0622)
		(mid 66.929 -14.681327)
		(end 66.548 -14.3002)
		(stroke
			(width 0.2)
			(type default)
		)
		(layer "In5.Cu")
	)
	(gr_line
		(start 66.548 -14.3002)
		(end 65.786 -14.3002)
		(stroke
			(width 0.2)
			(type default)
		)
		(layer "In5.Cu")
	)
	(gr_line
		(start 67.34556 -10.668)
		(end 68.302886 -10.668)
		(stroke
			(width 0.2)
			(type default)
		)
		(layer "In5.Cu")
	)
	(gr_arc
		(start 67.34556 -9.90092)
		(mid 66.96202 -10.28446)
		(end 67.34556 -10.668)
		(stroke
			(width 0.2)
			(type default)
		)
		(layer "In5.Cu")
	)
	(gr_line
		(start 67.818 -22.606)
		(end 64.262 -22.606)
		(stroke
			(width 0.381)
			(type default)
		)
		(layer "In5.Cu")
	)
	(gr_line
		(start 68.072 -49.022)
		(end 65.151 -51.943)
		(stroke
			(width 0.381)
			(type default)
		)
		(layer "In5.Cu")
	)
	(gr_line
		(start 68.072 -46.609)
		(end 68.072 -49.022)
		(stroke
			(width 0.381)
			(type default)
		)
		(layer "In5.Cu")
	)
	(gr_line
		(start 68.072 -14.98854)
		(end 68.834 -14.98854)
		(stroke
			(width 0.2)
			(type default)
		)
		(layer "In5.Cu")
	)
	(gr_arc
		(start 68.072254 -14.22146)
		(mid 67.68846 -14.604873)
		(end 68.072 -14.98854)
		(stroke
			(width 0.2)
			(type default)
		)
		(layer "In5.Cu")
	)
	(gr_arc
		(start 68.302886 -10.668)
		(mid 68.68668 -10.284587)
		(end 68.30314 -9.90092)
		(stroke
			(width 0.2)
			(type default)
		)
		(layer "In5.Cu")
	)
	(gr_line
		(start 68.30314 -9.90092)
		(end 67.34556 -9.90092)
		(stroke
			(width 0.2)
			(type default)
		)
		(layer "In5.Cu")
	)
	(gr_line
		(start 68.58 -23.368)
		(end 67.818 -22.606)
		(stroke
			(width 0.381)
			(type default)
		)
		(layer "In5.Cu")
	)
	(gr_arc
		(start 68.75145 -28.403296)
		(mid 69.133212 -28.788614)
		(end 69.51853 -28.406852)
		(stroke
			(width 0.2)
			(type default)
		)
		(layer "In5.Cu")
	)
	(gr_line
		(start 68.75526 -27.51963)
		(end 68.75145 -28.403296)
		(stroke
			(width 0.2)
			(type default)
		)
		(layer "In5.Cu")
	)
	(gr_arc
		(start 68.834 -14.98854)
		(mid 69.21754 -14.605)
		(end 68.834 -14.22146)
		(stroke
			(width 0.2)
			(type default)
		)
		(layer "In5.Cu")
	)
	(gr_line
		(start 68.834 -14.22146)
		(end 68.072254 -14.22146)
		(stroke
			(width 0.2)
			(type default)
		)
		(layer "In5.Cu")
	)
	(gr_line
		(start 69.51853 -28.406852)
		(end 69.52234 -27.52344)
		(stroke
			(width 0.2)
			(type default)
		)
		(layer "In5.Cu")
	)
	(gr_arc
		(start 69.52234 -27.52344)
		(mid 69.140705 -27.138123)
		(end 68.75526 -27.51963)
		(stroke
			(width 0.2)
			(type default)
		)
		(layer "In5.Cu")
	)
	(gr_line
		(start 70.104 -44.577)
		(end 68.072 -46.609)
		(stroke
			(width 0.381)
			(type default)
		)
		(layer "In5.Cu")
	)
	(gr_line
		(start 71.370952 -10.668)
		(end 72.328532 -10.668)
		(stroke
			(width 0.2)
			(type default)
		)
		(layer "In5.Cu")
	)
	(gr_arc
		(start 71.371206 -9.90092)
		(mid 70.987412 -10.284333)
		(end 71.370952 -10.668)
		(stroke
			(width 0.2)
			(type default)
		)
		(layer "In5.Cu")
	)
	(gr_line
		(start 72.009 -18.034)
		(end 61.722 -18.034)
		(stroke
			(width 0.381)
			(type default)
		)
		(layer "In5.Cu")
	)
	(gr_arc
		(start 72.328532 -10.668)
		(mid 72.712072 -10.28446)
		(end 72.328532 -9.90092)
		(stroke
			(width 0.2)
			(type default)
		)
		(layer "In5.Cu")
	)
	(gr_line
		(start 72.328532 -9.90092)
		(end 71.371206 -9.90092)
		(stroke
			(width 0.2)
			(type default)
		)
		(layer "In5.Cu")
	)
	(gr_line
		(start 72.39 -23.368)
		(end 68.58 -23.368)
		(stroke
			(width 0.381)
			(type default)
		)
		(layer "In5.Cu")
	)
	(gr_line
		(start 72.517 -18.542)
		(end 72.009 -18.034)
		(stroke
			(width 0.381)
			(type default)
		)
		(layer "In5.Cu")
	)
	(gr_line
		(start 72.8472 -15.09014)
		(end 73.7108 -15.09014)
		(stroke
			(width 0.2)
			(type default)
		)
		(layer "In5.Cu")
	)
	(gr_arc
		(start 72.847454 -14.32306)
		(mid 72.46366 -14.706473)
		(end 72.8472 -15.09014)
		(stroke
			(width 0.2)
			(type default)
		)
		(layer "In5.Cu")
	)
	(gr_line
		(start 73.279 -22.479)
		(end 72.39 -23.368)
		(stroke
			(width 0.381)
			(type default)
		)
		(layer "In5.Cu")
	)
	(gr_line
		(start 73.533 -44.577)
		(end 70.104 -44.577)
		(stroke
			(width 0.381)
			(type default)
		)
		(layer "In5.Cu")
	)
	(gr_arc
		(start 73.7108 -15.09014)
		(mid 74.09434 -14.7066)
		(end 73.7108 -14.32306)
		(stroke
			(width 0.2)
			(type default)
		)
		(layer "In5.Cu")
	)
	(gr_line
		(start 73.7108 -14.32306)
		(end 72.847454 -14.32306)
		(stroke
			(width 0.2)
			(type default)
		)
		(layer "In5.Cu")
	)
	(gr_line
		(start 75.370944 -10.668)
		(end 76.328524 -10.668)
		(stroke
			(width 0.2)
			(type default)
		)
		(layer "In5.Cu")
	)
	(gr_arc
		(start 75.371198 -9.90092)
		(mid 74.987404 -10.284333)
		(end 75.370944 -10.668)
		(stroke
			(width 0.2)
			(type default)
		)
		(layer "In5.Cu")
	)
	(gr_line
		(start 75.946 -42.164)
		(end 73.533 -44.577)
		(stroke
			(width 0.381)
			(type default)
		)
		(layer "In5.Cu")
	)
	(gr_line
		(start 76.2 -22.479)
		(end 73.279 -22.479)
		(stroke
			(width 0.381)
			(type default)
		)
		(layer "In5.Cu")
	)
	(gr_arc
		(start 76.328524 -10.668)
		(mid 76.712064 -10.28446)
		(end 76.328524 -9.90092)
		(stroke
			(width 0.2)
			(type default)
		)
		(layer "In5.Cu")
	)
	(gr_line
		(start 76.328524 -9.90092)
		(end 75.371198 -9.90092)
		(stroke
			(width 0.2)
			(type default)
		)
		(layer "In5.Cu")
	)
	(gr_line
		(start 77.216 -23.495)
		(end 76.2 -22.479)
		(stroke
			(width 0.381)
			(type default)
		)
		(layer "In5.Cu")
	)
	(gr_line
		(start 77.4192 -14.96314)
		(end 78.2828 -14.96314)
		(stroke
			(width 0.2)
			(type default)
		)
		(layer "In5.Cu")
	)
	(gr_arc
		(start 77.419454 -14.19606)
		(mid 77.03566 -14.579473)
		(end 77.4192 -14.96314)
		(stroke
			(width 0.2)
			(type default)
		)
		(layer "In5.Cu")
	)
	(gr_arc
		(start 77.972666 -29.55925)
		(mid 77.633576 -29.90596)
		(end 77.980286 -30.24505)
		(stroke
			(width 0.2)
			(type default)
		)
		(layer "In5.Cu")
	)
	(gr_line
		(start 77.978 -42.164)
		(end 75.946 -42.164)
		(stroke
			(width 0.381)
			(type default)
		)
		(layer "In5.Cu")
	)
	(gr_line
		(start 77.980286 -30.24505)
		(end 78.538832 -30.2387)
		(stroke
			(width 0.2)
			(type default)
		)
		(layer "In5.Cu")
	)
	(gr_line
		(start 78.090014 -31.508446)
		(end 78.648814 -31.53283)
		(stroke
			(width 0.2)
			(type default)
		)
		(layer "In5.Cu")
	)
	(gr_arc
		(start 78.12024 -30.823154)
		(mid 77.762614 -31.150687)
		(end 78.090014 -31.508446)
		(stroke
			(width 0.2)
			(type default)
		)
		(layer "In5.Cu")
	)
	(gr_arc
		(start 78.2828 -14.96314)
		(mid 78.66634 -14.5796)
		(end 78.2828 -14.19606)
		(stroke
			(width 0.2)
			(type default)
		)
		(layer "In5.Cu")
	)
	(gr_line
		(start 78.2828 -14.19606)
		(end 77.419454 -14.19606)
		(stroke
			(width 0.2)
			(type default)
		)
		(layer "In5.Cu")
	)
	(gr_line
		(start 78.531466 -29.5529)
		(end 77.972666 -29.55925)
		(stroke
			(width 0.2)
			(type default)
		)
		(layer "In5.Cu")
	)
	(gr_arc
		(start 78.538832 -30.2387)
		(mid 78.878175 -29.892117)
		(end 78.531466 -29.5529)
		(stroke
			(width 0.2)
			(type default)
		)
		(layer "In5.Cu")
	)
	(gr_arc
		(start 78.648814 -31.53283)
		(mid 79.006446 -31.20517)
		(end 78.678786 -30.847538)
		(stroke
			(width 0.2)
			(type default)
		)
		(layer "In5.Cu")
	)
	(gr_line
		(start 78.678786 -30.847538)
		(end 78.12024 -30.823154)
		(stroke
			(width 0.2)
			(type default)
		)
		(layer "In5.Cu")
	)
	(gr_line
		(start 79.370936 -10.7188)
		(end 80.328516 -10.7188)
		(stroke
			(width 0.2)
			(type default)
		)
		(layer "In5.Cu")
	)
	(gr_arc
		(start 79.37119 -9.95172)
		(mid 78.987396 -10.335133)
		(end 79.370936 -10.7188)
		(stroke
			(width 0.2)
			(type default)
		)
		(layer "In5.Cu")
	)
	(gr_line
		(start 79.629 -23.495)
		(end 77.216 -23.495)
		(stroke
			(width 0.381)
			(type default)
		)
		(layer "In5.Cu")
	)
	(gr_line
		(start 80.2132 -14.96314)
		(end 81.076546 -14.96314)
		(stroke
			(width 0.2)
			(type default)
		)
		(layer "In5.Cu")
	)
	(gr_arc
		(start 80.2132 -14.19606)
		(mid 79.82966 -14.5796)
		(end 80.2132 -14.96314)
		(stroke
			(width 0.2)
			(type default)
		)
		(layer "In5.Cu")
	)
	(gr_arc
		(start 80.2259 -54.685946)
		(mid 80.568673 -55.0291)
		(end 80.9117 -54.6862)
		(stroke
			(width 0.2)
			(type default)
		)
		(layer "In5.Cu")
	)
	(gr_line
		(start 80.2259 -54.1274)
		(end 80.2259 -54.685946)
		(stroke
			(width 0.2)
			(type default)
		)
		(layer "In5.Cu")
	)
	(gr_line
		(start 80.264 -60.7187)
		(end 81.0514 -60.7187)
		(stroke
			(width 0.2)
			(type default)
		)
		(layer "In5.Cu")
	)
	(gr_line
		(start 80.264 -39.878)
		(end 77.978 -42.164)
		(stroke
			(width 0.381)
			(type default)
		)
		(layer "In5.Cu")
	)
	(gr_line
		(start 80.264 -37.973)
		(end 80.264 -39.878)
		(stroke
			(width 0.381)
			(type default)
		)
		(layer "In5.Cu")
	)
	(gr_arc
		(start 80.264254 -60.0329)
		(mid 79.9211 -60.375673)
		(end 80.264 -60.7187)
		(stroke
			(width 0.2)
			(type default)
		)
		(layer "In5.Cu")
	)
	(gr_arc
		(start 80.328516 -10.7188)
		(mid 80.712056 -10.33526)
		(end 80.328516 -9.95172)
		(stroke
			(width 0.2)
			(type default)
		)
		(layer "In5.Cu")
	)
	(gr_line
		(start 80.328516 -9.95172)
		(end 79.37119 -9.95172)
		(stroke
			(width 0.2)
			(type default)
		)
		(layer "In5.Cu")
	)
	(gr_line
		(start 80.391 -18.542)
		(end 72.517 -18.542)
		(stroke
			(width 0.381)
			(type default)
		)
		(layer "In5.Cu")
	)
	(gr_line
		(start 80.518 -22.606)
		(end 79.629 -23.495)
		(stroke
			(width 0.381)
			(type default)
		)
		(layer "In5.Cu")
	)
	(gr_line
		(start 80.645 -18.796)
		(end 80.391 -18.542)
		(stroke
			(width 0.381)
			(type default)
		)
		(layer "In5.Cu")
	)
	(gr_line
		(start 80.9117 -54.6862)
		(end 80.9117 -54.1274)
		(stroke
			(width 0.2)
			(type default)
		)
		(layer "In5.Cu")
	)
	(gr_arc
		(start 80.9117 -54.1274)
		(mid 80.5688 -53.7845)
		(end 80.2259 -54.1274)
		(stroke
			(width 0.2)
			(type default)
		)
		(layer "In5.Cu")
	)
	(gr_line
		(start 81.026 -22.606)
		(end 80.518 -22.606)
		(stroke
			(width 0.381)
			(type default)
		)
		(layer "In5.Cu")
	)
	(gr_arc
		(start 81.0514 -60.7187)
		(mid 81.3943 -60.3758)
		(end 81.0514 -60.0329)
		(stroke
			(width 0.2)
			(type default)
		)
		(layer "In5.Cu")
	)
	(gr_line
		(start 81.0514 -60.0329)
		(end 80.264254 -60.0329)
		(stroke
			(width 0.2)
			(type default)
		)
		(layer "In5.Cu")
	)
	(gr_arc
		(start 81.076546 -14.96314)
		(mid 81.46034 -14.579727)
		(end 81.0768 -14.19606)
		(stroke
			(width 0.2)
			(type default)
		)
		(layer "In5.Cu")
	)
	(gr_line
		(start 81.0768 -14.19606)
		(end 80.2132 -14.19606)
		(stroke
			(width 0.2)
			(type default)
		)
		(layer "In5.Cu")
	)
	(gr_line
		(start 81.28 -22.86)
		(end 81.026 -22.606)
		(stroke
			(width 0.381)
			(type default)
		)
		(layer "In5.Cu")
	)
	(gr_arc
		(start 81.3435 -53.593746)
		(mid 81.686273 -53.9369)
		(end 82.0293 -53.594)
		(stroke
			(width 0.2)
			(type default)
		)
		(layer "In5.Cu")
	)
	(gr_line
		(start 81.3435 -53.0098)
		(end 81.3435 -53.593746)
		(stroke
			(width 0.2)
			(type default)
		)
		(layer "In5.Cu")
	)
	(gr_line
		(start 81.407 -36.83)
		(end 80.264 -37.973)
		(stroke
			(width 0.381)
			(type default)
		)
		(layer "In5.Cu")
	)
	(gr_line
		(start 81.407 -36.068)
		(end 81.407 -36.83)
		(stroke
			(width 0.381)
			(type default)
		)
		(layer "In5.Cu")
	)
	(gr_line
		(start 82.0293 -53.594)
		(end 82.0293 -53.0098)
		(stroke
			(width 0.2)
			(type default)
		)
		(layer "In5.Cu")
	)
	(gr_arc
		(start 82.0293 -53.0098)
		(mid 81.6864 -52.6669)
		(end 81.3435 -53.0098)
		(stroke
			(width 0.2)
			(type default)
		)
		(layer "In5.Cu")
	)
	(gr_line
		(start 82.042 -35.433)
		(end 81.407 -36.068)
		(stroke
			(width 0.381)
			(type default)
		)
		(layer "In5.Cu")
	)
	(gr_line
		(start 82.296 -14.32814)
		(end 83.1596 -14.32814)
		(stroke
			(width 0.2)
			(type default)
		)
		(layer "In5.Cu")
	)
	(gr_arc
		(start 82.296254 -13.56106)
		(mid 81.91246 -13.944473)
		(end 82.296 -14.32814)
		(stroke
			(width 0.2)
			(type default)
		)
		(layer "In5.Cu")
	)
	(gr_arc
		(start 82.803746 -55.65902)
		(mid 82.83702 -56.146446)
		(end 83.324446 -56.113172)
		(stroke
			(width 0.2)
			(type default)
		)
		(layer "In5.Cu")
	)
	(gr_arc
		(start 83.1596 -14.32814)
		(mid 83.54314 -13.9446)
		(end 83.1596 -13.56106)
		(stroke
			(width 0.2)
			(type default)
		)
		(layer "In5.Cu")
	)
	(gr_line
		(start 83.1596 -13.56106)
		(end 82.296254 -13.56106)
		(stroke
			(width 0.2)
			(type default)
		)
		(layer "In5.Cu")
	)
	(gr_line
		(start 83.18119 -55.226204)
		(end 82.803746 -55.65902)
		(stroke
			(width 0.2)
			(type default)
		)
		(layer "In5.Cu")
	)
	(gr_arc
		(start 83.309968 -59.661806)
		(mid 83.308952 -60.146946)
		(end 83.794092 -60.147962)
		(stroke
			(width 0.2)
			(type default)
		)
		(layer "In5.Cu")
	)
	(gr_line
		(start 83.324446 -56.113172)
		(end 83.701636 -55.68061)
		(stroke
			(width 0.2)
			(type default)
		)
		(layer "In5.Cu")
	)
	(gr_line
		(start 83.388962 -10.79627)
		(end 84.310474 -10.79627)
		(stroke
			(width 0.2)
			(type default)
		)
		(layer "In5.Cu")
	)
	(gr_arc
		(start 83.389216 -10.02919)
		(mid 83.005422 -10.412603)
		(end 83.388962 -10.79627)
		(stroke
			(width 0.2)
			(type default)
		)
		(layer "In5.Cu")
	)
	(gr_line
		(start 83.439 -62.992)
		(end 93.599 -62.992)
		(stroke
			(width 0.381)
			(type default)
		)
		(layer "In5.Cu")
	)
	(gr_arc
		(start 83.701636 -55.68061)
		(mid 83.668625 -55.193446)
		(end 83.18119 -55.226204)
		(stroke
			(width 0.2)
			(type default)
		)
		(layer "In5.Cu")
	)
	(gr_line
		(start 83.794092 -60.147962)
		(end 84.348828 -59.595258)
		(stroke
			(width 0.2)
			(type default)
		)
		(layer "In5.Cu")
	)
	(gr_line
		(start 83.82 -18.796)
		(end 80.645 -18.796)
		(stroke
			(width 0.381)
			(type default)
		)
		(layer "In5.Cu")
	)
	(gr_line
		(start 83.868006 -59.106054)
		(end 83.309968 -59.661806)
		(stroke
			(width 0.2)
			(type default)
		)
		(layer "In5.Cu")
	)
	(gr_arc
		(start 83.885024 -54.567836)
		(mid 84.22386 -54.91988)
		(end 84.575904 -54.581044)
		(stroke
			(width 0.2)
			(type default)
		)
		(layer "In5.Cu")
	)
	(gr_line
		(start 83.895692 -54.009036)
		(end 83.885024 -54.567836)
		(stroke
			(width 0.2)
			(type default)
		)
		(layer "In5.Cu")
	)
	(gr_line
		(start 83.947 -10.922)
		(end 84.201 -11.176)
		(stroke
			(width 0.381)
			(type default)
		)
		(layer "In5.Cu")
	)
	(gr_line
		(start 84.201 -11.176)
		(end 84.709 -11.176)
		(stroke
			(width 0.381)
			(type default)
		)
		(layer "In5.Cu")
	)
	(gr_arc
		(start 84.310474 -10.79627)
		(mid 84.694014 -10.41273)
		(end 84.310474 -10.02919)
		(stroke
			(width 0.2)
			(type default)
		)
		(layer "In5.Cu")
	)
	(gr_line
		(start 84.310474 -10.02919)
		(end 83.389216 -10.02919)
		(stroke
			(width 0.2)
			(type default)
		)
		(layer "In5.Cu")
	)
	(gr_line
		(start 84.328 -18.288)
		(end 83.82 -18.796)
		(stroke
			(width 0.381)
			(type default)
		)
		(layer "In5.Cu")
	)
	(gr_arc
		(start 84.348828 -59.595258)
		(mid 84.354625 -59.108766)
		(end 83.868006 -59.106054)
		(stroke
			(width 0.2)
			(type default)
		)
		(layer "In5.Cu")
	)
	(gr_line
		(start 84.575904 -54.581044)
		(end 84.586572 -54.022498)
		(stroke
			(width 0.2)
			(type default)
		)
		(layer "In5.Cu")
	)
	(gr_arc
		(start 84.586572 -54.022498)
		(mid 84.247863 -53.670456)
		(end 83.895692 -54.009036)
		(stroke
			(width 0.2)
			(type default)
		)
		(layer "In5.Cu")
	)
	(gr_line
		(start 84.709 -11.176)
		(end 85.979 -12.446)
		(stroke
			(width 0.381)
			(type default)
		)
		(layer "In5.Cu")
	)
	(gr_arc
		(start 85.330538 -55.356506)
		(mid 85.670517 -55.707536)
		(end 86.021418 -55.367428)
		(stroke
			(width 0.2)
			(type default)
		)
		(layer "In5.Cu")
	)
	(gr_line
		(start 85.339174 -54.79034)
		(end 85.330538 -55.356506)
		(stroke
			(width 0.2)
			(type default)
		)
		(layer "In5.Cu")
	)
	(gr_arc
		(start 85.741764 -53.758592)
		(mid 86.080727 -54.110638)
		(end 86.432644 -53.771546)
		(stroke
			(width 0.2)
			(type default)
		)
		(layer "In5.Cu")
	)
	(gr_line
		(start 85.752178 -53.19522)
		(end 85.741764 -53.758592)
		(stroke
			(width 0.2)
			(type default)
		)
		(layer "In5.Cu")
	)
	(gr_line
		(start 85.979 -12.446)
		(end 93.091 -12.446)
		(stroke
			(width 0.381)
			(type default)
		)
		(layer "In5.Cu")
	)
	(gr_line
		(start 86.021418 -55.367428)
		(end 86.030054 -54.801008)
		(stroke
			(width 0.2)
			(type default)
		)
		(layer "In5.Cu")
	)
	(gr_arc
		(start 86.030054 -54.801008)
		(mid 85.689948 -54.450234)
		(end 85.339174 -54.79034)
		(stroke
			(width 0.2)
			(type default)
		)
		(layer "In5.Cu")
	)
	(gr_line
		(start 86.432644 -53.771546)
		(end 86.443058 -53.20792)
		(stroke
			(width 0.2)
			(type default)
		)
		(layer "In5.Cu")
	)
	(gr_arc
		(start 86.443058 -53.20792)
		(mid 86.103968 -52.85613)
		(end 85.752178 -53.19522)
		(stroke
			(width 0.2)
			(type default)
		)
		(layer "In5.Cu")
	)
	(gr_line
		(start 86.741 -18.288)
		(end 84.328 -18.288)
		(stroke
			(width 0.381)
			(type default)
		)
		(layer "In5.Cu")
	)
	(gr_arc
		(start 86.826852 -54.834028)
		(mid 87.165307 -55.186583)
		(end 87.517732 -54.847998)
		(stroke
			(width 0.2)
			(type default)
		)
		(layer "In5.Cu")
	)
	(gr_line
		(start 86.838028 -54.270402)
		(end 86.826852 -54.834028)
		(stroke
			(width 0.2)
			(type default)
		)
		(layer "In5.Cu")
	)
	(gr_line
		(start 86.868 -35.433)
		(end 82.042 -35.433)
		(stroke
			(width 0.381)
			(type default)
		)
		(layer "In5.Cu")
	)
	(gr_line
		(start 87.376 -34.925)
		(end 86.868 -35.433)
		(stroke
			(width 0.381)
			(type default)
		)
		(layer "In5.Cu")
	)
	(gr_line
		(start 87.517732 -54.847998)
		(end 87.528908 -54.284118)
		(stroke
			(width 0.2)
			(type default)
		)
		(layer "In5.Cu")
	)
	(gr_arc
		(start 87.528908 -54.284118)
		(mid 87.190326 -53.93182)
		(end 86.838028 -54.270402)
		(stroke
			(width 0.2)
			(type default)
		)
		(layer "In5.Cu")
	)
	(gr_line
		(start 87.757 -34.925)
		(end 87.376 -34.925)
		(stroke
			(width 0.381)
			(type default)
		)
		(layer "In5.Cu")
	)
	(gr_line
		(start 87.940896 -53.421534)
		(end 87.95893 -53.98008)
		(stroke
			(width 0.2)
			(type default)
		)
		(layer "In5.Cu")
	)
	(gr_line
		(start 87.943436 -53.421534)
		(end 87.940896 -53.421534)
		(stroke
			(width 0.2)
			(type default)
		)
		(layer "In5.Cu")
	)
	(gr_line
		(start 87.95893 -53.98008)
		(end 87.96147 -53.98008)
		(stroke
			(width 0.2)
			(type default)
		)
		(layer "In5.Cu")
	)
	(gr_arc
		(start 87.96147 -53.98008)
		(mid 88.317832 -54.31409)
		(end 88.651842 -53.957728)
		(stroke
			(width 0.2)
			(type default)
		)
		(layer "In5.Cu")
	)
	(gr_arc
		(start 88.633808 -53.399182)
		(mid 88.277446 -53.065172)
		(end 87.943436 -53.421534)
		(stroke
			(width 0.2)
			(type default)
		)
		(layer "In5.Cu")
	)
	(gr_line
		(start 88.636094 -53.399182)
		(end 88.633808 -53.399182)
		(stroke
			(width 0.2)
			(type default)
		)
		(layer "In5.Cu")
	)
	(gr_line
		(start 88.636348 -53.399436)
		(end 88.636094 -53.399182)
		(stroke
			(width 0.2)
			(type default)
		)
		(layer "In5.Cu")
	)
	(gr_line
		(start 88.646 -16.383)
		(end 86.741 -18.288)
		(stroke
			(width 0.381)
			(type default)
		)
		(layer "In5.Cu")
	)
	(gr_line
		(start 88.651842 -53.957728)
		(end 88.654382 -53.957728)
		(stroke
			(width 0.2)
			(type default)
		)
		(layer "In5.Cu")
	)
	(gr_line
		(start 88.654382 -53.957728)
		(end 88.636348 -53.399436)
		(stroke
			(width 0.2)
			(type default)
		)
		(layer "In5.Cu")
	)
	(gr_line
		(start 89.154 -22.86)
		(end 81.28 -22.86)
		(stroke
			(width 0.381)
			(type default)
		)
		(layer "In5.Cu")
	)
	(gr_line
		(start 89.281 -33.401)
		(end 87.757 -34.925)
		(stroke
			(width 0.381)
			(type default)
		)
		(layer "In5.Cu")
	)
	(gr_arc
		(start 89.415874 -54.043326)
		(mid 89.727024 -54.420008)
		(end 90.103706 -54.108858)
		(stroke
			(width 0.2)
			(type default)
		)
		(layer "In5.Cu")
	)
	(gr_line
		(start 89.46896 -53.486812)
		(end 89.415874 -54.043326)
		(stroke
			(width 0.2)
			(type default)
		)
		(layer "In5.Cu")
	)
	(gr_line
		(start 89.535 -22.479)
		(end 89.154 -22.86)
		(stroke
			(width 0.381)
			(type default)
		)
		(layer "In5.Cu")
	)
	(gr_line
		(start 89.535 -21.59)
		(end 89.535 -22.479)
		(stroke
			(width 0.381)
			(type default)
		)
		(layer "In5.Cu")
	)
	(gr_line
		(start 90.103706 -54.108858)
		(end 90.156792 -53.552598)
		(stroke
			(width 0.2)
			(type default)
		)
		(layer "In5.Cu")
	)
	(gr_arc
		(start 90.156792 -53.552598)
		(mid 89.845768 -53.175928)
		(end 89.46896 -53.486812)
		(stroke
			(width 0.2)
			(type default)
		)
		(layer "In5.Cu")
	)
	(gr_line
		(start 90.681556 -53.93817)
		(end 90.684096 -53.938424)
		(stroke
			(width 0.2)
			(type default)
		)
		(layer "In5.Cu")
	)
	(gr_arc
		(start 90.684096 -53.938424)
		(mid 91.010994 -54.30139)
		(end 91.37396 -53.974492)
		(stroke
			(width 0.2)
			(type default)
		)
		(layer "In5.Cu")
	)
	(gr_line
		(start 90.71102 -53.377592)
		(end 90.681556 -53.93817)
		(stroke
			(width 0.2)
			(type default)
		)
		(layer "In5.Cu")
	)
	(gr_line
		(start 90.71356 -53.377846)
		(end 90.71102 -53.377592)
		(stroke
			(width 0.2)
			(type default)
		)
		(layer "In5.Cu")
	)
	(gr_line
		(start 90.73769 -54.954932)
		(end 90.73896 -54.956964)
		(stroke
			(width 0.2)
			(type default)
		)
		(layer "In5.Cu")
	)
	(gr_line
		(start 90.73769 -54.954678)
		(end 90.73769 -54.954932)
		(stroke
			(width 0.2)
			(type default)
		)
		(layer "In5.Cu")
	)
	(gr_arc
		(start 90.73896 -54.956964)
		(mid 90.631264 -55.433468)
		(end 91.107768 -55.541164)
		(stroke
			(width 0.2)
			(type default)
		)
		(layer "In5.Cu")
	)
	(gr_line
		(start 91.107768 -55.541164)
		(end 91.109038 -55.543196)
		(stroke
			(width 0.2)
			(type default)
		)
		(layer "In5.Cu")
	)
	(gr_line
		(start 91.109038 -55.543196)
		(end 91.581732 -55.244746)
		(stroke
			(width 0.2)
			(type default)
		)
		(layer "In5.Cu")
	)
	(gr_line
		(start 91.210384 -54.656482)
		(end 90.73769 -54.954678)
		(stroke
			(width 0.2)
			(type default)
		)
		(layer "In5.Cu")
	)
	(gr_line
		(start 91.211654 -54.658514)
		(end 91.210384 -54.656482)
		(stroke
			(width 0.2)
			(type default)
		)
		(layer "In5.Cu")
	)
	(gr_line
		(start 91.37396 -53.974492)
		(end 91.3765 -53.974746)
		(stroke
			(width 0.2)
			(type default)
		)
		(layer "In5.Cu")
	)
	(gr_line
		(start 91.3765 -53.974746)
		(end 91.405964 -53.414422)
		(stroke
			(width 0.2)
			(type default)
		)
		(layer "In5.Cu")
	)
	(gr_arc
		(start 91.403424 -53.414168)
		(mid 91.076653 -53.050941)
		(end 90.71356 -53.377846)
		(stroke
			(width 0.2)
			(type default)
		)
		(layer "In5.Cu")
	)
	(gr_line
		(start 91.40571 -53.414168)
		(end 91.403424 -53.414168)
		(stroke
			(width 0.2)
			(type default)
		)
		(layer "In5.Cu")
	)
	(gr_line
		(start 91.405964 -53.414422)
		(end 91.40571 -53.414168)
		(stroke
			(width 0.2)
			(type default)
		)
		(layer "In5.Cu")
	)
	(gr_arc
		(start 91.580462 -55.242714)
		(mid 91.688158 -54.76621)
		(end 91.211654 -54.658514)
		(stroke
			(width 0.2)
			(type default)
		)
		(layer "In5.Cu")
	)
	(gr_line
		(start 91.581732 -55.244746)
		(end 91.580462 -55.242714)
		(stroke
			(width 0.2)
			(type default)
		)
		(layer "In5.Cu")
	)
	(gr_line
		(start 92.075 -33.401)
		(end 89.281 -33.401)
		(stroke
			(width 0.381)
			(type default)
		)
		(layer "In5.Cu")
	)
	(gr_line
		(start 92.456 -33.02)
		(end 92.075 -33.401)
		(stroke
			(width 0.381)
			(type default)
		)
		(layer "In5.Cu")
	)
	(gr_line
		(start 92.71 -16.383)
		(end 88.646 -16.383)
		(stroke
			(width 0.381)
			(type default)
		)
		(layer "In5.Cu")
	)
	(gr_line
		(start 93.091 -12.446)
		(end 93.599 -11.938)
		(stroke
			(width 0.381)
			(type default)
		)
		(layer "In5.Cu")
	)
	(gr_line
		(start 93.599 -62.992)
		(end 95.377 -61.214)
		(stroke
			(width 0.381)
			(type default)
		)
		(layer "In5.Cu")
	)
	(gr_line
		(start 93.599 -56.388)
		(end 93.599 -53.721)
		(stroke
			(width 0.381)
			(type default)
		)
		(layer "In5.Cu")
	)
	(gr_line
		(start 93.599 -53.721)
		(end 93.98 -53.34)
		(stroke
			(width 0.381)
			(type default)
		)
		(layer "In5.Cu")
	)
	(gr_line
		(start 93.599 -11.938)
		(end 93.599 -10.668)
		(stroke
			(width 0.381)
			(type default)
		)
		(layer "In5.Cu")
	)
	(gr_line
		(start 93.599 -10.668)
		(end 94.107 -10.16)
		(stroke
			(width 0.381)
			(type default)
		)
		(layer "In5.Cu")
	)
	(gr_line
		(start 93.726 -17.399)
		(end 89.535 -21.59)
		(stroke
			(width 0.381)
			(type default)
		)
		(layer "In5.Cu")
	)
	(gr_line
		(start 93.726 -17.399)
		(end 92.71 -16.383)
		(stroke
			(width 0.381)
			(type default)
		)
		(layer "In5.Cu")
	)
	(gr_line
		(start 93.98 -53.34)
		(end 94.742 -53.34)
		(stroke
			(width 0.381)
			(type default)
		)
		(layer "In5.Cu")
	)
	(gr_line
		(start 94.107 -10.16)
		(end 95.377 -10.16)
		(stroke
			(width 0.381)
			(type default)
		)
		(layer "In5.Cu")
	)
	(gr_line
		(start 94.742 -53.34)
		(end 96.647 -51.435)
		(stroke
			(width 0.381)
			(type default)
		)
		(layer "In5.Cu")
	)
	(gr_line
		(start 94.742 -33.02)
		(end 92.456 -33.02)
		(stroke
			(width 0.381)
			(type default)
		)
		(layer "In5.Cu")
	)
	(gr_line
		(start 95.377 -61.214)
		(end 95.377 -58.166)
		(stroke
			(width 0.381)
			(type default)
		)
		(layer "In5.Cu")
	)
	(gr_line
		(start 95.377 -58.166)
		(end 93.599 -56.388)
		(stroke
			(width 0.381)
			(type default)
		)
		(layer "In5.Cu")
	)
	(gr_line
		(start 95.377 -10.16)
		(end 96.393 -9.144)
		(stroke
			(width 0.381)
			(type default)
		)
		(layer "In5.Cu")
	)
	(gr_line
		(start 96.012 -49.276)
		(end 96.012 -45.085)
		(stroke
			(width 0.381)
			(type default)
		)
		(layer "In5.Cu")
	)
	(gr_line
		(start 96.012 -45.085)
		(end 96.52 -44.577)
		(stroke
			(width 0.381)
			(type default)
		)
		(layer "In5.Cu")
	)
	(gr_line
		(start 96.139 -34.925)
		(end 96.139 -34.417)
		(stroke
			(width 0.381)
			(type default)
		)
		(layer "In5.Cu")
	)
	(gr_line
		(start 96.139 -34.417)
		(end 94.742 -33.02)
		(stroke
			(width 0.381)
			(type default)
		)
		(layer "In5.Cu")
	)
	(gr_line
		(start 96.393 -9.144)
		(end 96.647 -9.144)
		(stroke
			(width 0.381)
			(type default)
		)
		(layer "In5.Cu")
	)
	(gr_line
		(start 96.52 -44.577)
		(end 97.282 -44.577)
		(stroke
			(width 0.381)
			(type default)
		)
		(layer "In5.Cu")
	)
	(gr_line
		(start 96.647 -51.435)
		(end 96.647 -49.911)
		(stroke
			(width 0.381)
			(type default)
		)
		(layer "In5.Cu")
	)
	(gr_line
		(start 96.647 -49.911)
		(end 96.012 -49.276)
		(stroke
			(width 0.381)
			(type default)
		)
		(layer "In5.Cu")
	)
	(gr_line
		(start 96.647 -35.433)
		(end 96.139 -34.925)
		(stroke
			(width 0.381)
			(type default)
		)
		(layer "In5.Cu")
	)
	(gr_line
		(start 96.647 -9.144)
		(end 97.028 -9.144)
		(stroke
			(width 0.381)
			(type default)
		)
		(layer "In5.Cu")
	)
	(gr_line
		(start 97.028 -9.144)
		(end 97.536 -9.652)
		(stroke
			(width 0.381)
			(type default)
		)
		(layer "In5.Cu")
	)
	(gr_line
		(start 97.282 -44.577)
		(end 97.79 -44.069)
		(stroke
			(width 0.381)
			(type default)
		)
		(layer "In5.Cu")
	)
	(gr_line
		(start 97.536 -13.589)
		(end 93.726 -17.399)
		(stroke
			(width 0.381)
			(type default)
		)
		(layer "In5.Cu")
	)
	(gr_line
		(start 97.536 -9.652)
		(end 97.536 -13.589)
		(stroke
			(width 0.381)
			(type default)
		)
		(layer "In5.Cu")
	)
	(gr_line
		(start 97.79 -44.069)
		(end 98.298 -44.069)
		(stroke
			(width 0.381)
			(type default)
		)
		(layer "In5.Cu")
	)
	(gr_line
		(start 98.298 -44.069)
		(end 98.933 -44.704)
		(stroke
			(width 0.381)
			(type default)
		)
		(layer "In5.Cu")
	)
	(gr_line
		(start 98.933 -44.704)
		(end 102.489 -44.704)
		(stroke
			(width 0.381)
			(type default)
		)
		(layer "In5.Cu")
	)
	(gr_line
		(start 99.187 -35.433)
		(end 96.647 -35.433)
		(stroke
			(width 0.381)
			(type default)
		)
		(layer "In5.Cu")
	)
	(gr_line
		(start 99.24542 -60.922154)
		(end 99.86518 -61.523372)
		(stroke
			(width 0.2)
			(type default)
		)
		(layer "In5.Cu")
	)
	(gr_line
		(start 99.247198 -60.920376)
		(end 99.24542 -60.922154)
		(stroke
			(width 0.2)
			(type default)
		)
		(layer "In5.Cu")
	)
	(gr_line
		(start 99.695 -35.941)
		(end 99.187 -35.433)
		(stroke
			(width 0.381)
			(type default)
		)
		(layer "In5.Cu")
	)
	(gr_arc
		(start 99.781106 -60.369704)
		(mid 99.238816 -60.378086)
		(end 99.247198 -60.920376)
		(stroke
			(width 0.2)
			(type default)
		)
		(layer "In5.Cu")
	)
	(gr_line
		(start 99.782884 -60.367926)
		(end 99.781106 -60.369704)
		(stroke
			(width 0.2)
			(type default)
		)
		(layer "In5.Cu")
	)
	(gr_line
		(start 99.86518 -61.523372)
		(end 99.865434 -61.523372)
		(stroke
			(width 0.2)
			(type default)
		)
		(layer "In5.Cu")
	)
	(gr_line
		(start 99.865434 -61.523372)
		(end 99.866958 -61.521848)
		(stroke
			(width 0.2)
			(type default)
		)
		(layer "In5.Cu")
	)
	(gr_arc
		(start 99.866958 -61.521848)
		(mid 100.409565 -61.513655)
		(end 100.40112 -60.971176)
		(stroke
			(width 0.2)
			(type default)
		)
		(layer "In5.Cu")
	)
	(gr_line
		(start 100.40112 -60.971176)
		(end 100.402898 -60.969398)
		(stroke
			(width 0.2)
			(type default)
		)
		(layer "In5.Cu")
	)
	(gr_line
		(start 100.402898 -60.969398)
		(end 99.782884 -60.367926)
		(stroke
			(width 0.2)
			(type default)
		)
		(layer "In5.Cu")
	)
	(gr_line
		(start 101.092 -35.941)
		(end 99.695 -35.941)
		(stroke
			(width 0.381)
			(type default)
		)
		(layer "In5.Cu")
	)
	(gr_line
		(start 101.185472 -62.20587)
		(end 101.795072 -62.817756)
		(stroke
			(width 0.2)
			(type default)
		)
		(layer "In5.Cu")
	)
	(gr_arc
		(start 101.734366 -61.66993)
		(mid 101.189299 -61.660676)
		(end 101.185472 -62.20587)
		(stroke
			(width 0.2)
			(type default)
		)
		(layer "In5.Cu")
	)
	(gr_arc
		(start 101.795072 -62.817756)
		(mid 102.337616 -62.818772)
		(end 102.338632 -62.276228)
		(stroke
			(width 0.2)
			(type default)
		)
		(layer "In5.Cu")
	)
	(gr_line
		(start 102.108 -36.957)
		(end 101.092 -35.941)
		(stroke
			(width 0.381)
			(type default)
		)
		(layer "In5.Cu")
	)
	(gr_line
		(start 102.338632 -62.276228)
		(end 101.734366 -61.66993)
		(stroke
			(width 0.2)
			(type default)
		)
		(layer "In5.Cu")
	)
	(gr_line
		(start 102.489 -44.704)
		(end 102.997 -44.196)
		(stroke
			(width 0.381)
			(type default)
		)
		(layer "In5.Cu")
	)
	(gr_line
		(start 102.489 -36.957)
		(end 102.108 -36.957)
		(stroke
			(width 0.381)
			(type default)
		)
		(layer "In5.Cu")
	)
	(gr_line
		(start 102.616 -42.291)
		(end 102.616 -41.148)
		(stroke
			(width 0.381)
			(type default)
		)
		(layer "In5.Cu")
	)
	(gr_line
		(start 102.616 -41.148)
		(end 102.87 -40.894)
		(stroke
			(width 0.381)
			(type default)
		)
		(layer "In5.Cu")
	)
	(gr_line
		(start 102.743 -37.465)
		(end 102.743 -37.211)
		(stroke
			(width 0.381)
			(type default)
		)
		(layer "In5.Cu")
	)
	(gr_line
		(start 102.743 -37.211)
		(end 102.489 -36.957)
		(stroke
			(width 0.381)
			(type default)
		)
		(layer "In5.Cu")
	)
	(gr_line
		(start 102.87 -40.894)
		(end 105.283 -40.894)
		(stroke
			(width 0.381)
			(type default)
		)
		(layer "In5.Cu")
	)
	(gr_line
		(start 102.997 -44.196)
		(end 102.997 -42.672)
		(stroke
			(width 0.381)
			(type default)
		)
		(layer "In5.Cu")
	)
	(gr_line
		(start 102.997 -42.672)
		(end 102.616 -42.291)
		(stroke
			(width 0.381)
			(type default)
		)
		(layer "In5.Cu")
	)
	(gr_line
		(start 102.997 -37.719)
		(end 102.743 -37.465)
		(stroke
			(width 0.381)
			(type default)
		)
		(layer "In5.Cu")
	)
	(gr_line
		(start 105.283 -40.894)
		(end 106.426 -39.751)
		(stroke
			(width 0.381)
			(type default)
		)
		(layer "In5.Cu")
	)
	(gr_line
		(start 105.918 -37.719)
		(end 102.997 -37.719)
		(stroke
			(width 0.381)
			(type default)
		)
		(layer "In5.Cu")
	)
	(gr_line
		(start 106.426 -39.751)
		(end 106.426 -38.227)
		(stroke
			(width 0.381)
			(type default)
		)
		(layer "In5.Cu")
	)
	(gr_line
		(start 106.426 -38.227)
		(end 105.918 -37.719)
		(stroke
			(width 0.381)
			(type default)
		)
		(layer "In5.Cu")
	)
	(gr_arc
		(start 1.54686 -67.178682)
		(mid 1.9304 -67.562222)
		(end 2.31394 -67.178682)
		(stroke
			(width 0.2)
			(type default)
		)
		(layer "In6.Cu")
	)
	(gr_line
		(start 1.54686 -66.221102)
		(end 1.54686 -67.178682)
		(stroke
			(width 0.2)
			(type default)
		)
		(layer "In6.Cu")
	)
	(gr_arc
		(start 1.54686 -64.178434)
		(mid 1.930273 -64.562228)
		(end 2.31394 -64.178688)
		(stroke
			(width 0.2)
			(type default)
		)
		(layer "In6.Cu")
	)
	(gr_line
		(start 1.54686 -63.221108)
		(end 1.54686 -64.178434)
		(stroke
			(width 0.2)
			(type default)
		)
		(layer "In6.Cu")
	)
	(gr_arc
		(start 1.54686 -61.178694)
		(mid 1.9304 -61.562234)
		(end 2.31394 -61.178694)
		(stroke
			(width 0.2)
			(type default)
		)
		(layer "In6.Cu")
	)
	(gr_line
		(start 1.54686 -60.221114)
		(end 1.54686 -61.178694)
		(stroke
			(width 0.2)
			(type default)
		)
		(layer "In6.Cu")
	)
	(gr_line
		(start 2.31394 -67.178682)
		(end 2.31394 -66.221356)
		(stroke
			(width 0.2)
			(type default)
		)
		(layer "In6.Cu")
	)
	(gr_arc
		(start 2.31394 -66.221356)
		(mid 1.930527 -65.837562)
		(end 1.54686 -66.221102)
		(stroke
			(width 0.2)
			(type default)
		)
		(layer "In6.Cu")
	)
	(gr_line
		(start 2.31394 -64.178688)
		(end 2.31394 -63.221108)
		(stroke
			(width 0.2)
			(type default)
		)
		(layer "In6.Cu")
	)
	(gr_arc
		(start 2.31394 -63.221108)
		(mid 1.9304 -62.837568)
		(end 1.54686 -63.221108)
		(stroke
			(width 0.2)
			(type default)
		)
		(layer "In6.Cu")
	)
	(gr_line
		(start 2.31394 -61.178694)
		(end 2.31394 -60.221368)
		(stroke
			(width 0.2)
			(type default)
		)
		(layer "In6.Cu")
	)
	(gr_arc
		(start 2.31394 -60.221368)
		(mid 1.930527 -59.837574)
		(end 1.54686 -60.221114)
		(stroke
			(width 0.2)
			(type default)
		)
		(layer "In6.Cu")
	)
	(gr_arc
		(start 2.94132 -59.664092)
		(mid 3.324733 -60.047886)
		(end 3.7084 -59.664346)
		(stroke
			(width 0.2)
			(type default)
		)
		(layer "In6.Cu")
	)
	(gr_line
		(start 2.94132 -58.706766)
		(end 2.94132 -59.664092)
		(stroke
			(width 0.2)
			(type default)
		)
		(layer "In6.Cu")
	)
	(gr_arc
		(start 3.06832 -65.664334)
		(mid 3.45186 -66.047874)
		(end 3.8354 -65.664334)
		(stroke
			(width 0.2)
			(type default)
		)
		(layer "In6.Cu")
	)
	(gr_line
		(start 3.06832 -64.706754)
		(end 3.06832 -65.664334)
		(stroke
			(width 0.2)
			(type default)
		)
		(layer "In6.Cu")
	)
	(gr_arc
		(start 3.06832 -62.66434)
		(mid 3.45186 -63.04788)
		(end 3.8354 -62.66434)
		(stroke
			(width 0.2)
			(type default)
		)
		(layer "In6.Cu")
	)
	(gr_line
		(start 3.06832 -61.70676)
		(end 3.06832 -62.66434)
		(stroke
			(width 0.2)
			(type default)
		)
		(layer "In6.Cu")
	)
	(gr_line
		(start 3.7084 -59.664346)
		(end 3.7084 -58.706766)
		(stroke
			(width 0.2)
			(type default)
		)
		(layer "In6.Cu")
	)
	(gr_arc
		(start 3.7084 -58.706766)
		(mid 3.32486 -58.323226)
		(end 2.94132 -58.706766)
		(stroke
			(width 0.2)
			(type default)
		)
		(layer "In6.Cu")
	)
	(gr_line
		(start 3.8354 -65.664334)
		(end 3.8354 -64.707008)
		(stroke
			(width 0.2)
			(type default)
		)
		(layer "In6.Cu")
	)
	(gr_arc
		(start 3.8354 -64.707008)
		(mid 3.451987 -64.323214)
		(end 3.06832 -64.706754)
		(stroke
			(width 0.2)
			(type default)
		)
		(layer "In6.Cu")
	)
	(gr_line
		(start 3.8354 -62.66434)
		(end 3.8354 -61.707014)
		(stroke
			(width 0.2)
			(type default)
		)
		(layer "In6.Cu")
	)
	(gr_arc
		(start 3.8354 -61.707014)
		(mid 3.451987 -61.32322)
		(end 3.06832 -61.70676)
		(stroke
			(width 0.2)
			(type default)
		)
		(layer "In6.Cu")
	)
	(gr_line
		(start 5.114798 -49.276)
		(end 5.114798 -43.688)
		(stroke
			(width 0.2)
			(type default)
		)
		(layer "In6.Cu")
	)
	(gr_line
		(start 5.114798 -43.688)
		(end 8.543798 -43.688)
		(stroke
			(width 0.2)
			(type default)
		)
		(layer "In6.Cu")
	)
	(gr_arc
		(start 7.747 -51.6128)
		(mid 8.128 -51.9938)
		(end 8.509 -51.6128)
		(stroke
			(width 0.2)
			(type default)
		)
		(layer "In6.Cu")
	)
	(gr_line
		(start 7.747 -50.6222)
		(end 7.747 -51.6128)
		(stroke
			(width 0.2)
			(type default)
		)
		(layer "In6.Cu")
	)
	(gr_arc
		(start 8.4582 -53.8988)
		(mid 8.8392 -54.2798)
		(end 9.2202 -53.8988)
		(stroke
			(width 0.2)
			(type default)
		)
		(layer "In6.Cu")
	)
	(gr_line
		(start 8.4582 -52.9082)
		(end 8.4582 -53.8988)
		(stroke
			(width 0.2)
			(type default)
		)
		(layer "In6.Cu")
	)
	(gr_line
		(start 8.509 -51.6128)
		(end 8.509 -50.622454)
		(stroke
			(width 0.2)
			(type default)
		)
		(layer "In6.Cu")
	)
	(gr_arc
		(start 8.509 -50.622454)
		(mid 8.128127 -50.2412)
		(end 7.747 -50.6222)
		(stroke
			(width 0.2)
			(type default)
		)
		(layer "In6.Cu")
	)
	(gr_line
		(start 8.543798 -49.276)
		(end 5.114798 -49.276)
		(stroke
			(width 0.2)
			(type default)
		)
		(layer "In6.Cu")
	)
	(gr_line
		(start 8.543798 -43.688)
		(end 8.543798 -49.276)
		(stroke
			(width 0.2)
			(type default)
		)
		(layer "In6.Cu")
	)
	(gr_line
		(start 9.2202 -53.8988)
		(end 9.2202 -52.908454)
		(stroke
			(width 0.2)
			(type default)
		)
		(layer "In6.Cu")
	)
	(gr_arc
		(start 9.2202 -52.908454)
		(mid 8.839327 -52.5272)
		(end 8.4582 -52.9082)
		(stroke
			(width 0.2)
			(type default)
		)
		(layer "In6.Cu")
	)
	(gr_line
		(start 9.240774 -62.748922)
		(end 9.266174 -63.637668)
		(stroke
			(width 0.2)
			(type default)
		)
		(layer "In6.Cu")
	)
	(gr_line
		(start 9.240774 -59.192922)
		(end 9.266174 -60.081668)
		(stroke
			(width 0.2)
			(type default)
		)
		(layer "In6.Cu")
	)
	(gr_arc
		(start 9.24306 -65.405)
		(mid 9.6266 -65.78854)
		(end 10.01014 -65.405)
		(stroke
			(width 0.2)
			(type default)
		)
		(layer "In6.Cu")
	)
	(gr_line
		(start 9.24306 -64.516)
		(end 9.24306 -65.405)
		(stroke
			(width 0.2)
			(type default)
		)
		(layer "In6.Cu")
	)
	(gr_arc
		(start 9.24306 -61.849)
		(mid 9.6266 -62.23254)
		(end 10.01014 -61.849)
		(stroke
			(width 0.2)
			(type default)
		)
		(layer "In6.Cu")
	)
	(gr_line
		(start 9.24306 -60.96)
		(end 9.24306 -61.849)
		(stroke
			(width 0.2)
			(type default)
		)
		(layer "In6.Cu")
	)
	(gr_arc
		(start 9.24306 -58.293)
		(mid 9.6266 -58.67654)
		(end 10.01014 -58.293)
		(stroke
			(width 0.2)
			(type default)
		)
		(layer "In6.Cu")
	)
	(gr_line
		(start 9.24306 -57.404)
		(end 9.24306 -58.293)
		(stroke
			(width 0.2)
			(type default)
		)
		(layer "In6.Cu")
	)
	(gr_arc
		(start 9.24306 -56.515)
		(mid 9.6266 -56.89854)
		(end 10.01014 -56.515)
		(stroke
			(width 0.2)
			(type default)
		)
		(layer "In6.Cu")
	)
	(gr_line
		(start 9.24306 -55.626)
		(end 9.24306 -56.515)
		(stroke
			(width 0.2)
			(type default)
		)
		(layer "In6.Cu")
	)
	(gr_line
		(start 9.243314 -62.748922)
		(end 9.240774 -62.748922)
		(stroke
			(width 0.2)
			(type default)
		)
		(layer "In6.Cu")
	)
	(gr_line
		(start 9.243314 -59.192922)
		(end 9.240774 -59.192922)
		(stroke
			(width 0.2)
			(type default)
		)
		(layer "In6.Cu")
	)
	(gr_line
		(start 9.266174 -63.637668)
		(end 9.266428 -63.637922)
		(stroke
			(width 0.2)
			(type default)
		)
		(layer "In6.Cu")
	)
	(gr_line
		(start 9.266174 -60.081668)
		(end 9.266428 -60.081922)
		(stroke
			(width 0.2)
			(type default)
		)
		(layer "In6.Cu")
	)
	(gr_line
		(start 9.266428 -63.637922)
		(end 9.268714 -63.637922)
		(stroke
			(width 0.2)
			(type default)
		)
		(layer "In6.Cu")
	)
	(gr_line
		(start 9.266428 -60.081922)
		(end 9.268714 -60.081922)
		(stroke
			(width 0.2)
			(type default)
		)
		(layer "In6.Cu")
	)
	(gr_arc
		(start 9.268714 -63.637922)
		(mid 9.662922 -64.010286)
		(end 10.035286 -63.616078)
		(stroke
			(width 0.2)
			(type default)
		)
		(layer "In6.Cu")
	)
	(gr_arc
		(start 9.268714 -60.081922)
		(mid 9.662922 -60.454286)
		(end 10.035286 -60.060078)
		(stroke
			(width 0.2)
			(type default)
		)
		(layer "In6.Cu")
	)
	(gr_circle
		(center 9.5504 -51.7398)
		(end 9.90854 -51.7398)
		(stroke
			(width 0.2)
			(type default)
		)
		(fill no)
		(layer "In6.Cu")
	)
	(gr_circle
		(center 9.5504 -50.4952)
		(end 9.90854 -50.4952)
		(stroke
			(width 0.2)
			(type default)
		)
		(fill no)
		(layer "In6.Cu")
	)
	(gr_arc
		(start 10.009886 -62.727078)
		(mid 9.615678 -62.354714)
		(end 9.243314 -62.748922)
		(stroke
			(width 0.2)
			(type default)
		)
		(layer "In6.Cu")
	)
	(gr_arc
		(start 10.009886 -59.171078)
		(mid 9.615678 -58.798714)
		(end 9.243314 -59.192922)
		(stroke
			(width 0.2)
			(type default)
		)
		(layer "In6.Cu")
	)
	(gr_line
		(start 10.01014 -65.405)
		(end 10.01014 -64.516254)
		(stroke
			(width 0.2)
			(type default)
		)
		(layer "In6.Cu")
	)
	(gr_arc
		(start 10.01014 -64.516254)
		(mid 9.626727 -64.13246)
		(end 9.24306 -64.516)
		(stroke
			(width 0.2)
			(type default)
		)
		(layer "In6.Cu")
	)
	(gr_line
		(start 10.01014 -61.849)
		(end 10.01014 -60.960254)
		(stroke
			(width 0.2)
			(type default)
		)
		(layer "In6.Cu")
	)
	(gr_arc
		(start 10.01014 -60.960254)
		(mid 9.626727 -60.57646)
		(end 9.24306 -60.96)
		(stroke
			(width 0.2)
			(type default)
		)
		(layer "In6.Cu")
	)
	(gr_line
		(start 10.01014 -58.293)
		(end 10.01014 -57.404254)
		(stroke
			(width 0.2)
			(type default)
		)
		(layer "In6.Cu")
	)
	(gr_arc
		(start 10.01014 -57.404254)
		(mid 9.626727 -57.02046)
		(end 9.24306 -57.404)
		(stroke
			(width 0.2)
			(type default)
		)
		(layer "In6.Cu")
	)
	(gr_line
		(start 10.01014 -56.515)
		(end 10.01014 -55.626254)
		(stroke
			(width 0.2)
			(type default)
		)
		(layer "In6.Cu")
	)
	(gr_arc
		(start 10.01014 -55.626254)
		(mid 9.626727 -55.24246)
		(end 9.24306 -55.626)
		(stroke
			(width 0.2)
			(type default)
		)
		(layer "In6.Cu")
	)
	(gr_line
		(start 10.012426 -62.727078)
		(end 10.009886 -62.727078)
		(stroke
			(width 0.2)
			(type default)
		)
		(layer "In6.Cu")
	)
	(gr_line
		(start 10.012426 -59.171078)
		(end 10.009886 -59.171078)
		(stroke
			(width 0.2)
			(type default)
		)
		(layer "In6.Cu")
	)
	(gr_line
		(start 10.035286 -63.616078)
		(end 10.037826 -63.616078)
		(stroke
			(width 0.2)
			(type default)
		)
		(layer "In6.Cu")
	)
	(gr_line
		(start 10.035286 -60.060078)
		(end 10.037826 -60.060078)
		(stroke
			(width 0.2)
			(type default)
		)
		(layer "In6.Cu")
	)
	(gr_line
		(start 10.037826 -63.616078)
		(end 10.012426 -62.727078)
		(stroke
			(width 0.2)
			(type default)
		)
		(layer "In6.Cu")
	)
	(gr_line
		(start 10.037826 -60.060078)
		(end 10.012426 -59.171078)
		(stroke
			(width 0.2)
			(type default)
		)
		(layer "In6.Cu")
	)
	(gr_circle
		(center 10.2616 -54.0258)
		(end 10.61974 -54.0258)
		(stroke
			(width 0.2)
			(type default)
		)
		(fill no)
		(layer "In6.Cu")
	)
	(gr_circle
		(center 10.2616 -52.7812)
		(end 10.61974 -52.7812)
		(stroke
			(width 0.2)
			(type default)
		)
		(fill no)
		(layer "In6.Cu")
	)
	(gr_arc
		(start 12.7889 -48.617886)
		(mid 13.172313 -49.00168)
		(end 13.55598 -48.61814)
		(stroke
			(width 0.2)
			(type default)
		)
		(layer "In6.Cu")
	)
	(gr_line
		(start 12.7889 -47.66056)
		(end 12.7889 -48.617886)
		(stroke
			(width 0.2)
			(type default)
		)
		(layer "In6.Cu")
	)
	(gr_line
		(start 13.55598 -48.61814)
		(end 13.55598 -47.66056)
		(stroke
			(width 0.2)
			(type default)
		)
		(layer "In6.Cu")
	)
	(gr_arc
		(start 13.55598 -47.66056)
		(mid 13.17244 -47.27702)
		(end 12.7889 -47.66056)
		(stroke
			(width 0.2)
			(type default)
		)
		(layer "In6.Cu")
	)
	(gr_line
		(start 14.15288 -47.21606)
		(end 15.082266 -47.21606)
		(stroke
			(width 0.2)
			(type default)
		)
		(layer "In6.Cu")
	)
	(gr_arc
		(start 14.153134 -46.44898)
		(mid 13.76934 -46.832393)
		(end 14.15288 -47.21606)
		(stroke
			(width 0.2)
			(type default)
		)
		(layer "In6.Cu")
	)
	(gr_arc
		(start 15.082266 -47.21606)
		(mid 15.465806 -46.83252)
		(end 15.082266 -46.44898)
		(stroke
			(width 0.2)
			(type default)
		)
		(layer "In6.Cu")
	)
	(gr_line
		(start 15.082266 -46.44898)
		(end 14.153134 -46.44898)
		(stroke
			(width 0.2)
			(type default)
		)
		(layer "In6.Cu")
	)
	(gr_line
		(start 19.408394 -10.634218)
		(end 20.327874 -10.634218)
		(stroke
			(width 0.2)
			(type default)
		)
		(layer "In6.Cu")
	)
	(gr_arc
		(start 19.408648 -9.867138)
		(mid 19.024854 -10.250551)
		(end 19.408394 -10.634218)
		(stroke
			(width 0.2)
			(type default)
		)
		(layer "In6.Cu")
	)
	(gr_line
		(start 20.09521 -15.872206)
		(end 21.052536 -15.872206)
		(stroke
			(width 0.2)
			(type default)
		)
		(layer "In6.Cu")
	)
	(gr_arc
		(start 20.09521 -15.105126)
		(mid 19.71167 -15.488666)
		(end 20.09521 -15.872206)
		(stroke
			(width 0.2)
			(type default)
		)
		(layer "In6.Cu")
	)
	(gr_arc
		(start 20.327874 -10.634218)
		(mid 20.711414 -10.250678)
		(end 20.327874 -9.867138)
		(stroke
			(width 0.2)
			(type default)
		)
		(layer "In6.Cu")
	)
	(gr_line
		(start 20.327874 -9.867138)
		(end 19.408648 -9.867138)
		(stroke
			(width 0.2)
			(type default)
		)
		(layer "In6.Cu")
	)
	(gr_arc
		(start 21.052536 -15.872206)
		(mid 21.43633 -15.488793)
		(end 21.05279 -15.105126)
		(stroke
			(width 0.2)
			(type default)
		)
		(layer "In6.Cu")
	)
	(gr_line
		(start 21.05279 -15.105126)
		(end 20.09521 -15.105126)
		(stroke
			(width 0.2)
			(type default)
		)
		(layer "In6.Cu")
	)
	(gr_line
		(start 21.6662 -14.20114)
		(end 22.5298 -14.20114)
		(stroke
			(width 0.2)
			(type default)
		)
		(layer "In6.Cu")
	)
	(gr_arc
		(start 21.666454 -13.43406)
		(mid 21.28266 -13.817473)
		(end 21.6662 -14.20114)
		(stroke
			(width 0.2)
			(type default)
		)
		(layer "In6.Cu")
	)
	(gr_arc
		(start 22.5298 -14.20114)
		(mid 22.91334 -13.8176)
		(end 22.5298 -13.43406)
		(stroke
			(width 0.2)
			(type default)
		)
		(layer "In6.Cu")
	)
	(gr_line
		(start 22.5298 -13.43406)
		(end 21.666454 -13.43406)
		(stroke
			(width 0.2)
			(type default)
		)
		(layer "In6.Cu")
	)
	(gr_line
		(start 23.408386 -10.634218)
		(end 24.327866 -10.634218)
		(stroke
			(width 0.2)
			(type default)
		)
		(layer "In6.Cu")
	)
	(gr_arc
		(start 23.40864 -9.867138)
		(mid 23.024846 -10.250551)
		(end 23.408386 -10.634218)
		(stroke
			(width 0.2)
			(type default)
		)
		(layer "In6.Cu")
	)
	(gr_arc
		(start 24.327866 -10.634218)
		(mid 24.711406 -10.250678)
		(end 24.327866 -9.867138)
		(stroke
			(width 0.2)
			(type default)
		)
		(layer "In6.Cu")
	)
	(gr_line
		(start 24.327866 -9.867138)
		(end 23.40864 -9.867138)
		(stroke
			(width 0.2)
			(type default)
		)
		(layer "In6.Cu")
	)
	(gr_line
		(start 25.4127 -14.20114)
		(end 26.276046 -14.20114)
		(stroke
			(width 0.2)
			(type default)
		)
		(layer "In6.Cu")
	)
	(gr_arc
		(start 25.4127 -13.43406)
		(mid 25.02916 -13.8176)
		(end 25.4127 -14.20114)
		(stroke
			(width 0.2)
			(type default)
		)
		(layer "In6.Cu")
	)
	(gr_arc
		(start 26.276046 -14.20114)
		(mid 26.65984 -13.817727)
		(end 26.2763 -13.43406)
		(stroke
			(width 0.2)
			(type default)
		)
		(layer "In6.Cu")
	)
	(gr_line
		(start 26.2763 -13.43406)
		(end 25.4127 -13.43406)
		(stroke
			(width 0.2)
			(type default)
		)
		(layer "In6.Cu")
	)
	(gr_line
		(start 27.408378 -10.634218)
		(end 28.327604 -10.634218)
		(stroke
			(width 0.2)
			(type default)
		)
		(layer "In6.Cu")
	)
	(gr_arc
		(start 27.408378 -9.867138)
		(mid 27.024838 -10.250678)
		(end 27.408378 -10.634218)
		(stroke
			(width 0.2)
			(type default)
		)
		(layer "In6.Cu")
	)
	(gr_arc
		(start 28.327604 -10.634218)
		(mid 28.711398 -10.250805)
		(end 28.327858 -9.867138)
		(stroke
			(width 0.2)
			(type default)
		)
		(layer "In6.Cu")
	)
	(gr_line
		(start 28.327858 -9.867138)
		(end 27.408378 -9.867138)
		(stroke
			(width 0.2)
			(type default)
		)
		(layer "In6.Cu")
	)
	(gr_line
		(start 29.4132 -14.96314)
		(end 30.276546 -14.96314)
		(stroke
			(width 0.2)
			(type default)
		)
		(layer "In6.Cu")
	)
	(gr_arc
		(start 29.4132 -14.19606)
		(mid 29.02966 -14.5796)
		(end 29.4132 -14.96314)
		(stroke
			(width 0.2)
			(type default)
		)
		(layer "In6.Cu")
	)
	(gr_arc
		(start 30.276546 -14.96314)
		(mid 30.66034 -14.579727)
		(end 30.2768 -14.19606)
		(stroke
			(width 0.2)
			(type default)
		)
		(layer "In6.Cu")
	)
	(gr_line
		(start 30.2768 -14.19606)
		(end 29.4132 -14.19606)
		(stroke
			(width 0.2)
			(type default)
		)
		(layer "In6.Cu")
	)
	(gr_line
		(start 31.40837 -10.634218)
		(end 32.327596 -10.634218)
		(stroke
			(width 0.2)
			(type default)
		)
		(layer "In6.Cu")
	)
	(gr_arc
		(start 31.40837 -9.867138)
		(mid 31.02483 -10.250678)
		(end 31.40837 -10.634218)
		(stroke
			(width 0.2)
			(type default)
		)
		(layer "In6.Cu")
	)
	(gr_arc
		(start 32.327596 -10.634218)
		(mid 32.71139 -10.250805)
		(end 32.32785 -9.867138)
		(stroke
			(width 0.2)
			(type default)
		)
		(layer "In6.Cu")
	)
	(gr_line
		(start 32.32785 -9.867138)
		(end 31.40837 -9.867138)
		(stroke
			(width 0.2)
			(type default)
		)
		(layer "In6.Cu")
	)
	(gr_line
		(start 33.4264 -14.96314)
		(end 34.289746 -14.96314)
		(stroke
			(width 0.2)
			(type default)
		)
		(layer "In6.Cu")
	)
	(gr_arc
		(start 33.4264 -14.19606)
		(mid 33.04286 -14.5796)
		(end 33.4264 -14.96314)
		(stroke
			(width 0.2)
			(type default)
		)
		(layer "In6.Cu")
	)
	(gr_arc
		(start 34.289746 -14.96314)
		(mid 34.67354 -14.579727)
		(end 34.29 -14.19606)
		(stroke
			(width 0.2)
			(type default)
		)
		(layer "In6.Cu")
	)
	(gr_line
		(start 34.29 -14.19606)
		(end 33.4264 -14.19606)
		(stroke
			(width 0.2)
			(type default)
		)
		(layer "In6.Cu")
	)
	(gr_line
		(start 35.408362 -10.634218)
		(end 36.327588 -10.634218)
		(stroke
			(width 0.2)
			(type default)
		)
		(layer "In6.Cu")
	)
	(gr_arc
		(start 35.408362 -9.867138)
		(mid 35.024822 -10.250678)
		(end 35.408362 -10.634218)
		(stroke
			(width 0.2)
			(type default)
		)
		(layer "In6.Cu")
	)
	(gr_arc
		(start 36.327588 -10.634218)
		(mid 36.711382 -10.250805)
		(end 36.327842 -9.867138)
		(stroke
			(width 0.2)
			(type default)
		)
		(layer "In6.Cu")
	)
	(gr_line
		(start 36.327842 -9.867138)
		(end 35.408362 -9.867138)
		(stroke
			(width 0.2)
			(type default)
		)
		(layer "In6.Cu")
	)
	(gr_line
		(start 37.41801 -14.20114)
		(end 38.281356 -14.20114)
		(stroke
			(width 0.2)
			(type default)
		)
		(layer "In6.Cu")
	)
	(gr_arc
		(start 37.41801 -13.43406)
		(mid 37.03447 -13.8176)
		(end 37.41801 -14.20114)
		(stroke
			(width 0.2)
			(type default)
		)
		(layer "In6.Cu")
	)
	(gr_arc
		(start 37.88664 -30.2006)
		(mid 38.27018 -30.58414)
		(end 38.65372 -30.2006)
		(stroke
			(width 0.2)
			(type default)
		)
		(layer "In6.Cu")
	)
	(gr_line
		(start 37.88664 -29.337)
		(end 37.88664 -30.2006)
		(stroke
			(width 0.2)
			(type default)
		)
		(layer "In6.Cu")
	)
	(gr_arc
		(start 38.281356 -14.20114)
		(mid 38.66515 -13.817727)
		(end 38.28161 -13.43406)
		(stroke
			(width 0.2)
			(type default)
		)
		(layer "In6.Cu")
	)
	(gr_line
		(start 38.28161 -13.43406)
		(end 37.41801 -13.43406)
		(stroke
			(width 0.2)
			(type default)
		)
		(layer "In6.Cu")
	)
	(gr_line
		(start 38.65372 -30.2006)
		(end 38.65372 -29.337254)
		(stroke
			(width 0.2)
			(type default)
		)
		(layer "In6.Cu")
	)
	(gr_arc
		(start 38.65372 -29.337254)
		(mid 38.270307 -28.95346)
		(end 37.88664 -29.337)
		(stroke
			(width 0.2)
			(type default)
		)
		(layer "In6.Cu")
	)
	(gr_line
		(start 39.408354 -10.634218)
		(end 40.327834 -10.634218)
		(stroke
			(width 0.2)
			(type default)
		)
		(layer "In6.Cu")
	)
	(gr_arc
		(start 39.408608 -9.867138)
		(mid 39.024814 -10.250551)
		(end 39.408354 -10.634218)
		(stroke
			(width 0.2)
			(type default)
		)
		(layer "In6.Cu")
	)
	(gr_line
		(start 39.44366 -12.73048)
		(end 40.40124 -12.73048)
		(stroke
			(width 0.2)
			(type default)
		)
		(layer "In6.Cu")
	)
	(gr_arc
		(start 39.443914 -11.9634)
		(mid 39.06012 -12.346813)
		(end 39.44366 -12.73048)
		(stroke
			(width 0.2)
			(type default)
		)
		(layer "In6.Cu")
	)
	(gr_arc
		(start 40.327834 -10.634218)
		(mid 40.711374 -10.250678)
		(end 40.327834 -9.867138)
		(stroke
			(width 0.2)
			(type default)
		)
		(layer "In6.Cu")
	)
	(gr_line
		(start 40.327834 -9.867138)
		(end 39.408608 -9.867138)
		(stroke
			(width 0.2)
			(type default)
		)
		(layer "In6.Cu")
	)
	(gr_arc
		(start 40.40124 -12.73048)
		(mid 40.78478 -12.34694)
		(end 40.40124 -11.9634)
		(stroke
			(width 0.2)
			(type default)
		)
		(layer "In6.Cu")
	)
	(gr_line
		(start 40.40124 -11.9634)
		(end 39.443914 -11.9634)
		(stroke
			(width 0.2)
			(type default)
		)
		(layer "In6.Cu")
	)
	(gr_line
		(start 41.418002 -14.20114)
		(end 42.281348 -14.20114)
		(stroke
			(width 0.2)
			(type default)
		)
		(layer "In6.Cu")
	)
	(gr_arc
		(start 41.418002 -13.43406)
		(mid 41.034462 -13.8176)
		(end 41.418002 -14.20114)
		(stroke
			(width 0.2)
			(type default)
		)
		(layer "In6.Cu")
	)
	(gr_arc
		(start 42.281348 -14.20114)
		(mid 42.665142 -13.817727)
		(end 42.281602 -13.43406)
		(stroke
			(width 0.2)
			(type default)
		)
		(layer "In6.Cu")
	)
	(gr_line
		(start 42.281602 -13.43406)
		(end 41.418002 -13.43406)
		(stroke
			(width 0.2)
			(type default)
		)
		(layer "In6.Cu")
	)
	(gr_line
		(start 42.45356 -44.5389)
		(end 43.41114 -44.5389)
		(stroke
			(width 0.2)
			(type default)
		)
		(layer "In6.Cu")
	)
	(gr_arc
		(start 42.453814 -43.77182)
		(mid 42.07002 -44.155233)
		(end 42.45356 -44.5389)
		(stroke
			(width 0.2)
			(type default)
		)
		(layer "In6.Cu")
	)
	(gr_line
		(start 43.25366 -12.98194)
		(end 44.210986 -12.98194)
		(stroke
			(width 0.2)
			(type default)
		)
		(layer "In6.Cu")
	)
	(gr_arc
		(start 43.25366 -12.21486)
		(mid 42.87012 -12.5984)
		(end 43.25366 -12.98194)
		(stroke
			(width 0.2)
			(type default)
		)
		(layer "In6.Cu")
	)
	(gr_line
		(start 43.408346 -10.634218)
		(end 44.327826 -10.634218)
		(stroke
			(width 0.2)
			(type default)
		)
		(layer "In6.Cu")
	)
	(gr_arc
		(start 43.4086 -9.867138)
		(mid 43.024806 -10.250551)
		(end 43.408346 -10.634218)
		(stroke
			(width 0.2)
			(type default)
		)
		(layer "In6.Cu")
	)
	(gr_arc
		(start 43.41114 -44.5389)
		(mid 43.79468 -44.15536)
		(end 43.41114 -43.77182)
		(stroke
			(width 0.2)
			(type default)
		)
		(layer "In6.Cu")
	)
	(gr_line
		(start 43.41114 -43.77182)
		(end 42.453814 -43.77182)
		(stroke
			(width 0.2)
			(type default)
		)
		(layer "In6.Cu")
	)
	(gr_arc
		(start 44.210986 -12.98194)
		(mid 44.59478 -12.598527)
		(end 44.21124 -12.21486)
		(stroke
			(width 0.2)
			(type default)
		)
		(layer "In6.Cu")
	)
	(gr_line
		(start 44.21124 -12.21486)
		(end 43.25366 -12.21486)
		(stroke
			(width 0.2)
			(type default)
		)
		(layer "In6.Cu")
	)
	(gr_arc
		(start 44.327826 -10.634218)
		(mid 44.711366 -10.250678)
		(end 44.327826 -9.867138)
		(stroke
			(width 0.2)
			(type default)
		)
		(layer "In6.Cu")
	)
	(gr_line
		(start 44.327826 -9.867138)
		(end 43.4086 -9.867138)
		(stroke
			(width 0.2)
			(type default)
		)
		(layer "In6.Cu")
	)
	(gr_line
		(start 44.98975 -44.30014)
		(end 45.947838 -44.32173)
		(stroke
			(width 0.2)
			(type default)
		)
		(layer "In6.Cu")
	)
	(gr_arc
		(start 45.007276 -43.53306)
		(mid 44.615103 -43.907837)
		(end 44.98975 -44.30014)
		(stroke
			(width 0.2)
			(type default)
		)
		(layer "In6.Cu")
	)
	(gr_line
		(start 45.466 -14.1986)
		(end 46.176946 -14.1986)
		(stroke
			(width 0.2)
			(type default)
		)
		(layer "In6.Cu")
	)
	(gr_arc
		(start 45.466 -13.4366)
		(mid 45.085 -13.8176)
		(end 45.466 -14.1986)
		(stroke
			(width 0.2)
			(type default)
		)
		(layer "In6.Cu")
	)
	(gr_arc
		(start 45.947838 -44.32173)
		(mid 46.340014 -43.946826)
		(end 45.96511 -43.55465)
		(stroke
			(width 0.2)
			(type default)
		)
		(layer "In6.Cu")
	)
	(gr_line
		(start 45.96511 -43.55465)
		(end 45.007276 -43.53306)
		(stroke
			(width 0.2)
			(type default)
		)
		(layer "In6.Cu")
	)
	(gr_arc
		(start 46.176946 -14.1986)
		(mid 46.5582 -13.817727)
		(end 46.1772 -13.4366)
		(stroke
			(width 0.2)
			(type default)
		)
		(layer "In6.Cu")
	)
	(gr_line
		(start 46.1772 -13.4366)
		(end 45.466 -13.4366)
		(stroke
			(width 0.2)
			(type default)
		)
		(layer "In6.Cu")
	)
	(gr_line
		(start 47.408338 -10.634218)
		(end 48.327818 -10.634218)
		(stroke
			(width 0.2)
			(type default)
		)
		(layer "In6.Cu")
	)
	(gr_arc
		(start 47.408592 -9.867138)
		(mid 47.024798 -10.250551)
		(end 47.408338 -10.634218)
		(stroke
			(width 0.2)
			(type default)
		)
		(layer "In6.Cu")
	)
	(gr_line
		(start 47.46371 -14.1732)
		(end 48.183546 -14.1732)
		(stroke
			(width 0.2)
			(type default)
		)
		(layer "In6.Cu")
	)
	(gr_arc
		(start 47.46371 -13.4112)
		(mid 47.08271 -13.7922)
		(end 47.46371 -14.1732)
		(stroke
			(width 0.2)
			(type default)
		)
		(layer "In6.Cu")
	)
	(gr_arc
		(start 48.183546 -14.1732)
		(mid 48.5648 -13.792327)
		(end 48.1838 -13.4112)
		(stroke
			(width 0.2)
			(type default)
		)
		(layer "In6.Cu")
	)
	(gr_line
		(start 48.1838 -13.4112)
		(end 47.46371 -13.4112)
		(stroke
			(width 0.2)
			(type default)
		)
		(layer "In6.Cu")
	)
	(gr_arc
		(start 48.327818 -10.634218)
		(mid 48.711358 -10.250678)
		(end 48.327818 -9.867138)
		(stroke
			(width 0.2)
			(type default)
		)
		(layer "In6.Cu")
	)
	(gr_line
		(start 48.327818 -9.867138)
		(end 47.408592 -9.867138)
		(stroke
			(width 0.2)
			(type default)
		)
		(layer "In6.Cu")
	)
	(gr_line
		(start 49.176432 -38.313614)
		(end 49.81321 -38.892226)
		(stroke
			(width 0.2)
			(type default)
		)
		(layer "In6.Cu")
	)
	(gr_line
		(start 49.29505 -20.79498)
		(end 50.25263 -20.79498)
		(stroke
			(width 0.2)
			(type default)
		)
		(layer "In6.Cu")
	)
	(gr_arc
		(start 49.295304 -20.0279)
		(mid 48.91151 -20.411313)
		(end 49.29505 -20.79498)
		(stroke
			(width 0.2)
			(type default)
		)
		(layer "In6.Cu")
	)
	(gr_line
		(start 49.38903 -10.64387)
		(end 50.310542 -10.64387)
		(stroke
			(width 0.2)
			(type default)
		)
		(layer "In6.Cu")
	)
	(gr_arc
		(start 49.389284 -9.87679)
		(mid 49.00549 -10.260203)
		(end 49.38903 -10.64387)
		(stroke
			(width 0.2)
			(type default)
		)
		(layer "In6.Cu")
	)
	(gr_line
		(start 49.4538 -14.1986)
		(end 50.2158 -14.1986)
		(stroke
			(width 0.2)
			(type default)
		)
		(layer "In6.Cu")
	)
	(gr_arc
		(start 49.454054 -13.4366)
		(mid 49.0728 -13.817473)
		(end 49.4538 -14.1986)
		(stroke
			(width 0.2)
			(type default)
		)
		(layer "In6.Cu")
	)
	(gr_arc
		(start 49.692052 -37.74567)
		(mid 49.15027 -37.771832)
		(end 49.176432 -38.313614)
		(stroke
			(width 0.2)
			(type default)
		)
		(layer "In6.Cu")
	)
	(gr_arc
		(start 49.81321 -38.892226)
		(mid 50.356403 -38.869633)
		(end 50.33137 -38.326568)
		(stroke
			(width 0.2)
			(type default)
		)
		(layer "In6.Cu")
	)
	(gr_arc
		(start 50.2158 -14.1986)
		(mid 50.5968 -13.8176)
		(end 50.2158 -13.4366)
		(stroke
			(width 0.2)
			(type default)
		)
		(layer "In6.Cu")
	)
	(gr_line
		(start 50.2158 -13.4366)
		(end 49.454054 -13.4366)
		(stroke
			(width 0.2)
			(type default)
		)
		(layer "In6.Cu")
	)
	(gr_arc
		(start 50.25263 -20.79498)
		(mid 50.63617 -20.41144)
		(end 50.25263 -20.0279)
		(stroke
			(width 0.2)
			(type default)
		)
		(layer "In6.Cu")
	)
	(gr_line
		(start 50.25263 -20.0279)
		(end 49.295304 -20.0279)
		(stroke
			(width 0.2)
			(type default)
		)
		(layer "In6.Cu")
	)
	(gr_arc
		(start 50.262028 -48.49495)
		(mid 50.63998 -48.884078)
		(end 51.029108 -48.506126)
		(stroke
			(width 0.2)
			(type default)
		)
		(layer "In6.Cu")
	)
	(gr_line
		(start 50.274474 -47.63135)
		(end 50.262028 -48.49495)
		(stroke
			(width 0.2)
			(type default)
		)
		(layer "In6.Cu")
	)
	(gr_arc
		(start 50.310542 -10.64387)
		(mid 50.694082 -10.26033)
		(end 50.310542 -9.87679)
		(stroke
			(width 0.2)
			(type default)
		)
		(layer "In6.Cu")
	)
	(gr_line
		(start 50.310542 -9.87679)
		(end 49.389284 -9.87679)
		(stroke
			(width 0.2)
			(type default)
		)
		(layer "In6.Cu")
	)
	(gr_line
		(start 50.33137 -38.326568)
		(end 49.692052 -37.74567)
		(stroke
			(width 0.2)
			(type default)
		)
		(layer "In6.Cu")
	)
	(gr_line
		(start 51.029108 -48.506126)
		(end 51.041554 -47.64278)
		(stroke
			(width 0.2)
			(type default)
		)
		(layer "In6.Cu")
	)
	(gr_arc
		(start 51.041554 -47.64278)
		(mid 50.663729 -47.253654)
		(end 50.274474 -47.63135)
		(stroke
			(width 0.2)
			(type default)
		)
		(layer "In6.Cu")
	)
	(gr_line
		(start 51.282346 -34.47034)
		(end 52.16652 -34.47034)
		(stroke
			(width 0.2)
			(type default)
		)
		(layer "In6.Cu")
	)
	(gr_arc
		(start 51.2826 -33.70326)
		(mid 50.898806 -34.086673)
		(end 51.282346 -34.47034)
		(stroke
			(width 0.2)
			(type default)
		)
		(layer "In6.Cu")
	)
	(gr_line
		(start 52.1462 -14.32814)
		(end 53.009546 -14.32814)
		(stroke
			(width 0.2)
			(type default)
		)
		(layer "In6.Cu")
	)
	(gr_arc
		(start 52.1462 -13.56106)
		(mid 51.76266 -13.9446)
		(end 52.1462 -14.32814)
		(stroke
			(width 0.2)
			(type default)
		)
		(layer "In6.Cu")
	)
	(gr_arc
		(start 52.16652 -34.47034)
		(mid 52.55006 -34.0868)
		(end 52.16652 -33.70326)
		(stroke
			(width 0.2)
			(type default)
		)
		(layer "In6.Cu")
	)
	(gr_line
		(start 52.16652 -33.70326)
		(end 51.2826 -33.70326)
		(stroke
			(width 0.2)
			(type default)
		)
		(layer "In6.Cu")
	)
	(gr_arc
		(start 52.52339 -34.93262)
		(mid 52.14112 -35.31743)
		(end 52.52593 -35.6997)
		(stroke
			(width 0.2)
			(type default)
		)
		(layer "In6.Cu")
	)
	(gr_line
		(start 52.52593 -35.6997)
		(end 53.479954 -35.696652)
		(stroke
			(width 0.2)
			(type default)
		)
		(layer "In6.Cu")
	)
	(gr_arc
		(start 52.768246 -29.826966)
		(mid 53.151659 -30.21076)
		(end 53.535326 -29.82722)
		(stroke
			(width 0.2)
			(type default)
		)
		(layer "In6.Cu")
	)
	(gr_line
		(start 52.768246 -28.897834)
		(end 52.768246 -29.826966)
		(stroke
			(width 0.2)
			(type default)
		)
		(layer "In6.Cu")
	)
	(gr_arc
		(start 53.009546 -14.32814)
		(mid 53.39334 -13.944727)
		(end 53.0098 -13.56106)
		(stroke
			(width 0.2)
			(type default)
		)
		(layer "In6.Cu")
	)
	(gr_line
		(start 53.0098 -13.56106)
		(end 52.1462 -13.56106)
		(stroke
			(width 0.2)
			(type default)
		)
		(layer "In6.Cu")
	)
	(gr_line
		(start 53.477668 -34.929572)
		(end 52.52339 -34.93262)
		(stroke
			(width 0.2)
			(type default)
		)
		(layer "In6.Cu")
	)
	(gr_arc
		(start 53.479954 -35.696652)
		(mid 53.862478 -35.311969)
		(end 53.477668 -34.929572)
		(stroke
			(width 0.2)
			(type default)
		)
		(layer "In6.Cu")
	)
	(gr_line
		(start 53.535326 -29.82722)
		(end 53.535326 -28.897834)
		(stroke
			(width 0.2)
			(type default)
		)
		(layer "In6.Cu")
	)
	(gr_arc
		(start 53.535326 -28.897834)
		(mid 53.151786 -28.514294)
		(end 52.768246 -28.897834)
		(stroke
			(width 0.2)
			(type default)
		)
		(layer "In6.Cu")
	)
	(gr_line
		(start 59.078114 -11.320018)
		(end 59.997594 -11.320018)
		(stroke
			(width 0.2)
			(type default)
		)
		(layer "In6.Cu")
	)
	(gr_arc
		(start 59.078368 -10.552938)
		(mid 58.694574 -10.936351)
		(end 59.078114 -11.320018)
		(stroke
			(width 0.2)
			(type default)
		)
		(layer "In6.Cu")
	)
	(gr_arc
		(start 59.27471 -36.33724)
		(mid 59.65825 -36.72078)
		(end 60.04179 -36.33724)
		(stroke
			(width 0.2)
			(type default)
		)
		(layer "In6.Cu")
	)
	(gr_line
		(start 59.27471 -35.37966)
		(end 59.27471 -36.33724)
		(stroke
			(width 0.2)
			(type default)
		)
		(layer "In6.Cu")
	)
	(gr_arc
		(start 59.997594 -11.320018)
		(mid 60.381134 -10.936478)
		(end 59.997594 -10.552938)
		(stroke
			(width 0.2)
			(type default)
		)
		(layer "In6.Cu")
	)
	(gr_line
		(start 59.997594 -10.552938)
		(end 59.078368 -10.552938)
		(stroke
			(width 0.2)
			(type default)
		)
		(layer "In6.Cu")
	)
	(gr_line
		(start 60.04179 -36.33724)
		(end 60.04179 -35.379914)
		(stroke
			(width 0.2)
			(type default)
		)
		(layer "In6.Cu")
	)
	(gr_arc
		(start 60.04179 -35.379914)
		(mid 59.658377 -34.99612)
		(end 59.27471 -35.37966)
		(stroke
			(width 0.2)
			(type default)
		)
		(layer "In6.Cu")
	)
	(gr_line
		(start 60.551822 -45.897038)
		(end 60.607448 -46.75886)
		(stroke
			(width 0.2)
			(type default)
		)
		(layer "In6.Cu")
	)
	(gr_arc
		(start 60.607448 -46.75886)
		(mid 61.014864 -47.117)
		(end 61.373004 -46.709584)
		(stroke
			(width 0.2)
			(type default)
		)
		(layer "In6.Cu")
	)
	(gr_arc
		(start 61.317378 -45.848016)
		(mid 60.910088 -45.489868)
		(end 60.551822 -45.897038)
		(stroke
			(width 0.2)
			(type default)
		)
		(layer "In6.Cu")
	)
	(gr_line
		(start 61.373004 -46.709584)
		(end 61.317378 -45.848016)
		(stroke
			(width 0.2)
			(type default)
		)
		(layer "In6.Cu")
	)
	(gr_line
		(start 61.40831 -10.634218)
		(end 62.327536 -10.634218)
		(stroke
			(width 0.2)
			(type default)
		)
		(layer "In6.Cu")
	)
	(gr_arc
		(start 61.40831 -9.867138)
		(mid 61.02477 -10.250678)
		(end 61.40831 -10.634218)
		(stroke
			(width 0.2)
			(type default)
		)
		(layer "In6.Cu")
	)
	(gr_arc
		(start 62.327536 -10.634218)
		(mid 62.71133 -10.250805)
		(end 62.32779 -9.867138)
		(stroke
			(width 0.2)
			(type default)
		)
		(layer "In6.Cu")
	)
	(gr_line
		(start 62.32779 -9.867138)
		(end 61.40831 -9.867138)
		(stroke
			(width 0.2)
			(type default)
		)
		(layer "In6.Cu")
	)
	(gr_line
		(start 63.627 -15.0876)
		(end 64.389 -15.0876)
		(stroke
			(width 0.2)
			(type default)
		)
		(layer "In6.Cu")
	)
	(gr_arc
		(start 63.627254 -14.3256)
		(mid 63.246 -14.706473)
		(end 63.627 -15.0876)
		(stroke
			(width 0.2)
			(type default)
		)
		(layer "In6.Cu")
	)
	(gr_arc
		(start 64.389 -15.0876)
		(mid 64.77 -14.7066)
		(end 64.389 -14.3256)
		(stroke
			(width 0.2)
			(type default)
		)
		(layer "In6.Cu")
	)
	(gr_line
		(start 64.389 -14.3256)
		(end 63.627254 -14.3256)
		(stroke
			(width 0.2)
			(type default)
		)
		(layer "In6.Cu")
	)
	(gr_line
		(start 65.786 -15.0622)
		(end 66.547746 -15.0622)
		(stroke
			(width 0.2)
			(type default)
		)
		(layer "In6.Cu")
	)
	(gr_arc
		(start 65.786 -14.3002)
		(mid 65.405 -14.6812)
		(end 65.786 -15.0622)
		(stroke
			(width 0.2)
			(type default)
		)
		(layer "In6.Cu")
	)
	(gr_arc
		(start 66.547746 -15.0622)
		(mid 66.929 -14.681327)
		(end 66.548 -14.3002)
		(stroke
			(width 0.2)
			(type default)
		)
		(layer "In6.Cu")
	)
	(gr_line
		(start 66.548 -14.3002)
		(end 65.786 -14.3002)
		(stroke
			(width 0.2)
			(type default)
		)
		(layer "In6.Cu")
	)
	(gr_line
		(start 67.34556 -10.668)
		(end 68.302886 -10.668)
		(stroke
			(width 0.2)
			(type default)
		)
		(layer "In6.Cu")
	)
	(gr_arc
		(start 67.34556 -9.90092)
		(mid 66.96202 -10.28446)
		(end 67.34556 -10.668)
		(stroke
			(width 0.2)
			(type default)
		)
		(layer "In6.Cu")
	)
	(gr_line
		(start 68.072 -14.98854)
		(end 68.834 -14.98854)
		(stroke
			(width 0.2)
			(type default)
		)
		(layer "In6.Cu")
	)
	(gr_arc
		(start 68.072254 -14.22146)
		(mid 67.68846 -14.604873)
		(end 68.072 -14.98854)
		(stroke
			(width 0.2)
			(type default)
		)
		(layer "In6.Cu")
	)
	(gr_arc
		(start 68.302886 -10.668)
		(mid 68.68668 -10.284587)
		(end 68.30314 -9.90092)
		(stroke
			(width 0.2)
			(type default)
		)
		(layer "In6.Cu")
	)
	(gr_line
		(start 68.30314 -9.90092)
		(end 67.34556 -9.90092)
		(stroke
			(width 0.2)
			(type default)
		)
		(layer "In6.Cu")
	)
	(gr_arc
		(start 68.75145 -28.403296)
		(mid 69.133212 -28.788614)
		(end 69.51853 -28.406852)
		(stroke
			(width 0.2)
			(type default)
		)
		(layer "In6.Cu")
	)
	(gr_line
		(start 68.75526 -27.51963)
		(end 68.75145 -28.403296)
		(stroke
			(width 0.2)
			(type default)
		)
		(layer "In6.Cu")
	)
	(gr_arc
		(start 68.834 -14.98854)
		(mid 69.21754 -14.605)
		(end 68.834 -14.22146)
		(stroke
			(width 0.2)
			(type default)
		)
		(layer "In6.Cu")
	)
	(gr_line
		(start 68.834 -14.22146)
		(end 68.072254 -14.22146)
		(stroke
			(width 0.2)
			(type default)
		)
		(layer "In6.Cu")
	)
	(gr_line
		(start 69.51853 -28.406852)
		(end 69.52234 -27.52344)
		(stroke
			(width 0.2)
			(type default)
		)
		(layer "In6.Cu")
	)
	(gr_arc
		(start 69.52234 -27.52344)
		(mid 69.140705 -27.138123)
		(end 68.75526 -27.51963)
		(stroke
			(width 0.2)
			(type default)
		)
		(layer "In6.Cu")
	)
	(gr_line
		(start 71.370952 -10.668)
		(end 72.328532 -10.668)
		(stroke
			(width 0.2)
			(type default)
		)
		(layer "In6.Cu")
	)
	(gr_arc
		(start 71.371206 -9.90092)
		(mid 70.987412 -10.284333)
		(end 71.370952 -10.668)
		(stroke
			(width 0.2)
			(type default)
		)
		(layer "In6.Cu")
	)
	(gr_arc
		(start 72.328532 -10.668)
		(mid 72.712072 -10.28446)
		(end 72.328532 -9.90092)
		(stroke
			(width 0.2)
			(type default)
		)
		(layer "In6.Cu")
	)
	(gr_line
		(start 72.328532 -9.90092)
		(end 71.371206 -9.90092)
		(stroke
			(width 0.2)
			(type default)
		)
		(layer "In6.Cu")
	)
	(gr_line
		(start 72.8472 -15.09014)
		(end 73.7108 -15.09014)
		(stroke
			(width 0.2)
			(type default)
		)
		(layer "In6.Cu")
	)
	(gr_arc
		(start 72.847454 -14.32306)
		(mid 72.46366 -14.706473)
		(end 72.8472 -15.09014)
		(stroke
			(width 0.2)
			(type default)
		)
		(layer "In6.Cu")
	)
	(gr_arc
		(start 73.7108 -15.09014)
		(mid 74.09434 -14.7066)
		(end 73.7108 -14.32306)
		(stroke
			(width 0.2)
			(type default)
		)
		(layer "In6.Cu")
	)
	(gr_line
		(start 73.7108 -14.32306)
		(end 72.847454 -14.32306)
		(stroke
			(width 0.2)
			(type default)
		)
		(layer "In6.Cu")
	)
	(gr_line
		(start 75.370944 -10.668)
		(end 76.328524 -10.668)
		(stroke
			(width 0.2)
			(type default)
		)
		(layer "In6.Cu")
	)
	(gr_arc
		(start 75.371198 -9.90092)
		(mid 74.987404 -10.284333)
		(end 75.370944 -10.668)
		(stroke
			(width 0.2)
			(type default)
		)
		(layer "In6.Cu")
	)
	(gr_arc
		(start 76.328524 -10.668)
		(mid 76.712064 -10.28446)
		(end 76.328524 -9.90092)
		(stroke
			(width 0.2)
			(type default)
		)
		(layer "In6.Cu")
	)
	(gr_line
		(start 76.328524 -9.90092)
		(end 75.371198 -9.90092)
		(stroke
			(width 0.2)
			(type default)
		)
		(layer "In6.Cu")
	)
	(gr_line
		(start 77.4192 -14.96314)
		(end 78.2828 -14.96314)
		(stroke
			(width 0.2)
			(type default)
		)
		(layer "In6.Cu")
	)
	(gr_arc
		(start 77.419454 -14.19606)
		(mid 77.03566 -14.579473)
		(end 77.4192 -14.96314)
		(stroke
			(width 0.2)
			(type default)
		)
		(layer "In6.Cu")
	)
	(gr_arc
		(start 77.972666 -29.55925)
		(mid 77.633576 -29.90596)
		(end 77.980286 -30.24505)
		(stroke
			(width 0.2)
			(type default)
		)
		(layer "In6.Cu")
	)
	(gr_line
		(start 77.980286 -30.24505)
		(end 78.538832 -30.2387)
		(stroke
			(width 0.2)
			(type default)
		)
		(layer "In6.Cu")
	)
	(gr_line
		(start 78.090014 -31.508446)
		(end 78.648814 -31.53283)
		(stroke
			(width 0.2)
			(type default)
		)
		(layer "In6.Cu")
	)
	(gr_arc
		(start 78.12024 -30.823154)
		(mid 77.762614 -31.150687)
		(end 78.090014 -31.508446)
		(stroke
			(width 0.2)
			(type default)
		)
		(layer "In6.Cu")
	)
	(gr_arc
		(start 78.2828 -14.96314)
		(mid 78.66634 -14.5796)
		(end 78.2828 -14.19606)
		(stroke
			(width 0.2)
			(type default)
		)
		(layer "In6.Cu")
	)
	(gr_line
		(start 78.2828 -14.19606)
		(end 77.419454 -14.19606)
		(stroke
			(width 0.2)
			(type default)
		)
		(layer "In6.Cu")
	)
	(gr_line
		(start 78.531466 -29.5529)
		(end 77.972666 -29.55925)
		(stroke
			(width 0.2)
			(type default)
		)
		(layer "In6.Cu")
	)
	(gr_arc
		(start 78.538832 -30.2387)
		(mid 78.878175 -29.892117)
		(end 78.531466 -29.5529)
		(stroke
			(width 0.2)
			(type default)
		)
		(layer "In6.Cu")
	)
	(gr_arc
		(start 78.648814 -31.53283)
		(mid 79.006446 -31.20517)
		(end 78.678786 -30.847538)
		(stroke
			(width 0.2)
			(type default)
		)
		(layer "In6.Cu")
	)
	(gr_line
		(start 78.678786 -30.847538)
		(end 78.12024 -30.823154)
		(stroke
			(width 0.2)
			(type default)
		)
		(layer "In6.Cu")
	)
	(gr_line
		(start 79.370936 -10.7188)
		(end 80.328516 -10.7188)
		(stroke
			(width 0.2)
			(type default)
		)
		(layer "In6.Cu")
	)
	(gr_arc
		(start 79.37119 -9.95172)
		(mid 78.987396 -10.335133)
		(end 79.370936 -10.7188)
		(stroke
			(width 0.2)
			(type default)
		)
		(layer "In6.Cu")
	)
	(gr_line
		(start 80.2132 -14.96314)
		(end 81.076546 -14.96314)
		(stroke
			(width 0.2)
			(type default)
		)
		(layer "In6.Cu")
	)
	(gr_arc
		(start 80.2132 -14.19606)
		(mid 79.82966 -14.5796)
		(end 80.2132 -14.96314)
		(stroke
			(width 0.2)
			(type default)
		)
		(layer "In6.Cu")
	)
	(gr_arc
		(start 80.2259 -54.685946)
		(mid 80.568673 -55.0291)
		(end 80.9117 -54.6862)
		(stroke
			(width 0.2)
			(type default)
		)
		(layer "In6.Cu")
	)
	(gr_line
		(start 80.2259 -54.1274)
		(end 80.2259 -54.685946)
		(stroke
			(width 0.2)
			(type default)
		)
		(layer "In6.Cu")
	)
	(gr_line
		(start 80.264 -60.7187)
		(end 81.0514 -60.7187)
		(stroke
			(width 0.2)
			(type default)
		)
		(layer "In6.Cu")
	)
	(gr_arc
		(start 80.264254 -60.0329)
		(mid 79.9211 -60.375673)
		(end 80.264 -60.7187)
		(stroke
			(width 0.2)
			(type default)
		)
		(layer "In6.Cu")
	)
	(gr_arc
		(start 80.328516 -10.7188)
		(mid 80.712056 -10.33526)
		(end 80.328516 -9.95172)
		(stroke
			(width 0.2)
			(type default)
		)
		(layer "In6.Cu")
	)
	(gr_line
		(start 80.328516 -9.95172)
		(end 79.37119 -9.95172)
		(stroke
			(width 0.2)
			(type default)
		)
		(layer "In6.Cu")
	)
	(gr_line
		(start 80.9117 -54.6862)
		(end 80.9117 -54.1274)
		(stroke
			(width 0.2)
			(type default)
		)
		(layer "In6.Cu")
	)
	(gr_arc
		(start 80.9117 -54.1274)
		(mid 80.5688 -53.7845)
		(end 80.2259 -54.1274)
		(stroke
			(width 0.2)
			(type default)
		)
		(layer "In6.Cu")
	)
	(gr_arc
		(start 81.0514 -60.7187)
		(mid 81.3943 -60.3758)
		(end 81.0514 -60.0329)
		(stroke
			(width 0.2)
			(type default)
		)
		(layer "In6.Cu")
	)
	(gr_line
		(start 81.0514 -60.0329)
		(end 80.264254 -60.0329)
		(stroke
			(width 0.2)
			(type default)
		)
		(layer "In6.Cu")
	)
	(gr_arc
		(start 81.076546 -14.96314)
		(mid 81.46034 -14.579727)
		(end 81.0768 -14.19606)
		(stroke
			(width 0.2)
			(type default)
		)
		(layer "In6.Cu")
	)
	(gr_line
		(start 81.0768 -14.19606)
		(end 80.2132 -14.19606)
		(stroke
			(width 0.2)
			(type default)
		)
		(layer "In6.Cu")
	)
	(gr_arc
		(start 81.3435 -53.593746)
		(mid 81.686273 -53.9369)
		(end 82.0293 -53.594)
		(stroke
			(width 0.2)
			(type default)
		)
		(layer "In6.Cu")
	)
	(gr_line
		(start 81.3435 -53.0098)
		(end 81.3435 -53.593746)
		(stroke
			(width 0.2)
			(type default)
		)
		(layer "In6.Cu")
	)
	(gr_line
		(start 82.0293 -53.594)
		(end 82.0293 -53.0098)
		(stroke
			(width 0.2)
			(type default)
		)
		(layer "In6.Cu")
	)
	(gr_arc
		(start 82.0293 -53.0098)
		(mid 81.6864 -52.6669)
		(end 81.3435 -53.0098)
		(stroke
			(width 0.2)
			(type default)
		)
		(layer "In6.Cu")
	)
	(gr_line
		(start 82.296 -14.32814)
		(end 83.1596 -14.32814)
		(stroke
			(width 0.2)
			(type default)
		)
		(layer "In6.Cu")
	)
	(gr_arc
		(start 82.296254 -13.56106)
		(mid 81.91246 -13.944473)
		(end 82.296 -14.32814)
		(stroke
			(width 0.2)
			(type default)
		)
		(layer "In6.Cu")
	)
	(gr_arc
		(start 82.803746 -55.65902)
		(mid 82.83702 -56.146446)
		(end 83.324446 -56.113172)
		(stroke
			(width 0.2)
			(type default)
		)
		(layer "In6.Cu")
	)
	(gr_arc
		(start 83.1596 -14.32814)
		(mid 83.54314 -13.9446)
		(end 83.1596 -13.56106)
		(stroke
			(width 0.2)
			(type default)
		)
		(layer "In6.Cu")
	)
	(gr_line
		(start 83.1596 -13.56106)
		(end 82.296254 -13.56106)
		(stroke
			(width 0.2)
			(type default)
		)
		(layer "In6.Cu")
	)
	(gr_line
		(start 83.18119 -55.226204)
		(end 82.803746 -55.65902)
		(stroke
			(width 0.2)
			(type default)
		)
		(layer "In6.Cu")
	)
	(gr_arc
		(start 83.309968 -59.661806)
		(mid 83.308952 -60.146946)
		(end 83.794092 -60.147962)
		(stroke
			(width 0.2)
			(type default)
		)
		(layer "In6.Cu")
	)
	(gr_line
		(start 83.324446 -56.113172)
		(end 83.701636 -55.68061)
		(stroke
			(width 0.2)
			(type default)
		)
		(layer "In6.Cu")
	)
	(gr_line
		(start 83.388962 -10.79627)
		(end 84.310474 -10.79627)
		(stroke
			(width 0.2)
			(type default)
		)
		(layer "In6.Cu")
	)
	(gr_arc
		(start 83.389216 -10.02919)
		(mid 83.005422 -10.412603)
		(end 83.388962 -10.79627)
		(stroke
			(width 0.2)
			(type default)
		)
		(layer "In6.Cu")
	)
	(gr_arc
		(start 83.701636 -55.68061)
		(mid 83.668625 -55.193446)
		(end 83.18119 -55.226204)
		(stroke
			(width 0.2)
			(type default)
		)
		(layer "In6.Cu")
	)
	(gr_line
		(start 83.794092 -60.147962)
		(end 84.348828 -59.595258)
		(stroke
			(width 0.2)
			(type default)
		)
		(layer "In6.Cu")
	)
	(gr_line
		(start 83.868006 -59.106054)
		(end 83.309968 -59.661806)
		(stroke
			(width 0.2)
			(type default)
		)
		(layer "In6.Cu")
	)
	(gr_arc
		(start 83.885024 -54.567836)
		(mid 84.22386 -54.91988)
		(end 84.575904 -54.581044)
		(stroke
			(width 0.2)
			(type default)
		)
		(layer "In6.Cu")
	)
	(gr_line
		(start 83.895692 -54.009036)
		(end 83.885024 -54.567836)
		(stroke
			(width 0.2)
			(type default)
		)
		(layer "In6.Cu")
	)
	(gr_arc
		(start 84.310474 -10.79627)
		(mid 84.694014 -10.41273)
		(end 84.310474 -10.02919)
		(stroke
			(width 0.2)
			(type default)
		)
		(layer "In6.Cu")
	)
	(gr_line
		(start 84.310474 -10.02919)
		(end 83.389216 -10.02919)
		(stroke
			(width 0.2)
			(type default)
		)
		(layer "In6.Cu")
	)
	(gr_arc
		(start 84.348828 -59.595258)
		(mid 84.354625 -59.108766)
		(end 83.868006 -59.106054)
		(stroke
			(width 0.2)
			(type default)
		)
		(layer "In6.Cu")
	)
	(gr_line
		(start 84.575904 -54.581044)
		(end 84.586572 -54.022498)
		(stroke
			(width 0.2)
			(type default)
		)
		(layer "In6.Cu")
	)
	(gr_arc
		(start 84.586572 -54.022498)
		(mid 84.247863 -53.670456)
		(end 83.895692 -54.009036)
		(stroke
			(width 0.2)
			(type default)
		)
		(layer "In6.Cu")
	)
	(gr_line
		(start 85.09 -21.209)
		(end 85.09 -16.129)
		(stroke
			(width 0.381)
			(type default)
		)
		(layer "In6.Cu")
	)
	(gr_line
		(start 85.09 -16.129)
		(end 85.852 -15.367)
		(stroke
			(width 0.381)
			(type default)
		)
		(layer "In6.Cu")
	)
	(gr_arc
		(start 85.330538 -55.356506)
		(mid 85.670517 -55.707536)
		(end 86.021418 -55.367428)
		(stroke
			(width 0.2)
			(type default)
		)
		(layer "In6.Cu")
	)
	(gr_line
		(start 85.339174 -54.79034)
		(end 85.330538 -55.356506)
		(stroke
			(width 0.2)
			(type default)
		)
		(layer "In6.Cu")
	)
	(gr_arc
		(start 85.741764 -53.758592)
		(mid 86.080727 -54.110638)
		(end 86.432644 -53.771546)
		(stroke
			(width 0.2)
			(type default)
		)
		(layer "In6.Cu")
	)
	(gr_line
		(start 85.752178 -53.19522)
		(end 85.741764 -53.758592)
		(stroke
			(width 0.2)
			(type default)
		)
		(layer "In6.Cu")
	)
	(gr_line
		(start 85.852 -26.289)
		(end 85.852 -25.654)
		(stroke
			(width 0.381)
			(type default)
		)
		(layer "In6.Cu")
	)
	(gr_line
		(start 85.852 -25.654)
		(end 86.614 -24.892)
		(stroke
			(width 0.381)
			(type default)
		)
		(layer "In6.Cu")
	)
	(gr_line
		(start 85.852 -15.367)
		(end 91.694 -15.367)
		(stroke
			(width 0.381)
			(type default)
		)
		(layer "In6.Cu")
	)
	(gr_line
		(start 86.021418 -55.367428)
		(end 86.030054 -54.801008)
		(stroke
			(width 0.2)
			(type default)
		)
		(layer "In6.Cu")
	)
	(gr_arc
		(start 86.030054 -54.801008)
		(mid 85.689948 -54.450234)
		(end 85.339174 -54.79034)
		(stroke
			(width 0.2)
			(type default)
		)
		(layer "In6.Cu")
	)
	(gr_line
		(start 86.432644 -53.771546)
		(end 86.443058 -53.20792)
		(stroke
			(width 0.2)
			(type default)
		)
		(layer "In6.Cu")
	)
	(gr_arc
		(start 86.443058 -53.20792)
		(mid 86.103968 -52.85613)
		(end 85.752178 -53.19522)
		(stroke
			(width 0.2)
			(type default)
		)
		(layer "In6.Cu")
	)
	(gr_line
		(start 86.614 -24.892)
		(end 86.614 -22.733)
		(stroke
			(width 0.381)
			(type default)
		)
		(layer "In6.Cu")
	)
	(gr_line
		(start 86.614 -22.733)
		(end 85.09 -21.209)
		(stroke
			(width 0.381)
			(type default)
		)
		(layer "In6.Cu")
	)
	(gr_arc
		(start 86.826852 -54.834028)
		(mid 87.165307 -55.186583)
		(end 87.517732 -54.847998)
		(stroke
			(width 0.2)
			(type default)
		)
		(layer "In6.Cu")
	)
	(gr_line
		(start 86.838028 -54.270402)
		(end 86.826852 -54.834028)
		(stroke
			(width 0.2)
			(type default)
		)
		(layer "In6.Cu")
	)
	(gr_line
		(start 87.517732 -54.847998)
		(end 87.528908 -54.284118)
		(stroke
			(width 0.2)
			(type default)
		)
		(layer "In6.Cu")
	)
	(gr_arc
		(start 87.528908 -54.284118)
		(mid 87.190326 -53.93182)
		(end 86.838028 -54.270402)
		(stroke
			(width 0.2)
			(type default)
		)
		(layer "In6.Cu")
	)
	(gr_line
		(start 87.940896 -53.421534)
		(end 87.95893 -53.98008)
		(stroke
			(width 0.2)
			(type default)
		)
		(layer "In6.Cu")
	)
	(gr_line
		(start 87.943436 -53.421534)
		(end 87.940896 -53.421534)
		(stroke
			(width 0.2)
			(type default)
		)
		(layer "In6.Cu")
	)
	(gr_line
		(start 87.95893 -53.98008)
		(end 87.96147 -53.98008)
		(stroke
			(width 0.2)
			(type default)
		)
		(layer "In6.Cu")
	)
	(gr_arc
		(start 87.96147 -53.98008)
		(mid 88.317832 -54.31409)
		(end 88.651842 -53.957728)
		(stroke
			(width 0.2)
			(type default)
		)
		(layer "In6.Cu")
	)
	(gr_arc
		(start 88.633808 -53.399182)
		(mid 88.277446 -53.065172)
		(end 87.943436 -53.421534)
		(stroke
			(width 0.2)
			(type default)
		)
		(layer "In6.Cu")
	)
	(gr_line
		(start 88.636094 -53.399182)
		(end 88.633808 -53.399182)
		(stroke
			(width 0.2)
			(type default)
		)
		(layer "In6.Cu")
	)
	(gr_line
		(start 88.636348 -53.399436)
		(end 88.636094 -53.399182)
		(stroke
			(width 0.2)
			(type default)
		)
		(layer "In6.Cu")
	)
	(gr_line
		(start 88.646 -34.417)
		(end 88.646 -33.147)
		(stroke
			(width 0.381)
			(type default)
		)
		(layer "In6.Cu")
	)
	(gr_line
		(start 88.646 -33.147)
		(end 89.154 -32.639)
		(stroke
			(width 0.381)
			(type default)
		)
		(layer "In6.Cu")
	)
	(gr_line
		(start 88.646 -30.48)
		(end 88.646 -29.083)
		(stroke
			(width 0.381)
			(type default)
		)
		(layer "In6.Cu")
	)
	(gr_line
		(start 88.646 -29.083)
		(end 85.852 -26.289)
		(stroke
			(width 0.381)
			(type default)
		)
		(layer "In6.Cu")
	)
	(gr_line
		(start 88.651842 -53.957728)
		(end 88.654382 -53.957728)
		(stroke
			(width 0.2)
			(type default)
		)
		(layer "In6.Cu")
	)
	(gr_line
		(start 88.654382 -53.957728)
		(end 88.636348 -53.399436)
		(stroke
			(width 0.2)
			(type default)
		)
		(layer "In6.Cu")
	)
	(gr_line
		(start 89.154 -32.639)
		(end 89.154 -30.988)
		(stroke
			(width 0.381)
			(type default)
		)
		(layer "In6.Cu")
	)
	(gr_line
		(start 89.154 -30.988)
		(end 88.646 -30.48)
		(stroke
			(width 0.381)
			(type default)
		)
		(layer "In6.Cu")
	)
	(gr_line
		(start 89.154 -25.4)
		(end 91.948 -28.194)
		(stroke
			(width 0.381)
			(type default)
		)
		(layer "In6.Cu")
	)
	(gr_line
		(start 89.154 -21.463)
		(end 89.154 -25.4)
		(stroke
			(width 0.381)
			(type default)
		)
		(layer "In6.Cu")
	)
	(gr_arc
		(start 89.415874 -54.043326)
		(mid 89.727024 -54.420008)
		(end 90.103706 -54.108858)
		(stroke
			(width 0.2)
			(type default)
		)
		(layer "In6.Cu")
	)
	(gr_line
		(start 89.46896 -53.486812)
		(end 89.415874 -54.043326)
		(stroke
			(width 0.2)
			(type default)
		)
		(layer "In6.Cu")
	)
	(gr_line
		(start 90.103706 -54.108858)
		(end 90.156792 -53.552598)
		(stroke
			(width 0.2)
			(type default)
		)
		(layer "In6.Cu")
	)
	(gr_arc
		(start 90.156792 -53.552598)
		(mid 89.845768 -53.175928)
		(end 89.46896 -53.486812)
		(stroke
			(width 0.2)
			(type default)
		)
		(layer "In6.Cu")
	)
	(gr_line
		(start 90.681556 -53.93817)
		(end 90.684096 -53.938424)
		(stroke
			(width 0.2)
			(type default)
		)
		(layer "In6.Cu")
	)
	(gr_arc
		(start 90.684096 -53.938424)
		(mid 91.010994 -54.30139)
		(end 91.37396 -53.974492)
		(stroke
			(width 0.2)
			(type default)
		)
		(layer "In6.Cu")
	)
	(gr_line
		(start 90.71102 -53.377592)
		(end 90.681556 -53.93817)
		(stroke
			(width 0.2)
			(type default)
		)
		(layer "In6.Cu")
	)
	(gr_line
		(start 90.71356 -53.377846)
		(end 90.71102 -53.377592)
		(stroke
			(width 0.2)
			(type default)
		)
		(layer "In6.Cu")
	)
	(gr_line
		(start 90.73769 -54.954932)
		(end 90.73896 -54.956964)
		(stroke
			(width 0.2)
			(type default)
		)
		(layer "In6.Cu")
	)
	(gr_line
		(start 90.73769 -54.954678)
		(end 90.73769 -54.954932)
		(stroke
			(width 0.2)
			(type default)
		)
		(layer "In6.Cu")
	)
	(gr_arc
		(start 90.73896 -54.956964)
		(mid 90.631264 -55.433468)
		(end 91.107768 -55.541164)
		(stroke
			(width 0.2)
			(type default)
		)
		(layer "In6.Cu")
	)
	(gr_line
		(start 90.932 -38.608)
		(end 90.932 -36.703)
		(stroke
			(width 0.381)
			(type default)
		)
		(layer "In6.Cu")
	)
	(gr_line
		(start 90.932 -36.703)
		(end 88.646 -34.417)
		(stroke
			(width 0.381)
			(type default)
		)
		(layer "In6.Cu")
	)
	(gr_line
		(start 91.107768 -55.541164)
		(end 91.109038 -55.543196)
		(stroke
			(width 0.2)
			(type default)
		)
		(layer "In6.Cu")
	)
	(gr_line
		(start 91.109038 -55.543196)
		(end 91.581732 -55.244746)
		(stroke
			(width 0.2)
			(type default)
		)
		(layer "In6.Cu")
	)
	(gr_line
		(start 91.210384 -54.656482)
		(end 90.73769 -54.954678)
		(stroke
			(width 0.2)
			(type default)
		)
		(layer "In6.Cu")
	)
	(gr_line
		(start 91.211654 -54.658514)
		(end 91.210384 -54.656482)
		(stroke
			(width 0.2)
			(type default)
		)
		(layer "In6.Cu")
	)
	(gr_line
		(start 91.37396 -53.974492)
		(end 91.3765 -53.974746)
		(stroke
			(width 0.2)
			(type default)
		)
		(layer "In6.Cu")
	)
	(gr_line
		(start 91.3765 -53.974746)
		(end 91.405964 -53.414422)
		(stroke
			(width 0.2)
			(type default)
		)
		(layer "In6.Cu")
	)
	(gr_arc
		(start 91.403424 -53.414168)
		(mid 91.076653 -53.050941)
		(end 90.71356 -53.377846)
		(stroke
			(width 0.2)
			(type default)
		)
		(layer "In6.Cu")
	)
	(gr_line
		(start 91.40571 -53.414168)
		(end 91.403424 -53.414168)
		(stroke
			(width 0.2)
			(type default)
		)
		(layer "In6.Cu")
	)
	(gr_line
		(start 91.405964 -53.414422)
		(end 91.40571 -53.414168)
		(stroke
			(width 0.2)
			(type default)
		)
		(layer "In6.Cu")
	)
	(gr_arc
		(start 91.580462 -55.242714)
		(mid 91.688158 -54.76621)
		(end 91.211654 -54.658514)
		(stroke
			(width 0.2)
			(type default)
		)
		(layer "In6.Cu")
	)
	(gr_line
		(start 91.581732 -55.244746)
		(end 91.580462 -55.242714)
		(stroke
			(width 0.2)
			(type default)
		)
		(layer "In6.Cu")
	)
	(gr_line
		(start 91.694 -45.085)
		(end 91.694 -39.37)
		(stroke
			(width 0.381)
			(type default)
		)
		(layer "In6.Cu")
	)
	(gr_line
		(start 91.694 -39.37)
		(end 90.932 -38.608)
		(stroke
			(width 0.381)
			(type default)
		)
		(layer "In6.Cu")
	)
	(gr_line
		(start 91.694 -15.367)
		(end 92.71 -16.383)
		(stroke
			(width 0.381)
			(type default)
		)
		(layer "In6.Cu")
	)
	(gr_line
		(start 91.948 -28.194)
		(end 97.409 -28.194)
		(stroke
			(width 0.381)
			(type default)
		)
		(layer "In6.Cu")
	)
	(gr_line
		(start 92.71 -17.907)
		(end 89.154 -21.463)
		(stroke
			(width 0.381)
			(type default)
		)
		(layer "In6.Cu")
	)
	(gr_line
		(start 92.71 -16.383)
		(end 92.71 -17.907)
		(stroke
			(width 0.381)
			(type default)
		)
		(layer "In6.Cu")
	)
	(gr_line
		(start 93.218 -46.609)
		(end 91.694 -45.085)
		(stroke
			(width 0.381)
			(type default)
		)
		(layer "In6.Cu")
	)
	(gr_line
		(start 97.028 -46.609)
		(end 93.218 -46.609)
		(stroke
			(width 0.381)
			(type default)
		)
		(layer "In6.Cu")
	)
	(gr_line
		(start 97.409 -32.004)
		(end 97.663 -32.258)
		(stroke
			(width 0.3048)
			(type default)
		)
		(layer "In6.Cu")
	)
	(gr_line
		(start 97.409 -25.908)
		(end 97.409 -32.004)
		(stroke
			(width 0.3048)
			(type default)
		)
		(layer "In6.Cu")
	)
	(gr_line
		(start 97.663 -32.258)
		(end 98.298 -32.258)
		(stroke
			(width 0.3048)
			(type default)
		)
		(layer "In6.Cu")
	)
	(gr_line
		(start 98.044 -50.165)
		(end 98.044 -45.593)
		(stroke
			(width 0.3048)
			(type default)
		)
		(layer "In6.Cu")
	)
	(gr_line
		(start 98.044 -45.593)
		(end 97.028 -46.609)
		(stroke
			(width 0.381)
			(type default)
		)
		(layer "In6.Cu")
	)
	(gr_line
		(start 98.044 -45.593)
		(end 98.806 -44.831)
		(stroke
			(width 0.3048)
			(type default)
		)
		(layer "In6.Cu")
	)
	(gr_line
		(start 98.298 -32.258)
		(end 98.552 -32.004)
		(stroke
			(width 0.3048)
			(type default)
		)
		(layer "In6.Cu")
	)
	(gr_line
		(start 98.425 -57.15)
		(end 98.425 -50.546)
		(stroke
			(width 0.3048)
			(type default)
		)
		(layer "In6.Cu")
	)
	(gr_line
		(start 98.425 -50.546)
		(end 98.044 -50.165)
		(stroke
			(width 0.3048)
			(type default)
		)
		(layer "In6.Cu")
	)
	(gr_line
		(start 98.552 -32.004)
		(end 99.314 -32.004)
		(stroke
			(width 0.3048)
			(type default)
		)
		(layer "In6.Cu")
	)
	(gr_line
		(start 98.806 -44.831)
		(end 107.188 -44.831)
		(stroke
			(width 0.3048)
			(type default)
		)
		(layer "In6.Cu")
	)
	(gr_line
		(start 98.806 -24.511)
		(end 97.409 -25.908)
		(stroke
			(width 0.3048)
			(type default)
		)
		(layer "In6.Cu")
	)
	(gr_line
		(start 98.806 -21.717)
		(end 98.806 -24.511)
		(stroke
			(width 0.3048)
			(type default)
		)
		(layer "In6.Cu")
	)
	(gr_line
		(start 99.24542 -60.922154)
		(end 99.86518 -61.523372)
		(stroke
			(width 0.2)
			(type default)
		)
		(layer "In6.Cu")
	)
	(gr_line
		(start 99.247198 -60.920376)
		(end 99.24542 -60.922154)
		(stroke
			(width 0.2)
			(type default)
		)
		(layer "In6.Cu")
	)
	(gr_line
		(start 99.314 -32.004)
		(end 99.568 -32.258)
		(stroke
			(width 0.3048)
			(type default)
		)
		(layer "In6.Cu")
	)
	(gr_line
		(start 99.441 -42.926)
		(end 99.441 -37.084)
		(stroke
			(width 0.3048)
			(type default)
		)
		(layer "In6.Cu")
	)
	(gr_line
		(start 99.441 -37.084)
		(end 99.695 -36.83)
		(stroke
			(width 0.3048)
			(type default)
		)
		(layer "In6.Cu")
	)
	(gr_line
		(start 99.568 -32.639)
		(end 100.584 -33.655)
		(stroke
			(width 0.3048)
			(type default)
		)
		(layer "In6.Cu")
	)
	(gr_line
		(start 99.568 -32.258)
		(end 99.568 -32.639)
		(stroke
			(width 0.3048)
			(type default)
		)
		(layer "In6.Cu")
	)
	(gr_line
		(start 99.695 -43.18)
		(end 99.441 -42.926)
		(stroke
			(width 0.3048)
			(type default)
		)
		(layer "In6.Cu")
	)
	(gr_line
		(start 99.695 -36.83)
		(end 101.727 -36.83)
		(stroke
			(width 0.3048)
			(type default)
		)
		(layer "In6.Cu")
	)
	(gr_arc
		(start 99.781106 -60.369704)
		(mid 99.238816 -60.378086)
		(end 99.247198 -60.920376)
		(stroke
			(width 0.2)
			(type default)
		)
		(layer "In6.Cu")
	)
	(gr_line
		(start 99.782884 -60.367926)
		(end 99.781106 -60.369704)
		(stroke
			(width 0.2)
			(type default)
		)
		(layer "In6.Cu")
	)
	(gr_line
		(start 99.86518 -61.523372)
		(end 99.865434 -61.523372)
		(stroke
			(width 0.2)
			(type default)
		)
		(layer "In6.Cu")
	)
	(gr_line
		(start 99.865434 -61.523372)
		(end 99.866958 -61.521848)
		(stroke
			(width 0.2)
			(type default)
		)
		(layer "In6.Cu")
	)
	(gr_arc
		(start 99.866958 -61.521848)
		(mid 100.409565 -61.513655)
		(end 100.40112 -60.971176)
		(stroke
			(width 0.2)
			(type default)
		)
		(layer "In6.Cu")
	)
	(gr_line
		(start 100.40112 -60.971176)
		(end 100.402898 -60.969398)
		(stroke
			(width 0.2)
			(type default)
		)
		(layer "In6.Cu")
	)
	(gr_line
		(start 100.402898 -60.969398)
		(end 99.782884 -60.367926)
		(stroke
			(width 0.2)
			(type default)
		)
		(layer "In6.Cu")
	)
	(gr_line
		(start 100.584 -33.655)
		(end 104.013 -33.655)
		(stroke
			(width 0.3048)
			(type default)
		)
		(layer "In6.Cu")
	)
	(gr_line
		(start 100.711 -19.685)
		(end 98.806 -21.717)
		(stroke
			(width 0.381)
			(type default)
		)
		(layer "In6.Cu")
	)
	(gr_line
		(start 101.185472 -62.20587)
		(end 101.795072 -62.817756)
		(stroke
			(width 0.2)
			(type default)
		)
		(layer "In6.Cu")
	)
	(gr_line
		(start 101.6 -43.18)
		(end 99.695 -43.18)
		(stroke
			(width 0.3048)
			(type default)
		)
		(layer "In6.Cu")
	)
	(gr_line
		(start 101.727 -36.83)
		(end 102.743 -35.814)
		(stroke
			(width 0.3048)
			(type default)
		)
		(layer "In6.Cu")
	)
	(gr_arc
		(start 101.734366 -61.66993)
		(mid 101.189299 -61.660676)
		(end 101.185472 -62.20587)
		(stroke
			(width 0.2)
			(type default)
		)
		(layer "In6.Cu")
	)
	(gr_arc
		(start 101.795072 -62.817756)
		(mid 102.337616 -62.818772)
		(end 102.338632 -62.276228)
		(stroke
			(width 0.2)
			(type default)
		)
		(layer "In6.Cu")
	)
	(gr_line
		(start 101.854 -44.831)
		(end 101.854 -43.434)
		(stroke
			(width 0.3048)
			(type default)
		)
		(layer "In6.Cu")
	)
	(gr_line
		(start 101.854 -43.434)
		(end 101.6 -43.18)
		(stroke
			(width 0.3048)
			(type default)
		)
		(layer "In6.Cu")
	)
	(gr_line
		(start 102.338632 -62.276228)
		(end 101.734366 -61.66993)
		(stroke
			(width 0.2)
			(type default)
		)
		(layer "In6.Cu")
	)
	(gr_line
		(start 102.616 -61.341)
		(end 98.425 -57.15)
		(stroke
			(width 0.381)
			(type default)
		)
		(layer "In6.Cu")
	)
	(gr_line
		(start 102.743 -35.814)
		(end 102.743 -33.655)
		(stroke
			(width 0.3048)
			(type default)
		)
		(layer "In6.Cu")
	)
	(gr_line
		(start 104.013 -33.655)
		(end 104.267 -33.909)
		(stroke
			(width 0.3048)
			(type default)
		)
		(layer "In6.Cu")
	)
	(gr_line
		(start 104.267 -33.909)
		(end 110.998 -33.909)
		(stroke
			(width 0.3048)
			(type default)
		)
		(layer "In6.Cu")
	)
	(gr_line
		(start 107.188 -44.831)
		(end 107.442 -44.958)
		(stroke
			(width 0.3048)
			(type default)
		)
		(layer "In6.Cu")
	)
	(gr_line
		(start 107.442 -44.958)
		(end 108.585 -44.958)
		(stroke
			(width 0.3048)
			(type default)
		)
		(layer "In6.Cu")
	)
	(gr_line
		(start 108.331 -19.685)
		(end 100.711 -19.685)
		(stroke
			(width 0.381)
			(type default)
		)
		(layer "In6.Cu")
	)
	(gr_line
		(start 108.585 -44.958)
		(end 109.093 -45.466)
		(stroke
			(width 0.3048)
			(type default)
		)
		(layer "In6.Cu")
	)
	(gr_line
		(start 109.093 -45.466)
		(end 117.983 -45.466)
		(stroke
			(width 0.3048)
			(type default)
		)
		(layer "In6.Cu")
	)
	(gr_line
		(start 110.998 -33.909)
		(end 111.633 -33.274)
		(stroke
			(width 0.3048)
			(type default)
		)
		(layer "In6.Cu")
	)
	(gr_line
		(start 111.633 -33.274)
		(end 112.141 -33.274)
		(stroke
			(width 0.3048)
			(type default)
		)
		(layer "In6.Cu")
	)
	(gr_line
		(start 112.141 -33.274)
		(end 114.427 -30.988)
		(stroke
			(width 0.3048)
			(type default)
		)
		(layer "In6.Cu")
	)
	(gr_line
		(start 114.173 -13.843)
		(end 108.331 -19.685)
		(stroke
			(width 0.381)
			(type default)
		)
		(layer "In6.Cu")
	)
	(gr_line
		(start 114.427 -30.988)
		(end 117.856 -30.988)
		(stroke
			(width 0.3048)
			(type default)
		)
		(layer "In6.Cu")
	)
	(gr_line
		(start 117.856 -30.988)
		(end 118.999 -29.845)
		(stroke
			(width 0.381)
			(type default)
		)
		(layer "In6.Cu")
	)
	(gr_line
		(start 117.983 -45.466)
		(end 118.237 -45.72)
		(stroke
			(width 0.3048)
			(type default)
		)
		(layer "In6.Cu")
	)
	(gr_line
		(start 118.237 -45.72)
		(end 120.777 -45.72)
		(stroke
			(width 0.3048)
			(type default)
		)
		(layer "In6.Cu")
	)
	(gr_line
		(start 118.999 -29.845)
		(end 161.417 -29.845)
		(stroke
			(width 0.381)
			(type default)
		)
		(layer "In6.Cu")
	)
	(gr_line
		(start 120.777 -45.72)
		(end 121.158 -45.339)
		(stroke
			(width 0.381)
			(type default)
		)
		(layer "In6.Cu")
	)
	(gr_line
		(start 121.158 -45.339)
		(end 151.511 -45.339)
		(stroke
			(width 0.381)
			(type default)
		)
		(layer "In6.Cu")
	)
	(gr_line
		(start 131.318 -13.843)
		(end 114.173 -13.843)
		(stroke
			(width 0.381)
			(type default)
		)
		(layer "In6.Cu")
	)
	(gr_line
		(start 135.382 -61.341)
		(end 102.616 -61.341)
		(stroke
			(width 0.381)
			(type default)
		)
		(layer "In6.Cu")
	)
	(gr_line
		(start 135.382 -9.779)
		(end 131.318 -13.843)
		(stroke
			(width 0.381)
			(type default)
		)
		(layer "In6.Cu")
	)
	(gr_line
		(start 137.16 -64.77)
		(end 137.16 -63.119)
		(stroke
			(width 0.381)
			(type default)
		)
		(layer "In6.Cu")
	)
	(gr_line
		(start 137.16 -63.119)
		(end 135.382 -61.341)
		(stroke
			(width 0.381)
			(type default)
		)
		(layer "In6.Cu")
	)
	(gr_line
		(start 142.494 -70.104)
		(end 137.16 -64.77)
		(stroke
			(width 0.381)
			(type default)
		)
		(layer "In6.Cu")
	)
	(gr_line
		(start 144.78 -9.779)
		(end 135.382 -9.779)
		(stroke
			(width 0.381)
			(type default)
		)
		(layer "In6.Cu")
	)
	(gr_line
		(start 151.511 -45.339)
		(end 166.37 -60.198)
		(stroke
			(width 0.381)
			(type default)
		)
		(layer "In6.Cu")
	)
	(gr_line
		(start 152.019 -2.54)
		(end 144.78 -9.779)
		(stroke
			(width 0.381)
			(type default)
		)
		(layer "In6.Cu")
	)
	(gr_line
		(start 161.417 -29.845)
		(end 168.783 -22.479)
		(stroke
			(width 0.381)
			(type default)
		)
		(layer "In6.Cu")
	)
	(gr_line
		(start 166.37 -62.738)
		(end 168.656 -65.024)
		(stroke
			(width 0.381)
			(type default)
		)
		(layer "In6.Cu")
	)
	(gr_line
		(start 166.37 -60.198)
		(end 166.37 -62.738)
		(stroke
			(width 0.381)
			(type default)
		)
		(layer "In6.Cu")
	)
	(gr_line
		(start 166.497 -70.104)
		(end 142.494 -70.104)
		(stroke
			(width 0.381)
			(type default)
		)
		(layer "In6.Cu")
	)
	(gr_line
		(start 168.656 -67.945)
		(end 166.497 -70.104)
		(stroke
			(width 0.381)
			(type default)
		)
		(layer "In6.Cu")
	)
	(gr_line
		(start 168.656 -65.024)
		(end 168.656 -67.945)
		(stroke
			(width 0.381)
			(type default)
		)
		(layer "In6.Cu")
	)
	(gr_line
		(start 168.783 -22.479)
		(end 187.833 -22.479)
		(stroke
			(width 0.381)
			(type default)
		)
		(layer "In6.Cu")
	)
	(gr_line
		(start 187.833 -22.479)
		(end 195.961 -14.351)
		(stroke
			(width 0.381)
			(type default)
		)
		(layer "In6.Cu")
	)
	(gr_line
		(start 193.294 -2.54)
		(end 152.019 -2.54)
		(stroke
			(width 0.381)
			(type default)
		)
		(layer "In6.Cu")
	)
	(gr_line
		(start 195.961 -14.351)
		(end 195.961 -5.334)
		(stroke
			(width 0.381)
			(type default)
		)
		(layer "In6.Cu")
	)
	(gr_line
		(start 195.961 -5.334)
		(end 193.294 -2.54)
		(stroke
			(width 0.381)
			(type default)
		)
		(layer "In6.Cu")
	)
	(gr_line
		(start 9.6266 -65.405)
		(end 9.835896 -65.195704)
		(stroke
			(width 0.05715)
			(type default)
		)
		(layer "In7.Cu")
	)
	(gr_line
		(start 9.6266 -64.516)
		(end 9.835896 -64.725296)
		(stroke
			(width 0.05715)
			(type default)
		)
		(layer "In7.Cu")
	)
	(gr_line
		(start 9.6266 -62.738)
		(end 9.848596 -62.959996)
		(stroke
			(width 0.05715)
			(type default)
		)
		(layer "In7.Cu")
	)
	(gr_line
		(start 9.6266 -61.849)
		(end 9.835896 -61.639704)
		(stroke
			(width 0.05715)
			(type default)
		)
		(layer "In7.Cu")
	)
	(gr_line
		(start 9.6266 -60.96)
		(end 9.835896 -61.169296)
		(stroke
			(width 0.05715)
			(type default)
		)
		(layer "In7.Cu")
	)
	(gr_line
		(start 9.6266 -59.182)
		(end 9.848596 -59.403996)
		(stroke
			(width 0.05715)
			(type default)
		)
		(layer "In7.Cu")
	)
	(gr_line
		(start 9.6266 -58.293)
		(end 9.835896 -58.083704)
		(stroke
			(width 0.05715)
			(type default)
		)
		(layer "In7.Cu")
	)
	(gr_line
		(start 9.6266 -57.404)
		(end 9.835896 -57.613296)
		(stroke
			(width 0.05715)
			(type default)
		)
		(layer "In7.Cu")
	)
	(gr_line
		(start 9.6266 -56.515)
		(end 9.835896 -56.305704)
		(stroke
			(width 0.05715)
			(type default)
		)
		(layer "In7.Cu")
	)
	(gr_line
		(start 9.6266 -55.626)
		(end 9.835896 -55.835296)
		(stroke
			(width 0.05715)
			(type default)
		)
		(layer "In7.Cu")
	)
	(gr_line
		(start 9.652 -63.627)
		(end 9.848596 -63.430404)
		(stroke
			(width 0.05715)
			(type default)
		)
		(layer "In7.Cu")
	)
	(gr_line
		(start 9.652 -60.071)
		(end 9.848596 -59.874404)
		(stroke
			(width 0.05715)
			(type default)
		)
		(layer "In7.Cu")
	)
	(gr_line
		(start 13.17244 -48.61814)
		(end 13.416026 -48.374554)
		(stroke
			(width 0.05715)
			(type default)
		)
		(layer "In7.Cu")
	)
	(gr_line
		(start 13.17244 -47.66056)
		(end 13.416026 -47.904146)
		(stroke
			(width 0.05715)
			(type default)
		)
		(layer "In7.Cu")
	)
	(gr_line
		(start 14.15288 -46.83252)
		(end 14.382242 -46.603158)
		(stroke
			(width 0.05715)
			(type default)
		)
		(layer "In7.Cu")
	)
	(gr_line
		(start 14.852904 -46.603158)
		(end 15.082266 -46.83252)
		(stroke
			(width 0.05715)
			(type default)
		)
		(layer "In7.Cu")
	)
	(gr_line
		(start 15.027148 -45.567346)
		(end 15.100554 -45.49394)
		(stroke
			(width 0.05715)
			(type default)
		)
		(layer "In7.Cu")
	)
	(gr_line
		(start 15.028926 -46.03623)
		(end 15.327122 -46.03623)
		(stroke
			(width 0.05715)
			(type default)
		)
		(layer "In7.Cu")
	)
	(gr_line
		(start 15.327122 -46.03623)
		(end 15.569438 -45.793914)
		(stroke
			(width 0.05715)
			(type default)
		)
		(layer "In7.Cu")
	)
	(gr_line
		(start 15.569438 -45.495718)
		(end 15.569438 -45.793914)
		(stroke
			(width 0.05715)
			(type default)
		)
		(layer "In7.Cu")
	)
	(gr_line
		(start 15.813786 -44.780708)
		(end 15.887192 -44.707302)
		(stroke
			(width 0.05715)
			(type default)
		)
		(layer "In7.Cu")
	)
	(gr_line
		(start 15.815564 -45.249592)
		(end 16.11376 -45.249592)
		(stroke
			(width 0.05715)
			(type default)
		)
		(layer "In7.Cu")
	)
	(gr_line
		(start 16.11376 -45.249592)
		(end 16.356076 -45.007276)
		(stroke
			(width 0.05715)
			(type default)
		)
		(layer "In7.Cu")
	)
	(gr_line
		(start 16.356076 -44.70908)
		(end 16.356076 -45.007276)
		(stroke
			(width 0.05715)
			(type default)
		)
		(layer "In7.Cu")
	)
	(gr_line
		(start 16.447008 -55.630318)
		(end 16.447008 -55.928514)
		(stroke
			(width 0.05715)
			(type default)
		)
		(layer "In7.Cu")
	)
	(gr_line
		(start 16.447008 -55.630318)
		(end 16.689324 -55.388002)
		(stroke
			(width 0.05715)
			(type default)
		)
		(layer "In7.Cu")
	)
	(gr_line
		(start 16.689324 -55.388002)
		(end 16.98752 -55.388002)
		(stroke
			(width 0.05715)
			(type default)
		)
		(layer "In7.Cu")
	)
	(gr_line
		(start 16.915892 -55.930292)
		(end 16.989298 -55.856886)
		(stroke
			(width 0.05715)
			(type default)
		)
		(layer "In7.Cu")
	)
	(gr_line
		(start 16.955008 -46.179486)
		(end 16.955008 -46.477682)
		(stroke
			(width 0.05715)
			(type default)
		)
		(layer "In7.Cu")
	)
	(gr_line
		(start 16.955008 -46.179486)
		(end 17.197324 -45.93717)
		(stroke
			(width 0.05715)
			(type default)
		)
		(layer "In7.Cu")
	)
	(gr_line
		(start 17.197324 -45.93717)
		(end 17.49552 -45.93717)
		(stroke
			(width 0.05715)
			(type default)
		)
		(layer "In7.Cu")
	)
	(gr_line
		(start 17.233646 -54.84368)
		(end 17.233646 -55.141876)
		(stroke
			(width 0.05715)
			(type default)
		)
		(layer "In7.Cu")
	)
	(gr_line
		(start 17.233646 -54.84368)
		(end 17.475962 -54.601364)
		(stroke
			(width 0.05715)
			(type default)
		)
		(layer "In7.Cu")
	)
	(gr_line
		(start 17.423892 -46.47946)
		(end 17.497298 -46.406054)
		(stroke
			(width 0.05715)
			(type default)
		)
		(layer "In7.Cu")
	)
	(gr_line
		(start 17.475962 -54.601364)
		(end 17.774158 -54.601364)
		(stroke
			(width 0.05715)
			(type default)
		)
		(layer "In7.Cu")
	)
	(gr_line
		(start 17.70253 -55.143654)
		(end 17.775936 -55.070248)
		(stroke
			(width 0.05715)
			(type default)
		)
		(layer "In7.Cu")
	)
	(gr_line
		(start 22.297136 -49.26076)
		(end 22.507956 -49.04994)
		(stroke
			(width 0.05715)
			(type default)
		)
		(layer "In7.Cu")
	)
	(gr_line
		(start 22.507956 -49.04994)
		(end 22.850856 -49.04994)
		(stroke
			(width 0.05715)
			(type default)
		)
		(layer "In7.Cu")
	)
	(gr_line
		(start 22.627336 -49.5935)
		(end 22.731476 -49.5935)
		(stroke
			(width 0.05715)
			(type default)
		)
		(layer "In7.Cu")
	)
	(gr_line
		(start 22.850856 -49.04994)
		(end 23.061676 -49.26076)
		(stroke
			(width 0.05715)
			(type default)
		)
		(layer "In7.Cu")
	)
	(gr_line
		(start 23.409656 -49.26076)
		(end 23.620476 -49.04994)
		(stroke
			(width 0.05715)
			(type default)
		)
		(layer "In7.Cu")
	)
	(gr_line
		(start 23.620476 -49.04994)
		(end 23.963376 -49.04994)
		(stroke
			(width 0.05715)
			(type default)
		)
		(layer "In7.Cu")
	)
	(gr_line
		(start 23.739856 -49.5935)
		(end 23.843996 -49.5935)
		(stroke
			(width 0.05715)
			(type default)
		)
		(layer "In7.Cu")
	)
	(gr_line
		(start 23.959312 -44.572936)
		(end 23.959312 -44.871132)
		(stroke
			(width 0.05715)
			(type default)
		)
		(layer "In7.Cu")
	)
	(gr_line
		(start 23.959312 -44.572936)
		(end 24.201628 -44.33062)
		(stroke
			(width 0.05715)
			(type default)
		)
		(layer "In7.Cu")
	)
	(gr_line
		(start 23.963376 -49.04994)
		(end 24.174196 -49.26076)
		(stroke
			(width 0.05715)
			(type default)
		)
		(layer "In7.Cu")
	)
	(gr_line
		(start 24.201628 -44.33062)
		(end 24.499824 -44.33062)
		(stroke
			(width 0.05715)
			(type default)
		)
		(layer "In7.Cu")
	)
	(gr_line
		(start 24.428196 -44.87291)
		(end 24.501602 -44.799504)
		(stroke
			(width 0.05715)
			(type default)
		)
		(layer "In7.Cu")
	)
	(gr_line
		(start 24.522176 -49.26076)
		(end 24.732996 -49.04994)
		(stroke
			(width 0.05715)
			(type default)
		)
		(layer "In7.Cu")
	)
	(gr_line
		(start 24.732996 -49.04994)
		(end 25.075896 -49.04994)
		(stroke
			(width 0.05715)
			(type default)
		)
		(layer "In7.Cu")
	)
	(gr_line
		(start 24.852376 -49.5935)
		(end 24.956516 -49.5935)
		(stroke
			(width 0.05715)
			(type default)
		)
		(layer "In7.Cu")
	)
	(gr_line
		(start 25.075896 -49.04994)
		(end 25.286716 -49.26076)
		(stroke
			(width 0.05715)
			(type default)
		)
		(layer "In7.Cu")
	)
	(gr_line
		(start 26.747216 -47.971964)
		(end 26.747216 -48.269906)
		(stroke
			(width 0.05715)
			(type default)
		)
		(layer "In7.Cu")
	)
	(gr_line
		(start 26.747216 -47.971964)
		(end 26.989532 -47.729394)
		(stroke
			(width 0.05715)
			(type default)
		)
		(layer "In7.Cu")
	)
	(gr_line
		(start 26.989532 -47.729394)
		(end 27.287728 -47.729394)
		(stroke
			(width 0.05715)
			(type default)
		)
		(layer "In7.Cu")
	)
	(gr_line
		(start 27.2161 -48.271684)
		(end 27.289506 -48.198278)
		(stroke
			(width 0.05715)
			(type default)
		)
		(layer "In7.Cu")
	)
	(gr_line
		(start 27.254962 -41.124632)
		(end 27.323034 -41.192704)
		(stroke
			(width 0.05715)
			(type default)
		)
		(layer "In7.Cu")
	)
	(gr_line
		(start 28.073604 -47.468536)
		(end 28.284424 -47.257716)
		(stroke
			(width 0.05715)
			(type default)
		)
		(layer "In7.Cu")
	)
	(gr_line
		(start 28.284424 -47.257716)
		(end 28.627324 -47.257716)
		(stroke
			(width 0.05715)
			(type default)
		)
		(layer "In7.Cu")
	)
	(gr_line
		(start 28.403804 -47.801276)
		(end 28.507944 -47.801276)
		(stroke
			(width 0.05715)
			(type default)
		)
		(layer "In7.Cu")
	)
	(gr_line
		(start 28.619958 -42.956988)
		(end 28.68803 -43.02506)
		(stroke
			(width 0.05715)
			(type default)
		)
		(layer "In7.Cu")
	)
	(gr_line
		(start 28.627324 -47.257716)
		(end 28.838144 -47.468536)
		(stroke
			(width 0.05715)
			(type default)
		)
		(layer "In7.Cu")
	)
	(gr_line
		(start 29.123386 -43.02506)
		(end 29.191458 -42.956988)
		(stroke
			(width 0.05715)
			(type default)
		)
		(layer "In7.Cu")
	)
	(gr_line
		(start 29.186124 -47.468536)
		(end 29.396944 -47.257716)
		(stroke
			(width 0.05715)
			(type default)
		)
		(layer "In7.Cu")
	)
	(gr_line
		(start 29.396944 -47.257716)
		(end 29.739844 -47.257716)
		(stroke
			(width 0.05715)
			(type default)
		)
		(layer "In7.Cu")
	)
	(gr_line
		(start 29.516324 -47.801276)
		(end 29.620464 -47.801276)
		(stroke
			(width 0.05715)
			(type default)
		)
		(layer "In7.Cu")
	)
	(gr_line
		(start 29.625798 -42.522648)
		(end 29.69387 -42.454576)
		(stroke
			(width 0.05715)
			(type default)
		)
		(layer "In7.Cu")
	)
	(gr_line
		(start 29.739844 -47.257716)
		(end 29.950664 -47.468536)
		(stroke
			(width 0.05715)
			(type default)
		)
		(layer "In7.Cu")
	)
	(gr_line
		(start 30.298644 -47.468536)
		(end 30.509464 -47.257716)
		(stroke
			(width 0.05715)
			(type default)
		)
		(layer "In7.Cu")
	)
	(gr_line
		(start 30.509464 -47.257716)
		(end 30.852364 -47.257716)
		(stroke
			(width 0.05715)
			(type default)
		)
		(layer "In7.Cu")
	)
	(gr_line
		(start 30.628844 -47.801276)
		(end 30.732984 -47.801276)
		(stroke
			(width 0.05715)
			(type default)
		)
		(layer "In7.Cu")
	)
	(gr_line
		(start 30.8229 -51.149504)
		(end 30.896306 -51.22291)
		(stroke
			(width 0.05715)
			(type default)
		)
		(layer "In7.Cu")
	)
	(gr_line
		(start 30.824678 -50.68062)
		(end 31.122874 -50.68062)
		(stroke
			(width 0.05715)
			(type default)
		)
		(layer "In7.Cu")
	)
	(gr_line
		(start 30.852364 -47.257716)
		(end 31.063184 -47.468536)
		(stroke
			(width 0.05715)
			(type default)
		)
		(layer "In7.Cu")
	)
	(gr_line
		(start 31.122874 -50.68062)
		(end 31.36519 -50.922936)
		(stroke
			(width 0.05715)
			(type default)
		)
		(layer "In7.Cu")
	)
	(gr_line
		(start 31.36519 -50.922936)
		(end 31.36519 -51.221132)
		(stroke
			(width 0.05715)
			(type default)
		)
		(layer "In7.Cu")
	)
	(gr_line
		(start 38.9763 -41.20642)
		(end 38.9763 -41.31056)
		(stroke
			(width 0.05715)
			(type default)
		)
		(layer "In7.Cu")
	)
	(gr_line
		(start 39.30904 -41.64076)
		(end 39.51986 -41.42994)
		(stroke
			(width 0.05715)
			(type default)
		)
		(layer "In7.Cu")
	)
	(gr_line
		(start 39.30904 -40.87622)
		(end 39.51986 -41.08704)
		(stroke
			(width 0.05715)
			(type default)
		)
		(layer "In7.Cu")
	)
	(gr_line
		(start 39.51986 -41.08704)
		(end 39.51986 -41.42994)
		(stroke
			(width 0.05715)
			(type default)
		)
		(layer "In7.Cu")
	)
	(gr_line
		(start 40.58412 -39.75354)
		(end 40.79494 -39.96436)
		(stroke
			(width 0.05715)
			(type default)
		)
		(layer "In7.Cu")
	)
	(gr_line
		(start 40.79494 -39.96436)
		(end 41.13784 -39.96436)
		(stroke
			(width 0.05715)
			(type default)
		)
		(layer "In7.Cu")
	)
	(gr_line
		(start 40.91432 -39.4208)
		(end 41.01846 -39.4208)
		(stroke
			(width 0.05715)
			(type default)
		)
		(layer "In7.Cu")
	)
	(gr_line
		(start 41.13784 -39.96436)
		(end 41.34866 -39.75354)
		(stroke
			(width 0.05715)
			(type default)
		)
		(layer "In7.Cu")
	)
	(gr_line
		(start 45.872654 -47.24654)
		(end 46.083474 -47.45736)
		(stroke
			(width 0.05715)
			(type default)
		)
		(layer "In7.Cu")
	)
	(gr_line
		(start 46.083474 -47.45736)
		(end 46.426374 -47.45736)
		(stroke
			(width 0.05715)
			(type default)
		)
		(layer "In7.Cu")
	)
	(gr_line
		(start 46.202854 -46.9138)
		(end 46.306994 -46.9138)
		(stroke
			(width 0.05715)
			(type default)
		)
		(layer "In7.Cu")
	)
	(gr_line
		(start 46.426374 -47.45736)
		(end 46.637194 -47.24654)
		(stroke
			(width 0.05715)
			(type default)
		)
		(layer "In7.Cu")
	)
	(gr_line
		(start 46.985174 -47.24654)
		(end 47.195994 -47.45736)
		(stroke
			(width 0.05715)
			(type default)
		)
		(layer "In7.Cu")
	)
	(gr_line
		(start 47.195994 -47.45736)
		(end 47.538894 -47.45736)
		(stroke
			(width 0.05715)
			(type default)
		)
		(layer "In7.Cu")
	)
	(gr_line
		(start 47.315374 -46.9138)
		(end 47.419514 -46.9138)
		(stroke
			(width 0.05715)
			(type default)
		)
		(layer "In7.Cu")
	)
	(gr_line
		(start 47.538894 -47.45736)
		(end 47.749714 -47.24654)
		(stroke
			(width 0.05715)
			(type default)
		)
		(layer "In7.Cu")
	)
	(gr_line
		(start 49.4538 -13.8176)
		(end 49.599596 -13.963396)
		(stroke
			(width 0.05715)
			(type default)
		)
		(layer "In7.Cu")
	)
	(gr_line
		(start 50.070004 -13.963396)
		(end 50.2158 -13.8176)
		(stroke
			(width 0.05715)
			(type default)
		)
		(layer "In7.Cu")
	)
	(gr_line
		(start 50.20945 -51.25466)
		(end 50.42027 -51.04384)
		(stroke
			(width 0.05715)
			(type default)
		)
		(layer "In7.Cu")
	)
	(gr_line
		(start 50.42027 -51.04384)
		(end 50.76317 -51.04384)
		(stroke
			(width 0.05715)
			(type default)
		)
		(layer "In7.Cu")
	)
	(gr_line
		(start 50.53965 -51.5874)
		(end 50.64379 -51.5874)
		(stroke
			(width 0.05715)
			(type default)
		)
		(layer "In7.Cu")
	)
	(gr_line
		(start 50.76317 -51.04384)
		(end 50.97399 -51.25466)
		(stroke
			(width 0.05715)
			(type default)
		)
		(layer "In7.Cu")
	)
	(gr_line
		(start 51.180746 -45.46346)
		(end 51.391566 -45.25264)
		(stroke
			(width 0.05715)
			(type default)
		)
		(layer "In7.Cu")
	)
	(gr_line
		(start 51.32197 -51.25466)
		(end 51.53279 -51.04384)
		(stroke
			(width 0.05715)
			(type default)
		)
		(layer "In7.Cu")
	)
	(gr_line
		(start 51.391566 -45.25264)
		(end 51.734466 -45.25264)
		(stroke
			(width 0.05715)
			(type default)
		)
		(layer "In7.Cu")
	)
	(gr_line
		(start 51.510946 -45.7962)
		(end 51.615086 -45.7962)
		(stroke
			(width 0.05715)
			(type default)
		)
		(layer "In7.Cu")
	)
	(gr_line
		(start 51.53279 -51.04384)
		(end 51.87569 -51.04384)
		(stroke
			(width 0.05715)
			(type default)
		)
		(layer "In7.Cu")
	)
	(gr_line
		(start 51.65217 -51.5874)
		(end 51.75631 -51.5874)
		(stroke
			(width 0.05715)
			(type default)
		)
		(layer "In7.Cu")
	)
	(gr_line
		(start 51.734466 -45.25264)
		(end 51.945286 -45.46346)
		(stroke
			(width 0.05715)
			(type default)
		)
		(layer "In7.Cu")
	)
	(gr_line
		(start 51.87569 -51.04384)
		(end 52.08651 -51.25466)
		(stroke
			(width 0.05715)
			(type default)
		)
		(layer "In7.Cu")
	)
	(gr_line
		(start 52.1462 -13.9446)
		(end 52.342796 -14.141196)
		(stroke
			(width 0.05715)
			(type default)
		)
		(layer "In7.Cu")
	)
	(gr_line
		(start 52.293266 -45.46346)
		(end 52.504086 -45.25264)
		(stroke
			(width 0.05715)
			(type default)
		)
		(layer "In7.Cu")
	)
	(gr_line
		(start 52.504086 -45.25264)
		(end 52.846986 -45.25264)
		(stroke
			(width 0.05715)
			(type default)
		)
		(layer "In7.Cu")
	)
	(gr_line
		(start 52.623466 -45.7962)
		(end 52.727606 -45.7962)
		(stroke
			(width 0.05715)
			(type default)
		)
		(layer "In7.Cu")
	)
	(gr_line
		(start 52.813204 -14.141196)
		(end 53.0098 -13.9446)
		(stroke
			(width 0.05715)
			(type default)
		)
		(layer "In7.Cu")
	)
	(gr_line
		(start 52.846986 -45.25264)
		(end 53.057806 -45.46346)
		(stroke
			(width 0.05715)
			(type default)
		)
		(layer "In7.Cu")
	)
	(gr_line
		(start 53.151786 -29.82722)
		(end 53.381148 -29.597858)
		(stroke
			(width 0.05715)
			(type default)
		)
		(layer "In7.Cu")
	)
	(gr_line
		(start 53.151786 -28.897834)
		(end 53.381148 -29.127196)
		(stroke
			(width 0.05715)
			(type default)
		)
		(layer "In7.Cu")
	)
	(gr_line
		(start 53.191918 -44.52874)
		(end 53.402738 -44.73956)
		(stroke
			(width 0.05715)
			(type default)
		)
		(layer "In7.Cu")
	)
	(gr_line
		(start 53.402738 -44.73956)
		(end 53.745638 -44.73956)
		(stroke
			(width 0.05715)
			(type default)
		)
		(layer "In7.Cu")
	)
	(gr_line
		(start 53.522118 -44.196)
		(end 53.626258 -44.196)
		(stroke
			(width 0.05715)
			(type default)
		)
		(layer "In7.Cu")
	)
	(gr_line
		(start 53.745638 -44.73956)
		(end 53.956458 -44.52874)
		(stroke
			(width 0.05715)
			(type default)
		)
		(layer "In7.Cu")
	)
	(gr_line
		(start 54.304438 -44.52874)
		(end 54.515258 -44.73956)
		(stroke
			(width 0.05715)
			(type default)
		)
		(layer "In7.Cu")
	)
	(gr_line
		(start 54.515258 -44.73956)
		(end 54.858158 -44.73956)
		(stroke
			(width 0.05715)
			(type default)
		)
		(layer "In7.Cu")
	)
	(gr_line
		(start 54.634638 -44.196)
		(end 54.738778 -44.196)
		(stroke
			(width 0.05715)
			(type default)
		)
		(layer "In7.Cu")
	)
	(gr_line
		(start 54.858158 -44.73956)
		(end 55.068978 -44.52874)
		(stroke
			(width 0.05715)
			(type default)
		)
		(layer "In7.Cu")
	)
	(gr_line
		(start 55.416958 -44.52874)
		(end 55.627778 -44.73956)
		(stroke
			(width 0.05715)
			(type default)
		)
		(layer "In7.Cu")
	)
	(gr_line
		(start 55.627778 -44.73956)
		(end 55.970678 -44.73956)
		(stroke
			(width 0.05715)
			(type default)
		)
		(layer "In7.Cu")
	)
	(gr_line
		(start 55.747158 -44.196)
		(end 55.851298 -44.196)
		(stroke
			(width 0.05715)
			(type default)
		)
		(layer "In7.Cu")
	)
	(gr_line
		(start 55.970678 -44.73956)
		(end 56.181498 -44.52874)
		(stroke
			(width 0.05715)
			(type default)
		)
		(layer "In7.Cu")
	)
	(gr_line
		(start 60.9346 -45.8724)
		(end 61.15812 -46.09592)
		(stroke
			(width 0.05715)
			(type default)
		)
		(layer "In7.Cu")
	)
	(gr_line
		(start 60.990226 -46.734222)
		(end 61.15812 -46.566328)
		(stroke
			(width 0.05715)
			(type default)
		)
		(layer "In7.Cu")
	)
	(gr_line
		(start 61.520832 -54.79161)
		(end 61.731652 -54.58079)
		(stroke
			(width 0.05715)
			(type default)
		)
		(layer "In7.Cu")
	)
	(gr_line
		(start 61.679836 -57.10301)
		(end 61.890656 -56.89219)
		(stroke
			(width 0.05715)
			(type default)
		)
		(layer "In7.Cu")
	)
	(gr_line
		(start 61.731652 -54.58079)
		(end 62.074552 -54.58079)
		(stroke
			(width 0.05715)
			(type default)
		)
		(layer "In7.Cu")
	)
	(gr_line
		(start 61.851032 -55.12435)
		(end 61.955172 -55.12435)
		(stroke
			(width 0.05715)
			(type default)
		)
		(layer "In7.Cu")
	)
	(gr_line
		(start 61.890656 -56.89219)
		(end 62.233556 -56.89219)
		(stroke
			(width 0.05715)
			(type default)
		)
		(layer "In7.Cu")
	)
	(gr_line
		(start 62.010036 -57.43575)
		(end 62.114176 -57.43575)
		(stroke
			(width 0.05715)
			(type default)
		)
		(layer "In7.Cu")
	)
	(gr_line
		(start 62.074552 -54.58079)
		(end 62.285372 -54.79161)
		(stroke
			(width 0.05715)
			(type default)
		)
		(layer "In7.Cu")
	)
	(gr_line
		(start 62.233556 -56.89219)
		(end 62.444376 -57.10301)
		(stroke
			(width 0.05715)
			(type default)
		)
		(layer "In7.Cu")
	)
	(gr_line
		(start 62.792356 -57.10301)
		(end 63.003176 -56.89219)
		(stroke
			(width 0.05715)
			(type default)
		)
		(layer "In7.Cu")
	)
	(gr_line
		(start 62.884304 -47.01921)
		(end 63.095124 -46.80839)
		(stroke
			(width 0.05715)
			(type default)
		)
		(layer "In7.Cu")
	)
	(gr_line
		(start 63.003176 -56.89219)
		(end 63.346076 -56.89219)
		(stroke
			(width 0.05715)
			(type default)
		)
		(layer "In7.Cu")
	)
	(gr_line
		(start 63.095124 -46.80839)
		(end 63.438024 -46.80839)
		(stroke
			(width 0.05715)
			(type default)
		)
		(layer "In7.Cu")
	)
	(gr_line
		(start 63.122556 -57.43575)
		(end 63.226696 -57.43575)
		(stroke
			(width 0.05715)
			(type default)
		)
		(layer "In7.Cu")
	)
	(gr_line
		(start 63.214504 -47.35195)
		(end 63.318644 -47.35195)
		(stroke
			(width 0.05715)
			(type default)
		)
		(layer "In7.Cu")
	)
	(gr_line
		(start 63.346076 -56.89219)
		(end 63.556896 -57.10301)
		(stroke
			(width 0.05715)
			(type default)
		)
		(layer "In7.Cu")
	)
	(gr_line
		(start 63.438024 -46.80839)
		(end 63.648844 -47.01921)
		(stroke
			(width 0.05715)
			(type default)
		)
		(layer "In7.Cu")
	)
	(gr_line
		(start 63.627 -14.7066)
		(end 63.772796 -14.852396)
		(stroke
			(width 0.05715)
			(type default)
		)
		(layer "In7.Cu")
	)
	(gr_line
		(start 64.243204 -14.852396)
		(end 64.389 -14.7066)
		(stroke
			(width 0.05715)
			(type default)
		)
		(layer "In7.Cu")
	)
	(gr_line
		(start 64.430148 -17.079976)
		(end 64.503554 -17.153382)
		(stroke
			(width 0.05715)
			(type default)
		)
		(layer "In7.Cu")
	)
	(gr_line
		(start 64.431926 -16.611092)
		(end 64.730122 -16.611092)
		(stroke
			(width 0.05715)
			(type default)
		)
		(layer "In7.Cu")
	)
	(gr_line
		(start 64.730122 -16.611092)
		(end 64.972438 -16.853408)
		(stroke
			(width 0.05715)
			(type default)
		)
		(layer "In7.Cu")
	)
	(gr_line
		(start 64.972438 -16.853408)
		(end 64.972438 -17.151604)
		(stroke
			(width 0.05715)
			(type default)
		)
		(layer "In7.Cu")
	)
	(gr_line
		(start 65.458086 -57.10301)
		(end 65.668906 -56.89219)
		(stroke
			(width 0.05715)
			(type default)
		)
		(layer "In7.Cu")
	)
	(gr_line
		(start 65.668906 -56.89219)
		(end 66.011806 -56.89219)
		(stroke
			(width 0.05715)
			(type default)
		)
		(layer "In7.Cu")
	)
	(gr_line
		(start 65.786 -14.6812)
		(end 65.931796 -14.826996)
		(stroke
			(width 0.05715)
			(type default)
		)
		(layer "In7.Cu")
	)
	(gr_line
		(start 65.788286 -57.43575)
		(end 65.892426 -57.43575)
		(stroke
			(width 0.05715)
			(type default)
		)
		(layer "In7.Cu")
	)
	(gr_line
		(start 66.011806 -56.89219)
		(end 66.222626 -57.10301)
		(stroke
			(width 0.05715)
			(type default)
		)
		(layer "In7.Cu")
	)
	(gr_line
		(start 66.402204 -14.826996)
		(end 66.548 -14.6812)
		(stroke
			(width 0.05715)
			(type default)
		)
		(layer "In7.Cu")
	)
	(gr_line
		(start 66.54165 -55.12435)
		(end 66.609722 -55.056278)
		(stroke
			(width 0.05715)
			(type default)
		)
		(layer "In7.Cu")
	)
	(gr_line
		(start 66.570606 -57.10301)
		(end 66.781426 -56.89219)
		(stroke
			(width 0.05715)
			(type default)
		)
		(layer "In7.Cu")
	)
	(gr_line
		(start 66.781426 -56.89219)
		(end 67.124326 -56.89219)
		(stroke
			(width 0.05715)
			(type default)
		)
		(layer "In7.Cu")
	)
	(gr_line
		(start 66.900806 -57.43575)
		(end 67.004946 -57.43575)
		(stroke
			(width 0.05715)
			(type default)
		)
		(layer "In7.Cu")
	)
	(gr_line
		(start 67.124326 -56.89219)
		(end 67.335146 -57.10301)
		(stroke
			(width 0.05715)
			(type default)
		)
		(layer "In7.Cu")
	)
	(gr_line
		(start 67.683126 -57.10301)
		(end 67.893946 -56.89219)
		(stroke
			(width 0.05715)
			(type default)
		)
		(layer "In7.Cu")
	)
	(gr_line
		(start 67.893946 -56.89219)
		(end 68.236846 -56.89219)
		(stroke
			(width 0.05715)
			(type default)
		)
		(layer "In7.Cu")
	)
	(gr_line
		(start 68.013326 -57.43575)
		(end 68.117466 -57.43575)
		(stroke
			(width 0.05715)
			(type default)
		)
		(layer "In7.Cu")
	)
	(gr_line
		(start 68.118482 -53.080412)
		(end 68.186554 -53.01234)
		(stroke
			(width 0.05715)
			(type default)
		)
		(layer "In7.Cu")
	)
	(gr_line
		(start 68.236846 -56.89219)
		(end 68.447666 -57.10301)
		(stroke
			(width 0.05715)
			(type default)
		)
		(layer "In7.Cu")
	)
	(gr_line
		(start 75.987148 -19.736054)
		(end 76.060554 -19.80946)
		(stroke
			(width 0.05715)
			(type default)
		)
		(layer "In7.Cu")
	)
	(gr_line
		(start 75.988926 -19.26717)
		(end 76.287122 -19.26717)
		(stroke
			(width 0.05715)
			(type default)
		)
		(layer "In7.Cu")
	)
	(gr_line
		(start 76.287122 -19.26717)
		(end 76.529438 -19.509486)
		(stroke
			(width 0.05715)
			(type default)
		)
		(layer "In7.Cu")
	)
	(gr_line
		(start 76.529438 -19.509486)
		(end 76.529438 -19.807682)
		(stroke
			(width 0.05715)
			(type default)
		)
		(layer "In7.Cu")
	)
	(gr_line
		(start 76.773786 -20.522692)
		(end 76.847192 -20.596098)
		(stroke
			(width 0.05715)
			(type default)
		)
		(layer "In7.Cu")
	)
	(gr_line
		(start 76.775564 -20.053808)
		(end 77.07376 -20.053808)
		(stroke
			(width 0.05715)
			(type default)
		)
		(layer "In7.Cu")
	)
	(gr_line
		(start 77.07376 -20.053808)
		(end 77.316076 -20.296124)
		(stroke
			(width 0.05715)
			(type default)
		)
		(layer "In7.Cu")
	)
	(gr_line
		(start 77.316076 -20.296124)
		(end 77.316076 -20.59432)
		(stroke
			(width 0.05715)
			(type default)
		)
		(layer "In7.Cu")
	)
	(gr_line
		(start 77.560424 -21.30933)
		(end 77.63383 -21.382736)
		(stroke
			(width 0.05715)
			(type default)
		)
		(layer "In7.Cu")
	)
	(gr_line
		(start 77.562202 -20.840446)
		(end 77.860398 -20.840446)
		(stroke
			(width 0.05715)
			(type default)
		)
		(layer "In7.Cu")
	)
	(gr_line
		(start 77.860398 -20.840446)
		(end 78.102714 -21.082762)
		(stroke
			(width 0.05715)
			(type default)
		)
		(layer "In7.Cu")
	)
	(gr_line
		(start 78.102714 -21.082762)
		(end 78.102714 -21.380958)
		(stroke
			(width 0.05715)
			(type default)
		)
		(layer "In7.Cu")
	)
	(gr_line
		(start 80.22844 -47.36846)
		(end 80.43926 -47.15764)
		(stroke
			(width 0.05715)
			(type default)
		)
		(layer "In7.Cu")
	)
	(gr_line
		(start 80.264 -60.3758)
		(end 80.422496 -60.217304)
		(stroke
			(width 0.05715)
			(type default)
		)
		(layer "In7.Cu")
	)
	(gr_line
		(start 80.43926 -47.15764)
		(end 80.78216 -47.15764)
		(stroke
			(width 0.05715)
			(type default)
		)
		(layer "In7.Cu")
	)
	(gr_line
		(start 80.55864 -47.7012)
		(end 80.66278 -47.7012)
		(stroke
			(width 0.05715)
			(type default)
		)
		(layer "In7.Cu")
	)
	(gr_line
		(start 80.78216 -47.15764)
		(end 80.99298 -47.36846)
		(stroke
			(width 0.05715)
			(type default)
		)
		(layer "In7.Cu")
	)
	(gr_line
		(start 80.892904 -60.217304)
		(end 81.0514 -60.3758)
		(stroke
			(width 0.05715)
			(type default)
		)
		(layer "In7.Cu")
	)
	(gr_line
		(start 80.931258 -40.04818)
		(end 80.949292 -40.066214)
		(stroke
			(width 0.0508)
			(type default)
		)
		(layer "In7.Cu")
	)
	(gr_line
		(start 80.949292 -40.066214)
		(end 80.949546 -40.066214)
		(stroke
			(width 0.0508)
			(type default)
		)
		(layer "In7.Cu")
	)
	(gr_line
		(start 80.949546 -40.066214)
		(end 80.9498 -40.06596)
		(stroke
			(width 0.0508)
			(type default)
		)
		(layer "In7.Cu")
	)
	(gr_line
		(start 80.9498 -40.06596)
		(end 80.977232 -40.06596)
		(stroke
			(width 0.0508)
			(type default)
		)
		(layer "In7.Cu")
	)
	(gr_line
		(start 80.979772 -40.06596)
		(end 81.0387 -40.06596)
		(stroke
			(width 0.0508)
			(type default)
		)
		(layer "In7.Cu")
	)
	(gr_line
		(start 81.050384 -28.506928)
		(end 81.050384 -28.7782)
		(stroke
			(width 0.05715)
			(type default)
		)
		(layer "In7.Cu")
	)
	(gr_line
		(start 81.164938 -39.814754)
		(end 81.182972 -39.832788)
		(stroke
			(width 0.0508)
			(type default)
		)
		(layer "In7.Cu")
	)
	(gr_line
		(start 81.182972 -39.86276)
		(end 81.182972 -39.922704)
		(stroke
			(width 0.0508)
			(type default)
		)
		(layer "In7.Cu")
	)
	(gr_line
		(start 81.182972 -39.832788)
		(end 81.182972 -39.86022)
		(stroke
			(width 0.0508)
			(type default)
		)
		(layer "In7.Cu")
	)
	(gr_line
		(start 81.507838 -28.49372)
		(end 81.531968 -28.49372)
		(stroke
			(width 0.05715)
			(type default)
		)
		(layer "In7.Cu")
	)
	(gr_line
		(start 82.0928 -51.2064)
		(end 82.1182 -51.2064)
		(stroke
			(width 0.0508)
			(type default)
		)
		(layer "In7.Cu")
	)
	(gr_line
		(start 82.0928 -50.8762)
		(end 82.1182 -50.8762)
		(stroke
			(width 0.0508)
			(type default)
		)
		(layer "In7.Cu")
	)
	(gr_line
		(start 82.1182 -51.2064)
		(end 82.137758 -51.186842)
		(stroke
			(width 0.0508)
			(type default)
		)
		(layer "In7.Cu")
	)
	(gr_line
		(start 82.1182 -50.8762)
		(end 82.137758 -50.895758)
		(stroke
			(width 0.0508)
			(type default)
		)
		(layer "In7.Cu")
	)
	(gr_line
		(start 82.139536 -51.185064)
		(end 82.1817 -51.1429)
		(stroke
			(width 0.0508)
			(type default)
		)
		(layer "In7.Cu")
	)
	(gr_line
		(start 82.139536 -50.897536)
		(end 82.1817 -50.9397)
		(stroke
			(width 0.0508)
			(type default)
		)
		(layer "In7.Cu")
	)
	(gr_line
		(start 82.3849 -47.2694)
		(end 82.478118 -47.2694)
		(stroke
			(width 0.0508)
			(type default)
		)
		(layer "In7.Cu")
	)
	(gr_line
		(start 82.3849 -46.9392)
		(end 82.487262 -46.9392)
		(stroke
			(width 0.0508)
			(type default)
		)
		(layer "In7.Cu")
	)
	(gr_line
		(start 82.478118 -47.2694)
		(end 82.502248 -47.24527)
		(stroke
			(width 0.0508)
			(type default)
		)
		(layer "In7.Cu")
	)
	(gr_line
		(start 82.487262 -46.9392)
		(end 82.502248 -46.954186)
		(stroke
			(width 0.0508)
			(type default)
		)
		(layer "In7.Cu")
	)
	(gr_line
		(start 82.504026 -47.243492)
		(end 82.541618 -47.2059)
		(stroke
			(width 0.0508)
			(type default)
		)
		(layer "In7.Cu")
	)
	(gr_line
		(start 82.504026 -46.955964)
		(end 82.550762 -47.0027)
		(stroke
			(width 0.0508)
			(type default)
		)
		(layer "In7.Cu")
	)
	(gr_line
		(start 82.83575 -52.45735)
		(end 82.86115 -52.45735)
		(stroke
			(width 0.0508)
			(type default)
		)
		(layer "In7.Cu")
	)
	(gr_line
		(start 82.83575 -52.12715)
		(end 82.86115 -52.12715)
		(stroke
			(width 0.0508)
			(type default)
		)
		(layer "In7.Cu")
	)
	(gr_line
		(start 82.86115 -52.45735)
		(end 82.880708 -52.437792)
		(stroke
			(width 0.0508)
			(type default)
		)
		(layer "In7.Cu")
	)
	(gr_line
		(start 82.86115 -52.12715)
		(end 82.880708 -52.146708)
		(stroke
			(width 0.0508)
			(type default)
		)
		(layer "In7.Cu")
	)
	(gr_line
		(start 82.882486 -52.436014)
		(end 82.92465 -52.39385)
		(stroke
			(width 0.0508)
			(type default)
		)
		(layer "In7.Cu")
	)
	(gr_line
		(start 82.882486 -52.148486)
		(end 82.92465 -52.19065)
		(stroke
			(width 0.0508)
			(type default)
		)
		(layer "In7.Cu")
	)
	(gr_line
		(start 83.001358 -55.823358)
		(end 83.064096 -55.886096)
		(stroke
			(width 0.05715)
			(type default)
		)
		(layer "In7.Cu")
	)
	(gr_line
		(start 83.331558 -55.490618)
		(end 83.404202 -55.490618)
		(stroke
			(width 0.05715)
			(type default)
		)
		(layer "In7.Cu")
	)
	(gr_line
		(start 83.404202 -55.490618)
		(end 83.44154 -55.45328)
		(stroke
			(width 0.05715)
			(type default)
		)
		(layer "In7.Cu")
	)
	(gr_line
		(start 83.55203 -59.681872)
		(end 83.55203 -59.904884)
		(stroke
			(width 0.05715)
			(type default)
		)
		(layer "In7.Cu")
	)
	(gr_line
		(start 83.55203 -59.57443)
		(end 83.55203 -59.679332)
		(stroke
			(width 0.05715)
			(type default)
		)
		(layer "In7.Cu")
	)
	(gr_line
		(start 83.793838 -59.349132)
		(end 83.88223 -59.349132)
		(stroke
			(width 0.05715)
			(type default)
		)
		(layer "In7.Cu")
	)
	(gr_line
		(start 83.817968 -52.34686)
		(end 83.914488 -52.25034)
		(stroke
			(width 0.0508)
			(type default)
		)
		(layer "In7.Cu")
	)
	(gr_line
		(start 83.88477 -59.349132)
		(end 84.110068 -59.349132)
		(stroke
			(width 0.05715)
			(type default)
		)
		(layer "In7.Cu")
	)
	(gr_line
		(start 83.914488 -52.25034)
		(end 84.219288 -52.25034)
		(stroke
			(width 0.0508)
			(type default)
		)
		(layer "In7.Cu")
	)
	(gr_line
		(start 84.021168 -52.5526)
		(end 84.112608 -52.5526)
		(stroke
			(width 0.0508)
			(type default)
		)
		(layer "In7.Cu")
	)
	(gr_line
		(start 84.219288 -52.25034)
		(end 84.315808 -52.34686)
		(stroke
			(width 0.0508)
			(type default)
		)
		(layer "In7.Cu")
	)
	(gr_line
		(start 84.534248 -26.935684)
		(end 84.692236 -27.093672)
		(stroke
			(width 0.05715)
			(type default)
		)
		(layer "In7.Cu")
	)
	(gr_line
		(start 84.534248 -26.465276)
		(end 84.661502 -26.338022)
		(stroke
			(width 0.05715)
			(type default)
		)
		(layer "In7.Cu")
	)
	(gr_line
		(start 84.625688 -52.34686)
		(end 84.722208 -52.25034)
		(stroke
			(width 0.0508)
			(type default)
		)
		(layer "In7.Cu")
	)
	(gr_line
		(start 84.722208 -52.25034)
		(end 85.027008 -52.25034)
		(stroke
			(width 0.0508)
			(type default)
		)
		(layer "In7.Cu")
	)
	(gr_line
		(start 84.828888 -52.5526)
		(end 84.920328 -52.5526)
		(stroke
			(width 0.0508)
			(type default)
		)
		(layer "In7.Cu")
	)
	(gr_line
		(start 85.027008 -52.25034)
		(end 85.123528 -52.34686)
		(stroke
			(width 0.0508)
			(type default)
		)
		(layer "In7.Cu")
	)
	(gr_line
		(start 85.489796 -24.264112)
		(end 85.5345 -24.308816)
		(stroke
			(width 0.05715)
			(type default)
		)
		(layer "In7.Cu")
	)
	(gr_line
		(start 85.489796 -23.793704)
		(end 85.5345 -23.749)
		(stroke
			(width 0.05715)
			(type default)
		)
		(layer "In7.Cu")
	)
	(gr_line
		(start 85.585554 -42.786554)
		(end 85.65007 -42.85107)
		(stroke
			(width 0.0508)
			(type default)
		)
		(layer "In7.Cu")
	)
	(gr_line
		(start 85.587332 -42.497248)
		(end 85.72373 -42.497248)
		(stroke
			(width 0.0508)
			(type default)
		)
		(layer "In7.Cu")
	)
	(gr_line
		(start 85.72373 -42.497248)
		(end 85.939376 -42.71264)
		(stroke
			(width 0.0508)
			(type default)
		)
		(layer "In7.Cu")
	)
	(gr_line
		(start 85.939376 -42.71264)
		(end 85.939376 -42.849292)
		(stroke
			(width 0.0508)
			(type default)
		)
		(layer "In7.Cu")
	)
	(gr_line
		(start 86.23554 -52.09286)
		(end 86.33206 -51.99634)
		(stroke
			(width 0.0508)
			(type default)
		)
		(layer "In7.Cu")
	)
	(gr_line
		(start 86.33206 -51.99634)
		(end 86.63686 -51.99634)
		(stroke
			(width 0.0508)
			(type default)
		)
		(layer "In7.Cu")
	)
	(gr_line
		(start 86.43874 -52.2986)
		(end 86.53018 -52.2986)
		(stroke
			(width 0.0508)
			(type default)
		)
		(layer "In7.Cu")
	)
	(gr_line
		(start 86.63686 -51.99634)
		(end 86.73338 -52.09286)
		(stroke
			(width 0.0508)
			(type default)
		)
		(layer "In7.Cu")
	)
	(gr_line
		(start 86.728046 -46.9646)
		(end 86.77021 -47.006764)
		(stroke
			(width 0.0508)
			(type default)
		)
		(layer "In7.Cu")
	)
	(gr_line
		(start 86.728046 -46.7614)
		(end 86.77021 -46.719236)
		(stroke
			(width 0.0508)
			(type default)
		)
		(layer "In7.Cu")
	)
	(gr_line
		(start 86.771988 -47.008542)
		(end 86.915752 -47.152306)
		(stroke
			(width 0.0508)
			(type default)
		)
		(layer "In7.Cu")
	)
	(gr_line
		(start 86.771988 -46.717458)
		(end 86.915752 -46.573694)
		(stroke
			(width 0.0508)
			(type default)
		)
		(layer "In7.Cu")
	)
	(gr_line
		(start 86.915752 -47.152306)
		(end 86.927182 -47.152306)
		(stroke
			(width 0.0508)
			(type default)
		)
		(layer "In7.Cu")
	)
	(gr_line
		(start 86.967568 -44.649898)
		(end 86.967568 -44.741338)
		(stroke
			(width 0.0508)
			(type default)
		)
		(layer "In7.Cu")
	)
	(gr_line
		(start 86.9696 -55.6768)
		(end 86.995 -55.6768)
		(stroke
			(width 0.0508)
			(type default)
		)
		(layer "In7.Cu")
	)
	(gr_line
		(start 86.9696 -55.3466)
		(end 86.995 -55.3466)
		(stroke
			(width 0.0508)
			(type default)
		)
		(layer "In7.Cu")
	)
	(gr_line
		(start 86.995 -55.6768)
		(end 87.014558 -55.657242)
		(stroke
			(width 0.0508)
			(type default)
		)
		(layer "In7.Cu")
	)
	(gr_line
		(start 86.995 -55.3466)
		(end 87.014558 -55.366158)
		(stroke
			(width 0.0508)
			(type default)
		)
		(layer "In7.Cu")
	)
	(gr_line
		(start 87.016336 -55.655464)
		(end 87.0585 -55.6133)
		(stroke
			(width 0.0508)
			(type default)
		)
		(layer "In7.Cu")
	)
	(gr_line
		(start 87.016336 -55.367936)
		(end 87.0585 -55.4101)
		(stroke
			(width 0.0508)
			(type default)
		)
		(layer "In7.Cu")
	)
	(gr_line
		(start 87.04326 -52.09286)
		(end 87.13978 -51.99634)
		(stroke
			(width 0.0508)
			(type default)
		)
		(layer "In7.Cu")
	)
	(gr_line
		(start 87.13978 -51.99634)
		(end 87.44458 -51.99634)
		(stroke
			(width 0.0508)
			(type default)
		)
		(layer "In7.Cu")
	)
	(gr_line
		(start 87.173308 -44.944538)
		(end 87.269828 -44.848018)
		(stroke
			(width 0.0508)
			(type default)
		)
		(layer "In7.Cu")
	)
	(gr_line
		(start 87.173308 -44.446698)
		(end 87.269828 -44.543218)
		(stroke
			(width 0.0508)
			(type default)
		)
		(layer "In7.Cu")
	)
	(gr_line
		(start 87.24646 -52.2986)
		(end 87.3379 -52.2986)
		(stroke
			(width 0.0508)
			(type default)
		)
		(layer "In7.Cu")
	)
	(gr_line
		(start 87.269828 -44.543218)
		(end 87.269828 -44.848018)
		(stroke
			(width 0.0508)
			(type default)
		)
		(layer "In7.Cu")
	)
	(gr_line
		(start 87.338154 -47.15256)
		(end 87.790274 -47.60468)
		(stroke
			(width 0.0508)
			(type default)
		)
		(layer "In7.Cu")
	)
	(gr_line
		(start 87.338154 -46.853094)
		(end 87.338154 -47.15256)
		(stroke
			(width 0.0508)
			(type default)
		)
		(layer "In7.Cu")
	)
	(gr_line
		(start 87.44458 -51.99634)
		(end 87.5411 -52.09286)
		(stroke
			(width 0.0508)
			(type default)
		)
		(layer "In7.Cu")
	)
	(gr_line
		(start 87.543894 -46.649894)
		(end 87.757 -46.863)
		(stroke
			(width 0.0508)
			(type default)
		)
		(layer "In7.Cu")
	)
	(gr_line
		(start 87.85098 -52.09286)
		(end 87.9475 -51.99634)
		(stroke
			(width 0.0508)
			(type default)
		)
		(layer "In7.Cu")
	)
	(gr_line
		(start 87.889588 -29.867606)
		(end 88.035384 -30.013402)
		(stroke
			(width 0.05715)
			(type default)
		)
		(layer "In7.Cu")
	)
	(gr_line
		(start 87.889588 -29.397198)
		(end 88.035384 -29.251402)
		(stroke
			(width 0.05715)
			(type default)
		)
		(layer "In7.Cu")
	)
	(gr_line
		(start 87.9475 -51.99634)
		(end 88.2523 -51.99634)
		(stroke
			(width 0.0508)
			(type default)
		)
		(layer "In7.Cu")
	)
	(gr_line
		(start 88.05418 -52.2986)
		(end 88.14562 -52.2986)
		(stroke
			(width 0.0508)
			(type default)
		)
		(layer "In7.Cu")
	)
	(gr_line
		(start 88.2523 -51.99634)
		(end 88.34882 -52.09286)
		(stroke
			(width 0.0508)
			(type default)
		)
		(layer "In7.Cu")
	)
	(gr_line
		(start 88.6587 -52.09286)
		(end 88.75522 -51.99634)
		(stroke
			(width 0.0508)
			(type default)
		)
		(layer "In7.Cu")
	)
	(gr_line
		(start 88.75522 -51.99634)
		(end 89.06002 -51.99634)
		(stroke
			(width 0.0508)
			(type default)
		)
		(layer "In7.Cu")
	)
	(gr_line
		(start 88.8619 -52.2986)
		(end 88.95334 -52.2986)
		(stroke
			(width 0.0508)
			(type default)
		)
		(layer "In7.Cu")
	)
	(gr_line
		(start 89.06002 -51.99634)
		(end 89.15654 -52.09286)
		(stroke
			(width 0.0508)
			(type default)
		)
		(layer "In7.Cu")
	)
	(gr_line
		(start 89.5604 -56.0705)
		(end 89.5858 -56.0705)
		(stroke
			(width 0.0508)
			(type default)
		)
		(layer "In7.Cu")
	)
	(gr_line
		(start 89.5604 -55.7403)
		(end 89.5858 -55.7403)
		(stroke
			(width 0.0508)
			(type default)
		)
		(layer "In7.Cu")
	)
	(gr_line
		(start 89.5858 -56.0705)
		(end 89.605358 -56.050942)
		(stroke
			(width 0.0508)
			(type default)
		)
		(layer "In7.Cu")
	)
	(gr_line
		(start 89.5858 -55.7403)
		(end 89.605358 -55.759858)
		(stroke
			(width 0.0508)
			(type default)
		)
		(layer "In7.Cu")
	)
	(gr_line
		(start 89.607136 -56.049164)
		(end 89.6493 -56.007)
		(stroke
			(width 0.0508)
			(type default)
		)
		(layer "In7.Cu")
	)
	(gr_line
		(start 89.607136 -55.761636)
		(end 89.6493 -55.8038)
		(stroke
			(width 0.0508)
			(type default)
		)
		(layer "In7.Cu")
	)
	(gr_line
		(start 90.860372 -53.594)
		(end 90.907108 -53.547264)
		(stroke
			(width 0.0508)
			(type default)
		)
		(layer "In7.Cu")
	)
	(gr_line
		(start 90.86977 -53.7972)
		(end 90.907108 -53.834538)
		(stroke
			(width 0.0508)
			(type default)
		)
		(layer "In7.Cu")
	)
	(gr_line
		(start 90.908886 -53.836316)
		(end 91.029028 -53.956458)
		(stroke
			(width 0.0508)
			(type default)
		)
		(layer "In7.Cu")
	)
	(gr_line
		(start 90.908886 -53.545486)
		(end 91.058492 -53.39588)
		(stroke
			(width 0.0508)
			(type default)
		)
		(layer "In7.Cu")
	)
	(gr_line
		(start 91.390978 -48.8061)
		(end 91.390978 -49.114456)
		(stroke
			(width 0.0508)
			(type default)
		)
		(layer "In7.Cu")
	)
	(gr_line
		(start 91.390978 -48.8061)
		(end 91.759278 -48.4378)
		(stroke
			(width 0.0508)
			(type default)
		)
		(layer "In7.Cu")
	)
	(gr_line
		(start 91.596718 -49.317656)
		(end 91.759278 -49.155096)
		(stroke
			(width 0.0508)
			(type default)
		)
		(layer "In7.Cu")
	)
	(gr_line
		(start 91.7448 -24.765)
		(end 92.1766 -24.3332)
		(stroke
			(width 0.0508)
			(type default)
		)
		(layer "In7.Cu")
	)
	(gr_line
		(start 91.7448 -22.9108)
		(end 91.97086 -22.68474)
		(stroke
			(width 0.0508)
			(type default)
		)
		(layer "In7.Cu")
	)
	(gr_line
		(start 91.751658 -57.7723)
		(end 91.751658 -57.785)
		(stroke
			(width 0.0508)
			(type default)
		)
		(layer "In7.Cu")
	)
	(gr_line
		(start 91.751658 -57.7723)
		(end 91.771216 -57.752742)
		(stroke
			(width 0.0508)
			(type default)
		)
		(layer "In7.Cu")
	)
	(gr_line
		(start 91.772994 -57.750964)
		(end 91.815158 -57.7088)
		(stroke
			(width 0.0508)
			(type default)
		)
		(layer "In7.Cu")
	)
	(gr_line
		(start 91.821 -53.05298)
		(end 91.821 -53.14442)
		(stroke
			(width 0.0508)
			(type default)
		)
		(layer "In7.Cu")
	)
	(gr_line
		(start 91.821 -52.24526)
		(end 91.821 -52.3367)
		(stroke
			(width 0.0508)
			(type default)
		)
		(layer "In7.Cu")
	)
	(gr_line
		(start 92.018358 -57.7088)
		(end 92.060522 -57.750964)
		(stroke
			(width 0.0508)
			(type default)
		)
		(layer "In7.Cu")
	)
	(gr_line
		(start 92.02674 -53.34762)
		(end 92.12326 -53.2511)
		(stroke
			(width 0.0508)
			(type default)
		)
		(layer "In7.Cu")
	)
	(gr_line
		(start 92.02674 -52.84978)
		(end 92.12326 -52.9463)
		(stroke
			(width 0.0508)
			(type default)
		)
		(layer "In7.Cu")
	)
	(gr_line
		(start 92.02674 -52.5399)
		(end 92.12326 -52.44338)
		(stroke
			(width 0.0508)
			(type default)
		)
		(layer "In7.Cu")
	)
	(gr_line
		(start 92.02674 -52.04206)
		(end 92.12326 -52.13858)
		(stroke
			(width 0.0508)
			(type default)
		)
		(layer "In7.Cu")
	)
	(gr_line
		(start 92.0623 -57.752742)
		(end 92.081858 -57.7723)
		(stroke
			(width 0.0508)
			(type default)
		)
		(layer "In7.Cu")
	)
	(gr_line
		(start 92.081858 -57.7723)
		(end 92.081858 -57.785)
		(stroke
			(width 0.0508)
			(type default)
		)
		(layer "In7.Cu")
	)
	(gr_line
		(start 92.12326 -52.9463)
		(end 92.12326 -53.2511)
		(stroke
			(width 0.0508)
			(type default)
		)
		(layer "In7.Cu")
	)
	(gr_line
		(start 92.12326 -52.13858)
		(end 92.12326 -52.44338)
		(stroke
			(width 0.0508)
			(type default)
		)
		(layer "In7.Cu")
	)
	(gr_line
		(start 92.1766 -22.88794)
		(end 92.1766 -24.3332)
		(stroke
			(width 0.0508)
			(type default)
		)
		(layer "In7.Cu")
	)
	(gr_line
		(start 92.43187 -48.744886)
		(end 92.677742 -48.499014)
		(stroke
			(width 0.0508)
			(type default)
		)
		(layer "In7.Cu")
	)
	(gr_line
		(start 92.433648 -49.034192)
		(end 92.672916 -49.034192)
		(stroke
			(width 0.0508)
			(type default)
		)
		(layer "In7.Cu")
	)
	(gr_line
		(start 92.672916 -49.034192)
		(end 92.696538 -49.057814)
		(stroke
			(width 0.0508)
			(type default)
		)
		(layer "In7.Cu")
	)
	(gr_line
		(start 92.677742 -48.499014)
		(end 92.68333 -48.499014)
		(stroke
			(width 0.0508)
			(type default)
		)
		(layer "In7.Cu")
	)
	(gr_line
		(start 93.489526 -48.479964)
		(end 93.552518 -48.542956)
		(stroke
			(width 0.0508)
			(type default)
		)
		(layer "In7.Cu")
	)
	(gr_line
		(start 93.531436 -48.276764)
		(end 93.552518 -48.255682)
		(stroke
			(width 0.0508)
			(type default)
		)
		(layer "In7.Cu")
	)
	(gr_line
		(start 93.554296 -48.544734)
		(end 93.752924 -48.743362)
		(stroke
			(width 0.0508)
			(type default)
		)
		(layer "In7.Cu")
	)
	(gr_line
		(start 93.554296 -48.253904)
		(end 93.7768 -48.0314)
		(stroke
			(width 0.0508)
			(type default)
		)
		(layer "In7.Cu")
	)
	(gr_line
		(start 93.646244 -20.2184)
		(end 93.730064 -20.2184)
		(stroke
			(width 0.0508)
			(type default)
		)
		(layer "In7.Cu")
	)
	(gr_line
		(start 93.814646 -20.015454)
		(end 93.933264 -20.015454)
		(stroke
			(width 0.0508)
			(type default)
		)
		(layer "In7.Cu")
	)
	(gr_line
		(start 94.607888 -48.737012)
		(end 94.607888 -49.007522)
		(stroke
			(width 0.0508)
			(type default)
		)
		(layer "In7.Cu")
	)
	(gr_line
		(start 94.607888 -48.737012)
		(end 94.996 -48.3489)
		(stroke
			(width 0.0508)
			(type default)
		)
		(layer "In7.Cu")
	)
	(gr_line
		(start 94.678246 -51.67503)
		(end 94.678246 -51.76647)
		(stroke
			(width 0.0508)
			(type default)
		)
		(layer "In7.Cu")
	)
	(gr_line
		(start 94.678246 -50.86731)
		(end 94.678246 -50.95875)
		(stroke
			(width 0.0508)
			(type default)
		)
		(layer "In7.Cu")
	)
	(gr_line
		(start 94.678246 -50.05959)
		(end 94.678246 -50.15103)
		(stroke
			(width 0.0508)
			(type default)
		)
		(layer "In7.Cu")
	)
	(gr_line
		(start 94.678246 -49.633378)
		(end 94.678246 -49.681892)
		(stroke
			(width 0.0508)
			(type default)
		)
		(layer "In7.Cu")
	)
	(gr_line
		(start 94.811088 -49.430178)
		(end 94.811088 -49.478692)
		(stroke
			(width 0.0508)
			(type default)
		)
		(layer "In7.Cu")
	)
	(gr_line
		(start 94.813628 -49.210722)
		(end 94.831154 -49.192688)
		(stroke
			(width 0.0508)
			(type default)
		)
		(layer "In7.Cu")
	)
	(gr_line
		(start 94.831154 -49.192688)
		(end 94.843092 -49.181004)
		(stroke
			(width 0.0508)
			(type default)
		)
		(layer "In7.Cu")
	)
	(gr_line
		(start 94.834202 -20.012914)
		(end 94.902528 -19.944588)
		(stroke
			(width 0.0508)
			(type default)
		)
		(layer "In7.Cu")
	)
	(gr_line
		(start 94.843092 -49.181004)
		(end 94.976188 -49.048162)
		(stroke
			(width 0.0508)
			(type default)
		)
		(layer "In7.Cu")
	)
	(gr_line
		(start 94.883986 -51.96967)
		(end 94.980506 -51.87315)
		(stroke
			(width 0.0508)
			(type default)
		)
		(layer "In7.Cu")
	)
	(gr_line
		(start 94.883986 -51.47183)
		(end 94.980506 -51.56835)
		(stroke
			(width 0.0508)
			(type default)
		)
		(layer "In7.Cu")
	)
	(gr_line
		(start 94.883986 -51.16195)
		(end 94.980506 -51.06543)
		(stroke
			(width 0.0508)
			(type default)
		)
		(layer "In7.Cu")
	)
	(gr_line
		(start 94.883986 -50.66411)
		(end 94.980506 -50.76063)
		(stroke
			(width 0.0508)
			(type default)
		)
		(layer "In7.Cu")
	)
	(gr_line
		(start 94.883986 -50.35423)
		(end 94.980506 -50.25771)
		(stroke
			(width 0.0508)
			(type default)
		)
		(layer "In7.Cu")
	)
	(gr_line
		(start 94.883986 -49.85639)
		(end 94.980506 -49.95291)
		(stroke
			(width 0.0508)
			(type default)
		)
		(layer "In7.Cu")
	)
	(gr_line
		(start 94.980506 -51.56835)
		(end 94.980506 -51.87315)
		(stroke
			(width 0.0508)
			(type default)
		)
		(layer "In7.Cu")
	)
	(gr_line
		(start 94.980506 -50.76063)
		(end 94.980506 -51.06543)
		(stroke
			(width 0.0508)
			(type default)
		)
		(layer "In7.Cu")
	)
	(gr_line
		(start 94.980506 -49.95291)
		(end 94.980506 -50.25771)
		(stroke
			(width 0.0508)
			(type default)
		)
		(layer "In7.Cu")
	)
	(gr_line
		(start 94.987618 -20.218654)
		(end 95.02394 -20.2184)
		(stroke
			(width 0.0508)
			(type default)
		)
		(layer "In7.Cu")
	)
	(gr_line
		(start 95.02394 -20.2184)
		(end 95.10014 -20.1422)
		(stroke
			(width 0.0508)
			(type default)
		)
		(layer "In7.Cu")
	)
	(gr_line
		(start 95.1484 -54.0258)
		(end 95.1484 -54.78526)
		(stroke
			(width 0.0762)
			(type default)
		)
		(layer "In7.Cu")
	)
	(gr_line
		(start 95.1484 -54.0258)
		(end 95.5802 -53.594)
		(stroke
			(width 0.0762)
			(type default)
		)
		(layer "In7.Cu")
	)
	(gr_line
		(start 95.43034 -55.06466)
		(end 95.5802 -54.9148)
		(stroke
			(width 0.0762)
			(type default)
		)
		(layer "In7.Cu")
	)
	(gr_line
		(start 102.353618 -49.53127)
		(end 102.4636 -49.641252)
		(stroke
			(width 0.0508)
			(type default)
		)
		(layer "In7.Cu")
	)
	(gr_line
		(start 102.367588 -48.969168)
		(end 102.75824 -49.35982)
		(stroke
			(width 0.0508)
			(type default)
		)
		(layer "In7.Cu")
	)
	(gr_line
		(start 102.367588 -48.791876)
		(end 102.367588 -48.969168)
		(stroke
			(width 0.0508)
			(type default)
		)
		(layer "In7.Cu")
	)
	(gr_line
		(start 102.5144 -46.3296)
		(end 102.560374 -46.283626)
		(stroke
			(width 0.0508)
			(type default)
		)
		(layer "In7.Cu")
	)
	(gr_line
		(start 102.5144 -45.7708)
		(end 102.5906 -45.7708)
		(stroke
			(width 0.0508)
			(type default)
		)
		(layer "In7.Cu")
	)
	(gr_line
		(start 102.560374 -46.283626)
		(end 102.694486 -46.283626)
		(stroke
			(width 0.0508)
			(type default)
		)
		(layer "In7.Cu")
	)
	(gr_line
		(start 102.5906 -45.7708)
		(end 102.897686 -46.077886)
		(stroke
			(width 0.0508)
			(type default)
		)
		(layer "In7.Cu")
	)
	(gr_line
		(start 102.66934 -49.8094)
		(end 102.75824 -49.7205)
		(stroke
			(width 0.0508)
			(type default)
		)
		(layer "In7.Cu")
	)
	(gr_line
		(start 102.75824 -49.35982)
		(end 102.75824 -49.7205)
		(stroke
			(width 0.0508)
			(type default)
		)
		(layer "In7.Cu")
	)
	(gr_line
		(start 102.928674 -46.983904)
		(end 102.965504 -46.983904)
		(stroke
			(width 0.0508)
			(type default)
		)
		(layer "In7.Cu")
	)
	(gr_line
		(start 102.965504 -46.983904)
		(end 103.27386 -47.29226)
		(stroke
			(width 0.0508)
			(type default)
		)
		(layer "In7.Cu")
	)
	(gr_line
		(start 103.2256 -49.5046)
		(end 103.270558 -49.549558)
		(stroke
			(width 0.0508)
			(type default)
		)
		(layer "In7.Cu")
	)
	(gr_line
		(start 103.2256 -48.8442)
		(end 103.2256 -49.5046)
		(stroke
			(width 0.0508)
			(type default)
		)
		(layer "In7.Cu")
	)
	(gr_line
		(start 103.2256 -48.8442)
		(end 103.6828 -48.387)
		(stroke
			(width 0.0508)
			(type default)
		)
		(layer "In7.Cu")
	)
	(gr_line
		(start 103.283004 -66.29654)
		(end 103.404924 -66.41846)
		(stroke
			(width 0.0762)
			(type default)
		)
		(layer "In7.Cu")
	)
	(gr_line
		(start 103.404924 -66.41846)
		(end 103.862124 -66.41846)
		(stroke
			(width 0.0762)
			(type default)
		)
		(layer "In7.Cu")
	)
	(gr_line
		(start 103.4796 -47.108364)
		(end 103.693468 -46.894496)
		(stroke
			(width 0.0508)
			(type default)
		)
		(layer "In7.Cu")
	)
	(gr_line
		(start 103.559864 -49.271936)
		(end 103.559864 -49.54778)
		(stroke
			(width 0.0508)
			(type default)
		)
		(layer "In7.Cu")
	)
	(gr_line
		(start 103.559864 -49.271936)
		(end 103.6574 -49.1744)
		(stroke
			(width 0.0508)
			(type default)
		)
		(layer "In7.Cu")
	)
	(gr_line
		(start 103.562404 -66.0146)
		(end 103.704644 -66.0146)
		(stroke
			(width 0.0762)
			(type default)
		)
		(layer "In7.Cu")
	)
	(gr_line
		(start 103.862124 -66.41846)
		(end 103.984044 -66.29654)
		(stroke
			(width 0.0762)
			(type default)
		)
		(layer "In7.Cu")
	)
	(gr_line
		(start 104.446324 -66.29654)
		(end 104.568244 -66.41846)
		(stroke
			(width 0.0762)
			(type default)
		)
		(layer "In7.Cu")
	)
	(gr_line
		(start 104.568244 -66.41846)
		(end 105.025444 -66.41846)
		(stroke
			(width 0.0762)
			(type default)
		)
		(layer "In7.Cu")
	)
	(gr_line
		(start 104.725724 -66.0146)
		(end 104.867964 -66.0146)
		(stroke
			(width 0.0762)
			(type default)
		)
		(layer "In7.Cu")
	)
	(gr_line
		(start 105.025444 -66.41846)
		(end 105.147364 -66.29654)
		(stroke
			(width 0.0762)
			(type default)
		)
		(layer "In7.Cu")
	)
	(gr_line
		(start 105.609644 -66.29654)
		(end 105.731564 -66.41846)
		(stroke
			(width 0.0762)
			(type default)
		)
		(layer "In7.Cu")
	)
	(gr_line
		(start 105.731564 -66.41846)
		(end 106.188764 -66.41846)
		(stroke
			(width 0.0762)
			(type default)
		)
		(layer "In7.Cu")
	)
	(gr_line
		(start 105.889044 -66.0146)
		(end 106.031284 -66.0146)
		(stroke
			(width 0.0762)
			(type default)
		)
		(layer "In7.Cu")
	)
	(gr_line
		(start 106.188764 -66.41846)
		(end 106.310684 -66.29654)
		(stroke
			(width 0.0762)
			(type default)
		)
		(layer "In7.Cu")
	)
	(gr_line
		(start 106.884216 -41.315386)
		(end 107.077002 -41.1226)
		(stroke
			(width 0.0508)
			(type default)
		)
		(layer "In7.Cu")
	)
	(gr_line
		(start 106.9086 -40.649398)
		(end 107.176062 -40.91686)
		(stroke
			(width 0.0508)
			(type default)
		)
		(layer "In7.Cu")
	)
	(gr_line
		(start 106.941366 -54.565296)
		(end 107.0102 -54.63413)
		(stroke
			(width 0.0508)
			(type default)
		)
		(layer "In7.Cu")
	)
	(gr_line
		(start 106.943144 -54.27599)
		(end 107.112816 -54.27599)
		(stroke
			(width 0.0508)
			(type default)
		)
		(layer "In7.Cu")
	)
	(gr_line
		(start 107.0102 -54.63413)
		(end 107.0102 -54.76621)
		(stroke
			(width 0.0508)
			(type default)
		)
		(layer "In7.Cu")
	)
	(gr_line
		(start 107.112816 -54.27599)
		(end 107.116118 -54.279292)
		(stroke
			(width 0.0508)
			(type default)
		)
		(layer "In7.Cu")
	)
	(gr_line
		(start 107.319572 -66.29654)
		(end 107.441492 -66.41846)
		(stroke
			(width 0.0762)
			(type default)
		)
		(layer "In7.Cu")
	)
	(gr_line
		(start 107.441492 -66.41846)
		(end 107.898692 -66.41846)
		(stroke
			(width 0.0762)
			(type default)
		)
		(layer "In7.Cu")
	)
	(gr_line
		(start 107.552236 -53.475636)
		(end 107.678982 -53.602382)
		(stroke
			(width 0.0508)
			(type default)
		)
		(layer "In7.Cu")
	)
	(gr_line
		(start 107.569 -53.8988)
		(end 107.695746 -54.025546)
		(stroke
			(width 0.09525)
			(type default)
		)
		(layer "In7.Cu")
	)
	(gr_line
		(start 107.569 -53.808122)
		(end 107.569 -53.8988)
		(stroke
			(width 0.0508)
			(type default)
		)
		(layer "In7.Cu")
	)
	(gr_line
		(start 107.569 -53.779928)
		(end 107.569 -53.805582)
		(stroke
			(width 0.0508)
			(type default)
		)
		(layer "In7.Cu")
	)
	(gr_line
		(start 107.598972 -66.0146)
		(end 107.741212 -66.0146)
		(stroke
			(width 0.0762)
			(type default)
		)
		(layer "In7.Cu")
	)
	(gr_line
		(start 107.678982 -53.602382)
		(end 107.7722 -53.602382)
		(stroke
			(width 0.0508)
			(type default)
		)
		(layer "In7.Cu")
	)
	(gr_line
		(start 107.77474 -53.602382)
		(end 107.865418 -53.602382)
		(stroke
			(width 0.0508)
			(type default)
		)
		(layer "In7.Cu")
	)
	(gr_line
		(start 107.898692 -66.41846)
		(end 108.020612 -66.29654)
		(stroke
			(width 0.0762)
			(type default)
		)
		(layer "In7.Cu")
	)
	(gr_line
		(start 107.961684 -52.451)
		(end 108.15193 -52.451)
		(stroke
			(width 0.0508)
			(type default)
		)
		(layer "In7.Cu")
	)
	(gr_line
		(start 108.15193 -52.451)
		(end 108.207048 -52.395882)
		(stroke
			(width 0.0508)
			(type default)
		)
		(layer "In7.Cu")
	)
	(gr_line
		(start 108.177838 -52.6542)
		(end 108.207048 -52.68341)
		(stroke
			(width 0.0508)
			(type default)
		)
		(layer "In7.Cu")
	)
	(gr_line
		(start 108.208826 -52.685188)
		(end 108.272834 -52.749196)
		(stroke
			(width 0.0508)
			(type default)
		)
		(layer "In7.Cu")
	)
	(gr_line
		(start 108.208826 -52.394104)
		(end 108.272834 -52.330096)
		(stroke
			(width 0.0508)
			(type default)
		)
		(layer "In7.Cu")
	)
	(gr_line
		(start 108.272834 -52.749196)
		(end 108.46308 -52.749196)
		(stroke
			(width 0.09525)
			(type default)
		)
		(layer "In7.Cu")
	)
	(gr_line
		(start 108.5342 -50.8)
		(end 108.6104 -50.8)
		(stroke
			(width 0.0508)
			(type default)
		)
		(layer "In7.Cu")
	)
	(gr_line
		(start 108.5723 -51.049428)
		(end 108.618528 -51.0032)
		(stroke
			(width 0.0508)
			(type default)
		)
		(layer "In7.Cu")
	)
	(gr_line
		(start 108.6104 -50.8)
		(end 108.683806 -50.726594)
		(stroke
			(width 0.0508)
			(type default)
		)
		(layer "In7.Cu")
	)
	(gr_line
		(start 108.689394 -50.721006)
		(end 108.8263 -50.5841)
		(stroke
			(width 0.0508)
			(type default)
		)
		(layer "In7.Cu")
	)
	(gr_line
		(start 108.81614 -51.0032)
		(end 108.8263 -51.0032)
		(stroke
			(width 0.0508)
			(type default)
		)
		(layer "In7.Cu")
	)
	(gr_line
		(start 108.8263 -51.0032)
		(end 108.92155 -51.0032)
		(stroke
			(width 0.09525)
			(type default)
		)
		(layer "In7.Cu")
	)
	(gr_line
		(start 108.850176 -54.01056)
		(end 109.073696 -53.78704)
		(stroke
			(width 0.09525)
			(type default)
		)
		(layer "In7.Cu")
	)
	(gr_line
		(start 109.073696 -53.78704)
		(end 109.645196 -53.78704)
		(stroke
			(width 0.09525)
			(type default)
		)
		(layer "In7.Cu")
	)
	(gr_line
		(start 109.22635 -66.29654)
		(end 109.34827 -66.41846)
		(stroke
			(width 0.0762)
			(type default)
		)
		(layer "In7.Cu")
	)
	(gr_line
		(start 109.269276 -54.4322)
		(end 109.449616 -54.4322)
		(stroke
			(width 0.09525)
			(type default)
		)
		(layer "In7.Cu")
	)
	(gr_line
		(start 109.34827 -66.41846)
		(end 109.80547 -66.41846)
		(stroke
			(width 0.0762)
			(type default)
		)
		(layer "In7.Cu")
	)
	(gr_line
		(start 109.50575 -66.0146)
		(end 109.64799 -66.0146)
		(stroke
			(width 0.0762)
			(type default)
		)
		(layer "In7.Cu")
	)
	(gr_line
		(start 109.645196 -53.78704)
		(end 109.868716 -54.01056)
		(stroke
			(width 0.09525)
			(type default)
		)
		(layer "In7.Cu")
	)
	(gr_line
		(start 109.80547 -66.41846)
		(end 109.92739 -66.29654)
		(stroke
			(width 0.0762)
			(type default)
		)
		(layer "In7.Cu")
	)
	(gr_line
		(start 110.38967 -66.29654)
		(end 110.51159 -66.41846)
		(stroke
			(width 0.0762)
			(type default)
		)
		(layer "In7.Cu")
	)
	(gr_line
		(start 110.51159 -66.41846)
		(end 110.96879 -66.41846)
		(stroke
			(width 0.0762)
			(type default)
		)
		(layer "In7.Cu")
	)
	(gr_line
		(start 110.66907 -66.0146)
		(end 110.81131 -66.0146)
		(stroke
			(width 0.0762)
			(type default)
		)
		(layer "In7.Cu")
	)
	(gr_line
		(start 110.96879 -66.41846)
		(end 111.09071 -66.29654)
		(stroke
			(width 0.0762)
			(type default)
		)
		(layer "In7.Cu")
	)
	(gr_line
		(start 111.14786 -55.55234)
		(end 111.37138 -55.77586)
		(stroke
			(width 0.09525)
			(type default)
		)
		(layer "In7.Cu")
	)
	(gr_line
		(start 111.37138 -55.77586)
		(end 111.94288 -55.77586)
		(stroke
			(width 0.09525)
			(type default)
		)
		(layer "In7.Cu")
	)
	(gr_line
		(start 111.55299 -66.29654)
		(end 111.67491 -66.41846)
		(stroke
			(width 0.0762)
			(type default)
		)
		(layer "In7.Cu")
	)
	(gr_line
		(start 111.56696 -55.1307)
		(end 111.7473 -55.1307)
		(stroke
			(width 0.09525)
			(type default)
		)
		(layer "In7.Cu")
	)
	(gr_line
		(start 111.67491 -66.41846)
		(end 112.13211 -66.41846)
		(stroke
			(width 0.0762)
			(type default)
		)
		(layer "In7.Cu")
	)
	(gr_line
		(start 111.83239 -66.0146)
		(end 111.97463 -66.0146)
		(stroke
			(width 0.0762)
			(type default)
		)
		(layer "In7.Cu")
	)
	(gr_line
		(start 111.938562 -41.961562)
		(end 112.076484 -41.961562)
		(stroke
			(width 0.0508)
			(type default)
		)
		(layer "In7.Cu")
	)
	(gr_line
		(start 111.94288 -55.77586)
		(end 112.1664 -55.55234)
		(stroke
			(width 0.09525)
			(type default)
		)
		(layer "In7.Cu")
	)
	(gr_line
		(start 112.02035 -54.01056)
		(end 112.24387 -53.78704)
		(stroke
			(width 0.09525)
			(type default)
		)
		(layer "In7.Cu")
	)
	(gr_line
		(start 112.076484 -41.961562)
		(end 112.118648 -42.003726)
		(stroke
			(width 0.0508)
			(type default)
		)
		(layer "In7.Cu")
	)
	(gr_line
		(start 112.076484 -41.758362)
		(end 112.093248 -41.741598)
		(stroke
			(width 0.0508)
			(type default)
		)
		(layer "In7.Cu")
	)
	(gr_line
		(start 112.093248 -41.741598)
		(end 112.179862 -41.741598)
		(stroke
			(width 0.0508)
			(type default)
		)
		(layer "In7.Cu")
	)
	(gr_line
		(start 112.120426 -42.005504)
		(end 112.13592 -42.020998)
		(stroke
			(width 0.0508)
			(type default)
		)
		(layer "In7.Cu")
	)
	(gr_line
		(start 112.13211 -66.41846)
		(end 112.25403 -66.29654)
		(stroke
			(width 0.0762)
			(type default)
		)
		(layer "In7.Cu")
	)
	(gr_line
		(start 112.179862 -41.741598)
		(end 112.317784 -41.741598)
		(stroke
			(width 0.0762)
			(type default)
		)
		(layer "In7.Cu")
	)
	(gr_line
		(start 112.24387 -53.78704)
		(end 112.81537 -53.78704)
		(stroke
			(width 0.09525)
			(type default)
		)
		(layer "In7.Cu")
	)
	(gr_line
		(start 112.43945 -54.4322)
		(end 112.61979 -54.4322)
		(stroke
			(width 0.09525)
			(type default)
		)
		(layer "In7.Cu")
	)
	(gr_line
		(start 112.71631 -66.29654)
		(end 112.83823 -66.41846)
		(stroke
			(width 0.0762)
			(type default)
		)
		(layer "In7.Cu")
	)
	(gr_line
		(start 112.74298 -55.55234)
		(end 112.9665 -55.77586)
		(stroke
			(width 0.09525)
			(type default)
		)
		(layer "In7.Cu")
	)
	(gr_line
		(start 112.81537 -53.78704)
		(end 113.03889 -54.01056)
		(stroke
			(width 0.09525)
			(type default)
		)
		(layer "In7.Cu")
	)
	(gr_line
		(start 112.83823 -66.41846)
		(end 113.29543 -66.41846)
		(stroke
			(width 0.0762)
			(type default)
		)
		(layer "In7.Cu")
	)
	(gr_line
		(start 112.9665 -55.77586)
		(end 113.538 -55.77586)
		(stroke
			(width 0.09525)
			(type default)
		)
		(layer "In7.Cu")
	)
	(gr_line
		(start 112.99571 -66.0146)
		(end 113.13795 -66.0146)
		(stroke
			(width 0.0762)
			(type default)
		)
		(layer "In7.Cu")
	)
	(gr_line
		(start 113.16208 -55.1307)
		(end 113.34242 -55.1307)
		(stroke
			(width 0.09525)
			(type default)
		)
		(layer "In7.Cu")
	)
	(gr_line
		(start 113.29543 -66.41846)
		(end 113.41735 -66.29654)
		(stroke
			(width 0.0762)
			(type default)
		)
		(layer "In7.Cu")
	)
	(gr_line
		(start 113.538 -55.77586)
		(end 113.76152 -55.55234)
		(stroke
			(width 0.09525)
			(type default)
		)
		(layer "In7.Cu")
	)
	(gr_line
		(start 113.61547 -54.01056)
		(end 113.83899 -53.78704)
		(stroke
			(width 0.09525)
			(type default)
		)
		(layer "In7.Cu")
	)
	(gr_line
		(start 113.83899 -53.78704)
		(end 114.41049 -53.78704)
		(stroke
			(width 0.09525)
			(type default)
		)
		(layer "In7.Cu")
	)
	(gr_line
		(start 113.87963 -66.29654)
		(end 114.00155 -66.41846)
		(stroke
			(width 0.0762)
			(type default)
		)
		(layer "In7.Cu")
	)
	(gr_line
		(start 114.00155 -66.41846)
		(end 114.45875 -66.41846)
		(stroke
			(width 0.0762)
			(type default)
		)
		(layer "In7.Cu")
	)
	(gr_line
		(start 114.03457 -54.4322)
		(end 114.21491 -54.4322)
		(stroke
			(width 0.09525)
			(type default)
		)
		(layer "In7.Cu")
	)
	(gr_line
		(start 114.15903 -66.0146)
		(end 114.30127 -66.0146)
		(stroke
			(width 0.0762)
			(type default)
		)
		(layer "In7.Cu")
	)
	(gr_line
		(start 114.41049 -53.78704)
		(end 114.63401 -54.01056)
		(stroke
			(width 0.09525)
			(type default)
		)
		(layer "In7.Cu")
	)
	(gr_line
		(start 114.45875 -66.41846)
		(end 114.58067 -66.29654)
		(stroke
			(width 0.0762)
			(type default)
		)
		(layer "In7.Cu")
	)
	(gr_line
		(start 114.483388 -9.290812)
		(end 114.483388 -9.527032)
		(stroke
			(width 0.0762)
			(type default)
		)
		(layer "In7.Cu")
	)
	(gr_line
		(start 114.483388 -9.290812)
		(end 114.7318 -9.0424)
		(stroke
			(width 0.0762)
			(type default)
		)
		(layer "In7.Cu")
	)
	(gr_line
		(start 114.7318 -9.0424)
		(end 114.96802 -9.0424)
		(stroke
			(width 0.0762)
			(type default)
		)
		(layer "In7.Cu")
	)
	(gr_line
		(start 114.88039 -9.52881)
		(end 114.969798 -9.439402)
		(stroke
			(width 0.0762)
			(type default)
		)
		(layer "In7.Cu")
	)
	(gr_line
		(start 115.04295 -66.29654)
		(end 115.16487 -66.41846)
		(stroke
			(width 0.0762)
			(type default)
		)
		(layer "In7.Cu")
	)
	(gr_line
		(start 115.16487 -66.41846)
		(end 115.62207 -66.41846)
		(stroke
			(width 0.0762)
			(type default)
		)
		(layer "In7.Cu")
	)
	(gr_line
		(start 115.21059 -54.01056)
		(end 115.43411 -53.78704)
		(stroke
			(width 0.09525)
			(type default)
		)
		(layer "In7.Cu")
	)
	(gr_line
		(start 115.32235 -66.0146)
		(end 115.46459 -66.0146)
		(stroke
			(width 0.0762)
			(type default)
		)
		(layer "In7.Cu")
	)
	(gr_line
		(start 115.43411 -53.78704)
		(end 116.00561 -53.78704)
		(stroke
			(width 0.09525)
			(type default)
		)
		(layer "In7.Cu")
	)
	(gr_line
		(start 115.62207 -66.41846)
		(end 115.74399 -66.29654)
		(stroke
			(width 0.0762)
			(type default)
		)
		(layer "In7.Cu")
	)
	(gr_line
		(start 115.62969 -54.4322)
		(end 115.81003 -54.4322)
		(stroke
			(width 0.09525)
			(type default)
		)
		(layer "In7.Cu")
	)
	(gr_line
		(start 116.00561 -53.78704)
		(end 116.22913 -54.01056)
		(stroke
			(width 0.09525)
			(type default)
		)
		(layer "In7.Cu")
	)
	(gr_line
		(start 116.78539 -8.73506)
		(end 116.90731 -8.61314)
		(stroke
			(width 0.0762)
			(type default)
		)
		(layer "In7.Cu")
	)
	(gr_line
		(start 116.90731 -8.61314)
		(end 117.36451 -8.61314)
		(stroke
			(width 0.0762)
			(type default)
		)
		(layer "In7.Cu")
	)
	(gr_line
		(start 117.06479 -9.017)
		(end 117.20703 -9.017)
		(stroke
			(width 0.0762)
			(type default)
		)
		(layer "In7.Cu")
	)
	(gr_line
		(start 117.36451 -8.61314)
		(end 117.48643 -8.73506)
		(stroke
			(width 0.0762)
			(type default)
		)
		(layer "In7.Cu")
	)
	(gr_line
		(start 117.94871 -8.73506)
		(end 118.07063 -8.61314)
		(stroke
			(width 0.0762)
			(type default)
		)
		(layer "In7.Cu")
	)
	(gr_line
		(start 118.07063 -8.61314)
		(end 118.52783 -8.61314)
		(stroke
			(width 0.0762)
			(type default)
		)
		(layer "In7.Cu")
	)
	(gr_line
		(start 118.22811 -9.017)
		(end 118.37035 -9.017)
		(stroke
			(width 0.0762)
			(type default)
		)
		(layer "In7.Cu")
	)
	(gr_line
		(start 118.52783 -8.61314)
		(end 118.64975 -8.73506)
		(stroke
			(width 0.0762)
			(type default)
		)
		(layer "In7.Cu")
	)
	(gr_line
		(start 118.619778 -53.2892)
		(end 118.619778 -53.60543)
		(stroke
			(width 0.09525)
			(type default)
		)
		(layer "In7.Cu")
	)
	(gr_line
		(start 118.619778 -53.2892)
		(end 119.023892 -52.885086)
		(stroke
			(width 0.09525)
			(type default)
		)
		(layer "In7.Cu")
	)
	(gr_line
		(start 119.023892 -52.885086)
		(end 119.340122 -52.885086)
		(stroke
			(width 0.09525)
			(type default)
		)
		(layer "In7.Cu")
	)
	(gr_line
		(start 119.11203 -8.73506)
		(end 119.23395 -8.61314)
		(stroke
			(width 0.0762)
			(type default)
		)
		(layer "In7.Cu")
	)
	(gr_line
		(start 119.214392 -53.607208)
		(end 119.3419 -53.4797)
		(stroke
			(width 0.09525)
			(type default)
		)
		(layer "In7.Cu")
	)
	(gr_line
		(start 119.23395 -8.61314)
		(end 119.69115 -8.61314)
		(stroke
			(width 0.0762)
			(type default)
		)
		(layer "In7.Cu")
	)
	(gr_line
		(start 119.39143 -9.017)
		(end 119.53367 -9.017)
		(stroke
			(width 0.0762)
			(type default)
		)
		(layer "In7.Cu")
	)
	(gr_line
		(start 119.69115 -8.61314)
		(end 119.81307 -8.73506)
		(stroke
			(width 0.0762)
			(type default)
		)
		(layer "In7.Cu")
	)
	(gr_line
		(start 122.423174 -51.500786)
		(end 122.662188 -51.7398)
		(stroke
			(width 0.09525)
			(type default)
		)
		(layer "In7.Cu")
	)
	(gr_line
		(start 122.662188 -51.7398)
		(end 123.0122 -51.7398)
		(stroke
			(width 0.09525)
			(type default)
		)
		(layer "In7.Cu")
	)
	(gr_line
		(start 122.919236 -54.00929)
		(end 123.142756 -54.23281)
		(stroke
			(width 0.09525)
			(type default)
		)
		(layer "In7.Cu")
	)
	(gr_line
		(start 123.0122 -51.7398)
		(end 123.251214 -51.500786)
		(stroke
			(width 0.09525)
			(type default)
		)
		(layer "In7.Cu")
	)
	(gr_line
		(start 123.142756 -54.23281)
		(end 123.714256 -54.23281)
		(stroke
			(width 0.09525)
			(type default)
		)
		(layer "In7.Cu")
	)
	(gr_line
		(start 123.338336 -53.58765)
		(end 123.518676 -53.58765)
		(stroke
			(width 0.09525)
			(type default)
		)
		(layer "In7.Cu")
	)
	(gr_line
		(start 123.714256 -54.23281)
		(end 123.937776 -54.00929)
		(stroke
			(width 0.09525)
			(type default)
		)
		(layer "In7.Cu")
	)
	(gr_line
		(start 124.514356 -54.00929)
		(end 124.737876 -54.23281)
		(stroke
			(width 0.09525)
			(type default)
		)
		(layer "In7.Cu")
	)
	(gr_line
		(start 124.737876 -54.23281)
		(end 125.309376 -54.23281)
		(stroke
			(width 0.09525)
			(type default)
		)
		(layer "In7.Cu")
	)
	(gr_line
		(start 124.933456 -53.58765)
		(end 125.113796 -53.58765)
		(stroke
			(width 0.09525)
			(type default)
		)
		(layer "In7.Cu")
	)
	(gr_line
		(start 125.309376 -54.23281)
		(end 125.532896 -54.00929)
		(stroke
			(width 0.09525)
			(type default)
		)
		(layer "In7.Cu")
	)
	(gr_line
		(start 127.192786 -51.500786)
		(end 127.416306 -51.724306)
		(stroke
			(width 0.09525)
			(type default)
		)
		(layer "In7.Cu")
	)
	(gr_line
		(start 127.416306 -51.724306)
		(end 127.752094 -51.724306)
		(stroke
			(width 0.09525)
			(type default)
		)
		(layer "In7.Cu")
	)
	(gr_line
		(start 127.752094 -51.724306)
		(end 127.975614 -51.500786)
		(stroke
			(width 0.09525)
			(type default)
		)
		(layer "In7.Cu")
	)
	(gr_line
		(start 128.12014 -9.82726)
		(end 128.24206 -9.70534)
		(stroke
			(width 0.0762)
			(type default)
		)
		(layer "In7.Cu")
	)
	(gr_line
		(start 128.24206 -9.70534)
		(end 128.69926 -9.70534)
		(stroke
			(width 0.0762)
			(type default)
		)
		(layer "In7.Cu")
	)
	(gr_line
		(start 128.39954 -10.1092)
		(end 128.54178 -10.1092)
		(stroke
			(width 0.0762)
			(type default)
		)
		(layer "In7.Cu")
	)
	(gr_line
		(start 128.69926 -9.70534)
		(end 128.82118 -9.82726)
		(stroke
			(width 0.0762)
			(type default)
		)
		(layer "In7.Cu")
	)
	(gr_line
		(start 130.774186 -51.500786)
		(end 130.997706 -51.724306)
		(stroke
			(width 0.09525)
			(type default)
		)
		(layer "In7.Cu")
	)
	(gr_line
		(start 130.932936 -5.818378)
		(end 131.150868 -6.03631)
		(stroke
			(width 0.0762)
			(type default)
		)
		(layer "In7.Cu")
	)
	(gr_line
		(start 130.997706 -51.724306)
		(end 131.536694 -51.724306)
		(stroke
			(width 0.09525)
			(type default)
		)
		(layer "In7.Cu")
	)
	(gr_line
		(start 131.193286 -51.079146)
		(end 131.341114 -51.079146)
		(stroke
			(width 0.09525)
			(type default)
		)
		(layer "In7.Cu")
	)
	(gr_line
		(start 131.532884 -66.672206)
		(end 131.750816 -66.454274)
		(stroke
			(width 0.0762)
			(type default)
		)
		(layer "In7.Cu")
	)
	(gr_line
		(start 131.536694 -51.724306)
		(end 131.760214 -51.500786)
		(stroke
			(width 0.09525)
			(type default)
		)
		(layer "In7.Cu")
	)
	(gr_line
		(start 131.549394 -6.03631)
		(end 131.767326 -5.818378)
		(stroke
			(width 0.0762)
			(type default)
		)
		(layer "In7.Cu")
	)
	(gr_line
		(start 132.149342 -66.454274)
		(end 132.367274 -66.672206)
		(stroke
			(width 0.0762)
			(type default)
		)
		(layer "In7.Cu")
	)
	(gr_line
		(start 132.323586 -51.500786)
		(end 132.547106 -51.724306)
		(stroke
			(width 0.09525)
			(type default)
		)
		(layer "In7.Cu")
	)
	(gr_line
		(start 132.547106 -51.724306)
		(end 133.086094 -51.724306)
		(stroke
			(width 0.09525)
			(type default)
		)
		(layer "In7.Cu")
	)
	(gr_line
		(start 132.742686 -51.079146)
		(end 132.890514 -51.079146)
		(stroke
			(width 0.09525)
			(type default)
		)
		(layer "In7.Cu")
	)
	(gr_line
		(start 133.086094 -51.724306)
		(end 133.309614 -51.500786)
		(stroke
			(width 0.09525)
			(type default)
		)
		(layer "In7.Cu")
	)
	(gr_line
		(start 144.589246 -55.357268)
		(end 144.99336 -55.761382)
		(stroke
			(width 0.09525)
			(type default)
		)
		(layer "In7.Cu")
	)
	(gr_line
		(start 144.589246 -55.041038)
		(end 144.589246 -55.357268)
		(stroke
			(width 0.09525)
			(type default)
		)
		(layer "In7.Cu")
	)
	(gr_line
		(start 144.99336 -55.761382)
		(end 145.30959 -55.761382)
		(stroke
			(width 0.09525)
			(type default)
		)
		(layer "In7.Cu")
	)
	(gr_line
		(start 145.18386 -55.03926)
		(end 145.311368 -55.166768)
		(stroke
			(width 0.09525)
			(type default)
		)
		(layer "In7.Cu")
	)
	(gr_line
		(start 145.71726 -56.485028)
		(end 146.077432 -56.8452)
		(stroke
			(width 0.09525)
			(type default)
		)
		(layer "In7.Cu")
	)
	(gr_line
		(start 145.71726 -56.169052)
		(end 145.71726 -56.485028)
		(stroke
			(width 0.09525)
			(type default)
		)
		(layer "In7.Cu")
	)
	(gr_line
		(start 146.077432 -56.8452)
		(end 146.393408 -56.8452)
		(stroke
			(width 0.09525)
			(type default)
		)
		(layer "In7.Cu")
	)
	(gr_line
		(start 146.311874 -56.167274)
		(end 146.395186 -56.250586)
		(stroke
			(width 0.09525)
			(type default)
		)
		(layer "In7.Cu")
	)
	(gr_line
		(start 147.390104 -53.63464)
		(end 147.613624 -53.85816)
		(stroke
			(width 0.09525)
			(type default)
		)
		(layer "In7.Cu")
	)
	(gr_line
		(start 147.613624 -53.85816)
		(end 148.185124 -53.85816)
		(stroke
			(width 0.09525)
			(type default)
		)
		(layer "In7.Cu")
	)
	(gr_line
		(start 147.809204 -53.213)
		(end 147.989544 -53.213)
		(stroke
			(width 0.09525)
			(type default)
		)
		(layer "In7.Cu")
	)
	(gr_line
		(start 148.185124 -53.85816)
		(end 148.408644 -53.63464)
		(stroke
			(width 0.09525)
			(type default)
		)
		(layer "In7.Cu")
	)
	(gr_line
		(start 153.0604 -68.7324)
		(end 153.661618 -69.333618)
		(stroke
			(width 0.09525)
			(type default)
		)
		(layer "In7.Cu")
	)
	(gr_line
		(start 153.434796 -64.616076)
		(end 153.645108 -64.405764)
		(stroke
			(width 0.09525)
			(type default)
		)
		(layer "In7.Cu")
	)
	(gr_line
		(start 153.48204 -68.39204)
		(end 153.6954 -68.6054)
		(stroke
			(width 0.09525)
			(type default)
		)
		(layer "In7.Cu")
	)
	(gr_line
		(start 153.661618 -69.333618)
		(end 153.68651 -69.333618)
		(stroke
			(width 0.09525)
			(type default)
		)
		(layer "In7.Cu")
	)
	(gr_line
		(start 153.68905 -58.83529)
		(end 153.68905 -59.01563)
		(stroke
			(width 0.09525)
			(type default)
		)
		(layer "In7.Cu")
	)
	(gr_line
		(start 154.066748 -64.887348)
		(end 154.1018 -64.9224)
		(stroke
			(width 0.09525)
			(type default)
		)
		(layer "In7.Cu")
	)
	(gr_line
		(start 154.066748 -64.824864)
		(end 154.066748 -64.887348)
		(stroke
			(width 0.09525)
			(type default)
		)
		(layer "In7.Cu")
	)
	(gr_line
		(start 154.11069 -59.43473)
		(end 154.33421 -59.21121)
		(stroke
			(width 0.09525)
			(type default)
		)
		(layer "In7.Cu")
	)
	(gr_line
		(start 154.11069 -58.41619)
		(end 154.33421 -58.63971)
		(stroke
			(width 0.09525)
			(type default)
		)
		(layer "In7.Cu")
	)
	(gr_line
		(start 154.246834 -68.864734)
		(end 154.695906 -69.313806)
		(stroke
			(width 0.09525)
			(type default)
		)
		(layer "In7.Cu")
	)
	(gr_line
		(start 154.246834 -68.384166)
		(end 154.246834 -68.864734)
		(stroke
			(width 0.09525)
			(type default)
		)
		(layer "In7.Cu")
	)
	(gr_line
		(start 154.246834 -68.384166)
		(end 154.457654 -68.173346)
		(stroke
			(width 0.09525)
			(type default)
		)
		(layer "In7.Cu")
	)
	(gr_line
		(start 154.33421 -58.63971)
		(end 154.33421 -59.21121)
		(stroke
			(width 0.09525)
			(type default)
		)
		(layer "In7.Cu")
	)
	(gr_line
		(start 154.485848 -64.417448)
		(end 154.813 -64.7446)
		(stroke
			(width 0.09525)
			(type default)
		)
		(layer "In7.Cu")
	)
	(gr_line
		(start 154.485848 -63.83528)
		(end 154.485848 -64.417448)
		(stroke
			(width 0.09525)
			(type default)
		)
		(layer "In7.Cu")
	)
	(gr_line
		(start 154.684984 -68.615052)
		(end 154.684984 -68.632324)
		(stroke
			(width 0.09525)
			(type default)
		)
		(layer "In7.Cu")
	)
	(gr_line
		(start 154.684984 -68.615052)
		(end 154.879294 -68.420742)
		(stroke
			(width 0.09525)
			(type default)
		)
		(layer "In7.Cu")
	)
	(gr_line
		(start 154.695906 -69.313806)
		(end 154.913584 -69.313806)
		(stroke
			(width 0.09525)
			(type default)
		)
		(layer "In7.Cu")
	)
	(gr_line
		(start 154.923998 -63.993522)
		(end 154.923998 -64.034924)
		(stroke
			(width 0.09525)
			(type default)
		)
		(layer "In7.Cu")
	)
	(gr_line
		(start 155.00604 -61.284104)
		(end 155.22956 -61.507624)
		(stroke
			(width 0.09525)
			(type default)
		)
		(layer "In7.Cu")
	)
	(gr_line
		(start 155.00604 -60.712604)
		(end 155.00604 -61.284104)
		(stroke
			(width 0.09525)
			(type default)
		)
		(layer "In7.Cu")
	)
	(gr_line
		(start 155.00604 -60.712604)
		(end 155.22956 -60.489084)
		(stroke
			(width 0.09525)
			(type default)
		)
		(layer "In7.Cu")
	)
	(gr_line
		(start 155.276804 -55.759604)
		(end 155.404058 -55.886858)
		(stroke
			(width 0.09525)
			(type default)
		)
		(layer "In7.Cu")
	)
	(gr_line
		(start 155.278582 -55.16499)
		(end 155.594558 -55.16499)
		(stroke
			(width 0.09525)
			(type default)
		)
		(layer "In7.Cu")
	)
	(gr_line
		(start 155.594558 -55.16499)
		(end 155.998672 -55.569104)
		(stroke
			(width 0.09525)
			(type default)
		)
		(layer "In7.Cu")
	)
	(gr_line
		(start 155.6512 -60.908184)
		(end 155.6512 -61.088524)
		(stroke
			(width 0.09525)
			(type default)
		)
		(layer "In7.Cu")
	)
	(gr_line
		(start 155.998672 -55.569104)
		(end 155.998672 -55.88508)
		(stroke
			(width 0.09525)
			(type default)
		)
		(layer "In7.Cu")
	)
	(gr_line
		(start 156.404564 -56.887364)
		(end 156.532072 -57.014872)
		(stroke
			(width 0.09525)
			(type default)
		)
		(layer "In7.Cu")
	)
	(gr_line
		(start 156.406342 -56.29275)
		(end 156.722572 -56.29275)
		(stroke
			(width 0.09525)
			(type default)
		)
		(layer "In7.Cu")
	)
	(gr_line
		(start 156.722572 -56.29275)
		(end 157.126686 -56.696864)
		(stroke
			(width 0.09525)
			(type default)
		)
		(layer "In7.Cu")
	)
	(gr_line
		(start 157.1117 -61.570108)
		(end 157.1117 -61.750448)
		(stroke
			(width 0.09525)
			(type default)
		)
		(layer "In7.Cu")
	)
	(gr_line
		(start 157.1117 -59.6138)
		(end 157.1117 -59.79414)
		(stroke
			(width 0.09525)
			(type default)
		)
		(layer "In7.Cu")
	)
	(gr_line
		(start 157.126686 -56.696864)
		(end 157.126686 -57.013094)
		(stroke
			(width 0.09525)
			(type default)
		)
		(layer "In7.Cu")
	)
	(gr_line
		(start 157.53334 -62.169548)
		(end 157.75686 -61.946028)
		(stroke
			(width 0.09525)
			(type default)
		)
		(layer "In7.Cu")
	)
	(gr_line
		(start 157.53334 -61.151008)
		(end 157.75686 -61.374528)
		(stroke
			(width 0.09525)
			(type default)
		)
		(layer "In7.Cu")
	)
	(gr_line
		(start 157.53334 -60.21324)
		(end 157.75686 -59.98972)
		(stroke
			(width 0.09525)
			(type default)
		)
		(layer "In7.Cu")
	)
	(gr_line
		(start 157.53334 -59.1947)
		(end 157.75686 -59.41822)
		(stroke
			(width 0.09525)
			(type default)
		)
		(layer "In7.Cu")
	)
	(gr_line
		(start 157.75686 -61.374528)
		(end 157.75686 -61.946028)
		(stroke
			(width 0.09525)
			(type default)
		)
		(layer "In7.Cu")
	)
	(gr_line
		(start 157.75686 -59.41822)
		(end 157.75686 -59.98972)
		(stroke
			(width 0.09525)
			(type default)
		)
		(layer "In7.Cu")
	)
	(gr_line
		(start 171.35729 -53.831998)
		(end 171.680632 -54.15534)
		(stroke
			(width 0.0762)
			(type default)
		)
		(layer "In7.Cu")
	)
	(gr_line
		(start 171.35729 -53.659532)
		(end 171.35729 -53.831998)
		(stroke
			(width 0.0762)
			(type default)
		)
		(layer "In7.Cu")
	)
	(gr_line
		(start 171.680632 -54.15534)
		(end 171.853098 -54.15534)
		(stroke
			(width 0.0762)
			(type default)
		)
		(layer "In7.Cu")
	)
	(gr_line
		(start 171.754292 -53.657754)
		(end 171.854876 -53.758338)
		(stroke
			(width 0.0762)
			(type default)
		)
		(layer "In7.Cu")
	)
	(gr_line
		(start 172.301408 -54.776116)
		(end 172.62475 -55.099458)
		(stroke
			(width 0.0762)
			(type default)
		)
		(layer "In7.Cu")
	)
	(gr_line
		(start 172.301408 -54.60365)
		(end 172.301408 -54.776116)
		(stroke
			(width 0.0762)
			(type default)
		)
		(layer "In7.Cu")
	)
	(gr_line
		(start 172.62475 -55.099458)
		(end 172.797216 -55.099458)
		(stroke
			(width 0.0762)
			(type default)
		)
		(layer "In7.Cu")
	)
	(gr_line
		(start 172.69841 -54.601872)
		(end 172.798994 -54.702456)
		(stroke
			(width 0.0762)
			(type default)
		)
		(layer "In7.Cu")
	)
	(gr_line
		(start 177.360072 -58.794142)
		(end 177.68316 -59.11723)
		(stroke
			(width 0.0762)
			(type default)
		)
		(layer "In7.Cu")
	)
	(gr_line
		(start 177.360072 -58.621676)
		(end 177.360072 -58.794142)
		(stroke
			(width 0.0762)
			(type default)
		)
		(layer "In7.Cu")
	)
	(gr_line
		(start 177.68316 -59.11723)
		(end 177.855626 -59.11723)
		(stroke
			(width 0.0762)
			(type default)
		)
		(layer "In7.Cu")
	)
	(gr_line
		(start 177.757074 -58.619898)
		(end 177.857404 -58.720228)
		(stroke
			(width 0.0762)
			(type default)
		)
		(layer "In7.Cu")
	)
	(gr_line
		(start 180.661818 -60.938664)
		(end 180.98516 -61.262006)
		(stroke
			(width 0.0762)
			(type default)
		)
		(layer "In7.Cu")
	)
	(gr_line
		(start 180.661818 -60.766198)
		(end 180.661818 -60.938664)
		(stroke
			(width 0.0762)
			(type default)
		)
		(layer "In7.Cu")
	)
	(gr_line
		(start 180.98516 -61.262006)
		(end 181.157626 -61.262006)
		(stroke
			(width 0.0762)
			(type default)
		)
		(layer "In7.Cu")
	)
	(gr_line
		(start 181.05882 -60.76442)
		(end 181.159404 -60.865004)
		(stroke
			(width 0.0762)
			(type default)
		)
		(layer "In7.Cu")
	)
	(gr_line
		(start 181.48427 -61.761116)
		(end 181.807612 -62.084458)
		(stroke
			(width 0.0762)
			(type default)
		)
		(layer "In7.Cu")
	)
	(gr_line
		(start 181.48427 -61.58865)
		(end 181.48427 -61.761116)
		(stroke
			(width 0.0762)
			(type default)
		)
		(layer "In7.Cu")
	)
	(gr_line
		(start 181.807612 -62.084458)
		(end 181.980078 -62.084458)
		(stroke
			(width 0.0762)
			(type default)
		)
		(layer "In7.Cu")
	)
	(gr_line
		(start 181.881272 -61.586872)
		(end 181.981856 -61.687456)
		(stroke
			(width 0.0762)
			(type default)
		)
		(layer "In7.Cu")
	)
	(gr_line
		(start 184.824624 -62.1284)
		(end 184.856374 -62.146434)
		(stroke
			(width 0.0762)
			(type default)
		)
		(layer "In7.Cu")
	)
	(gr_line
		(start 186.732672 -66.672206)
		(end 186.950604 -66.454274)
		(stroke
			(width 0.0762)
			(type default)
		)
		(layer "In7.Cu")
	)
	(gr_line
		(start 187.34913 -66.454274)
		(end 187.567062 -66.672206)
		(stroke
			(width 0.0762)
			(type default)
		)
		(layer "In7.Cu")
	)
	(gr_arc
		(start 1.54686 -67.178682)
		(mid 1.9304 -67.562222)
		(end 2.31394 -67.178682)
		(stroke
			(width 0.2)
			(type default)
		)
		(layer "In8.Cu")
	)
	(gr_line
		(start 1.54686 -66.221102)
		(end 1.54686 -67.178682)
		(stroke
			(width 0.2)
			(type default)
		)
		(layer "In8.Cu")
	)
	(gr_arc
		(start 1.54686 -64.178434)
		(mid 1.930273 -64.562228)
		(end 2.31394 -64.178688)
		(stroke
			(width 0.2)
			(type default)
		)
		(layer "In8.Cu")
	)
	(gr_line
		(start 1.54686 -63.221108)
		(end 1.54686 -64.178434)
		(stroke
			(width 0.2)
			(type default)
		)
		(layer "In8.Cu")
	)
	(gr_arc
		(start 1.54686 -61.178694)
		(mid 1.9304 -61.562234)
		(end 2.31394 -61.178694)
		(stroke
			(width 0.2)
			(type default)
		)
		(layer "In8.Cu")
	)
	(gr_line
		(start 1.54686 -60.221114)
		(end 1.54686 -61.178694)
		(stroke
			(width 0.2)
			(type default)
		)
		(layer "In8.Cu")
	)
	(gr_line
		(start 2.31394 -67.178682)
		(end 2.31394 -66.221356)
		(stroke
			(width 0.2)
			(type default)
		)
		(layer "In8.Cu")
	)
	(gr_arc
		(start 2.31394 -66.221356)
		(mid 1.930527 -65.837562)
		(end 1.54686 -66.221102)
		(stroke
			(width 0.2)
			(type default)
		)
		(layer "In8.Cu")
	)
	(gr_line
		(start 2.31394 -64.178688)
		(end 2.31394 -63.221108)
		(stroke
			(width 0.2)
			(type default)
		)
		(layer "In8.Cu")
	)
	(gr_arc
		(start 2.31394 -63.221108)
		(mid 1.9304 -62.837568)
		(end 1.54686 -63.221108)
		(stroke
			(width 0.2)
			(type default)
		)
		(layer "In8.Cu")
	)
	(gr_line
		(start 2.31394 -61.178694)
		(end 2.31394 -60.221368)
		(stroke
			(width 0.2)
			(type default)
		)
		(layer "In8.Cu")
	)
	(gr_arc
		(start 2.31394 -60.221368)
		(mid 1.930527 -59.837574)
		(end 1.54686 -60.221114)
		(stroke
			(width 0.2)
			(type default)
		)
		(layer "In8.Cu")
	)
	(gr_arc
		(start 2.94132 -59.664092)
		(mid 3.324733 -60.047886)
		(end 3.7084 -59.664346)
		(stroke
			(width 0.2)
			(type default)
		)
		(layer "In8.Cu")
	)
	(gr_line
		(start 2.94132 -58.706766)
		(end 2.94132 -59.664092)
		(stroke
			(width 0.2)
			(type default)
		)
		(layer "In8.Cu")
	)
	(gr_arc
		(start 3.06832 -65.664334)
		(mid 3.45186 -66.047874)
		(end 3.8354 -65.664334)
		(stroke
			(width 0.2)
			(type default)
		)
		(layer "In8.Cu")
	)
	(gr_line
		(start 3.06832 -64.706754)
		(end 3.06832 -65.664334)
		(stroke
			(width 0.2)
			(type default)
		)
		(layer "In8.Cu")
	)
	(gr_arc
		(start 3.06832 -62.66434)
		(mid 3.45186 -63.04788)
		(end 3.8354 -62.66434)
		(stroke
			(width 0.2)
			(type default)
		)
		(layer "In8.Cu")
	)
	(gr_line
		(start 3.06832 -61.70676)
		(end 3.06832 -62.66434)
		(stroke
			(width 0.2)
			(type default)
		)
		(layer "In8.Cu")
	)
	(gr_line
		(start 3.7084 -59.664346)
		(end 3.7084 -58.706766)
		(stroke
			(width 0.2)
			(type default)
		)
		(layer "In8.Cu")
	)
	(gr_arc
		(start 3.7084 -58.706766)
		(mid 3.32486 -58.323226)
		(end 2.94132 -58.706766)
		(stroke
			(width 0.2)
			(type default)
		)
		(layer "In8.Cu")
	)
	(gr_line
		(start 3.8354 -65.664334)
		(end 3.8354 -64.707008)
		(stroke
			(width 0.2)
			(type default)
		)
		(layer "In8.Cu")
	)
	(gr_arc
		(start 3.8354 -64.707008)
		(mid 3.451987 -64.323214)
		(end 3.06832 -64.706754)
		(stroke
			(width 0.2)
			(type default)
		)
		(layer "In8.Cu")
	)
	(gr_line
		(start 3.8354 -62.66434)
		(end 3.8354 -61.707014)
		(stroke
			(width 0.2)
			(type default)
		)
		(layer "In8.Cu")
	)
	(gr_arc
		(start 3.8354 -61.707014)
		(mid 3.451987 -61.32322)
		(end 3.06832 -61.70676)
		(stroke
			(width 0.2)
			(type default)
		)
		(layer "In8.Cu")
	)
	(gr_line
		(start 5.114798 -49.276)
		(end 5.114798 -43.688)
		(stroke
			(width 0.2)
			(type default)
		)
		(layer "In8.Cu")
	)
	(gr_line
		(start 5.114798 -43.688)
		(end 8.543798 -43.688)
		(stroke
			(width 0.2)
			(type default)
		)
		(layer "In8.Cu")
	)
	(gr_arc
		(start 7.747 -51.6128)
		(mid 8.128 -51.9938)
		(end 8.509 -51.6128)
		(stroke
			(width 0.2)
			(type default)
		)
		(layer "In8.Cu")
	)
	(gr_line
		(start 7.747 -50.6222)
		(end 7.747 -51.6128)
		(stroke
			(width 0.2)
			(type default)
		)
		(layer "In8.Cu")
	)
	(gr_arc
		(start 8.4582 -53.8988)
		(mid 8.8392 -54.2798)
		(end 9.2202 -53.8988)
		(stroke
			(width 0.2)
			(type default)
		)
		(layer "In8.Cu")
	)
	(gr_line
		(start 8.4582 -52.9082)
		(end 8.4582 -53.8988)
		(stroke
			(width 0.2)
			(type default)
		)
		(layer "In8.Cu")
	)
	(gr_line
		(start 8.509 -51.6128)
		(end 8.509 -50.622454)
		(stroke
			(width 0.2)
			(type default)
		)
		(layer "In8.Cu")
	)
	(gr_arc
		(start 8.509 -50.622454)
		(mid 8.128127 -50.2412)
		(end 7.747 -50.6222)
		(stroke
			(width 0.2)
			(type default)
		)
		(layer "In8.Cu")
	)
	(gr_line
		(start 8.543798 -49.276)
		(end 5.114798 -49.276)
		(stroke
			(width 0.2)
			(type default)
		)
		(layer "In8.Cu")
	)
	(gr_line
		(start 8.543798 -43.688)
		(end 8.543798 -49.276)
		(stroke
			(width 0.2)
			(type default)
		)
		(layer "In8.Cu")
	)
	(gr_line
		(start 9.2202 -53.8988)
		(end 9.2202 -52.908454)
		(stroke
			(width 0.2)
			(type default)
		)
		(layer "In8.Cu")
	)
	(gr_arc
		(start 9.2202 -52.908454)
		(mid 8.839327 -52.5272)
		(end 8.4582 -52.9082)
		(stroke
			(width 0.2)
			(type default)
		)
		(layer "In8.Cu")
	)
	(gr_line
		(start 9.240774 -62.748922)
		(end 9.266174 -63.637668)
		(stroke
			(width 0.2)
			(type default)
		)
		(layer "In8.Cu")
	)
	(gr_line
		(start 9.240774 -59.192922)
		(end 9.266174 -60.081668)
		(stroke
			(width 0.2)
			(type default)
		)
		(layer "In8.Cu")
	)
	(gr_arc
		(start 9.24306 -65.405)
		(mid 9.6266 -65.78854)
		(end 10.01014 -65.405)
		(stroke
			(width 0.2)
			(type default)
		)
		(layer "In8.Cu")
	)
	(gr_line
		(start 9.24306 -64.516)
		(end 9.24306 -65.405)
		(stroke
			(width 0.2)
			(type default)
		)
		(layer "In8.Cu")
	)
	(gr_arc
		(start 9.24306 -61.849)
		(mid 9.6266 -62.23254)
		(end 10.01014 -61.849)
		(stroke
			(width 0.2)
			(type default)
		)
		(layer "In8.Cu")
	)
	(gr_line
		(start 9.24306 -60.96)
		(end 9.24306 -61.849)
		(stroke
			(width 0.2)
			(type default)
		)
		(layer "In8.Cu")
	)
	(gr_arc
		(start 9.24306 -58.293)
		(mid 9.6266 -58.67654)
		(end 10.01014 -58.293)
		(stroke
			(width 0.2)
			(type default)
		)
		(layer "In8.Cu")
	)
	(gr_line
		(start 9.24306 -57.404)
		(end 9.24306 -58.293)
		(stroke
			(width 0.2)
			(type default)
		)
		(layer "In8.Cu")
	)
	(gr_arc
		(start 9.24306 -56.515)
		(mid 9.6266 -56.89854)
		(end 10.01014 -56.515)
		(stroke
			(width 0.2)
			(type default)
		)
		(layer "In8.Cu")
	)
	(gr_line
		(start 9.24306 -55.626)
		(end 9.24306 -56.515)
		(stroke
			(width 0.2)
			(type default)
		)
		(layer "In8.Cu")
	)
	(gr_line
		(start 9.243314 -62.748922)
		(end 9.240774 -62.748922)
		(stroke
			(width 0.2)
			(type default)
		)
		(layer "In8.Cu")
	)
	(gr_line
		(start 9.243314 -59.192922)
		(end 9.240774 -59.192922)
		(stroke
			(width 0.2)
			(type default)
		)
		(layer "In8.Cu")
	)
	(gr_line
		(start 9.266174 -63.637668)
		(end 9.266428 -63.637922)
		(stroke
			(width 0.2)
			(type default)
		)
		(layer "In8.Cu")
	)
	(gr_line
		(start 9.266174 -60.081668)
		(end 9.266428 -60.081922)
		(stroke
			(width 0.2)
			(type default)
		)
		(layer "In8.Cu")
	)
	(gr_line
		(start 9.266428 -63.637922)
		(end 9.268714 -63.637922)
		(stroke
			(width 0.2)
			(type default)
		)
		(layer "In8.Cu")
	)
	(gr_line
		(start 9.266428 -60.081922)
		(end 9.268714 -60.081922)
		(stroke
			(width 0.2)
			(type default)
		)
		(layer "In8.Cu")
	)
	(gr_arc
		(start 9.268714 -63.637922)
		(mid 9.662922 -64.010286)
		(end 10.035286 -63.616078)
		(stroke
			(width 0.2)
			(type default)
		)
		(layer "In8.Cu")
	)
	(gr_arc
		(start 9.268714 -60.081922)
		(mid 9.662922 -60.454286)
		(end 10.035286 -60.060078)
		(stroke
			(width 0.2)
			(type default)
		)
		(layer "In8.Cu")
	)
	(gr_circle
		(center 9.5504 -51.7398)
		(end 9.90854 -51.7398)
		(stroke
			(width 0.2)
			(type default)
		)
		(fill no)
		(layer "In8.Cu")
	)
	(gr_circle
		(center 9.5504 -50.4952)
		(end 9.90854 -50.4952)
		(stroke
			(width 0.2)
			(type default)
		)
		(fill no)
		(layer "In8.Cu")
	)
	(gr_arc
		(start 10.009886 -62.727078)
		(mid 9.615678 -62.354714)
		(end 9.243314 -62.748922)
		(stroke
			(width 0.2)
			(type default)
		)
		(layer "In8.Cu")
	)
	(gr_arc
		(start 10.009886 -59.171078)
		(mid 9.615678 -58.798714)
		(end 9.243314 -59.192922)
		(stroke
			(width 0.2)
			(type default)
		)
		(layer "In8.Cu")
	)
	(gr_line
		(start 10.01014 -65.405)
		(end 10.01014 -64.516254)
		(stroke
			(width 0.2)
			(type default)
		)
		(layer "In8.Cu")
	)
	(gr_arc
		(start 10.01014 -64.516254)
		(mid 9.626727 -64.13246)
		(end 9.24306 -64.516)
		(stroke
			(width 0.2)
			(type default)
		)
		(layer "In8.Cu")
	)
	(gr_line
		(start 10.01014 -61.849)
		(end 10.01014 -60.960254)
		(stroke
			(width 0.2)
			(type default)
		)
		(layer "In8.Cu")
	)
	(gr_arc
		(start 10.01014 -60.960254)
		(mid 9.626727 -60.57646)
		(end 9.24306 -60.96)
		(stroke
			(width 0.2)
			(type default)
		)
		(layer "In8.Cu")
	)
	(gr_line
		(start 10.01014 -58.293)
		(end 10.01014 -57.404254)
		(stroke
			(width 0.2)
			(type default)
		)
		(layer "In8.Cu")
	)
	(gr_arc
		(start 10.01014 -57.404254)
		(mid 9.626727 -57.02046)
		(end 9.24306 -57.404)
		(stroke
			(width 0.2)
			(type default)
		)
		(layer "In8.Cu")
	)
	(gr_line
		(start 10.01014 -56.515)
		(end 10.01014 -55.626254)
		(stroke
			(width 0.2)
			(type default)
		)
		(layer "In8.Cu")
	)
	(gr_arc
		(start 10.01014 -55.626254)
		(mid 9.626727 -55.24246)
		(end 9.24306 -55.626)
		(stroke
			(width 0.2)
			(type default)
		)
		(layer "In8.Cu")
	)
	(gr_line
		(start 10.012426 -62.727078)
		(end 10.009886 -62.727078)
		(stroke
			(width 0.2)
			(type default)
		)
		(layer "In8.Cu")
	)
	(gr_line
		(start 10.012426 -59.171078)
		(end 10.009886 -59.171078)
		(stroke
			(width 0.2)
			(type default)
		)
		(layer "In8.Cu")
	)
	(gr_line
		(start 10.035286 -63.616078)
		(end 10.037826 -63.616078)
		(stroke
			(width 0.2)
			(type default)
		)
		(layer "In8.Cu")
	)
	(gr_line
		(start 10.035286 -60.060078)
		(end 10.037826 -60.060078)
		(stroke
			(width 0.2)
			(type default)
		)
		(layer "In8.Cu")
	)
	(gr_line
		(start 10.037826 -63.616078)
		(end 10.012426 -62.727078)
		(stroke
			(width 0.2)
			(type default)
		)
		(layer "In8.Cu")
	)
	(gr_line
		(start 10.037826 -60.060078)
		(end 10.012426 -59.171078)
		(stroke
			(width 0.2)
			(type default)
		)
		(layer "In8.Cu")
	)
	(gr_circle
		(center 10.2616 -54.0258)
		(end 10.61974 -54.0258)
		(stroke
			(width 0.2)
			(type default)
		)
		(fill no)
		(layer "In8.Cu")
	)
	(gr_circle
		(center 10.2616 -52.7812)
		(end 10.61974 -52.7812)
		(stroke
			(width 0.2)
			(type default)
		)
		(fill no)
		(layer "In8.Cu")
	)
	(gr_arc
		(start 12.7889 -48.617886)
		(mid 13.172313 -49.00168)
		(end 13.55598 -48.61814)
		(stroke
			(width 0.2)
			(type default)
		)
		(layer "In8.Cu")
	)
	(gr_line
		(start 12.7889 -47.66056)
		(end 12.7889 -48.617886)
		(stroke
			(width 0.2)
			(type default)
		)
		(layer "In8.Cu")
	)
	(gr_line
		(start 13.55598 -48.61814)
		(end 13.55598 -47.66056)
		(stroke
			(width 0.2)
			(type default)
		)
		(layer "In8.Cu")
	)
	(gr_arc
		(start 13.55598 -47.66056)
		(mid 13.17244 -47.27702)
		(end 12.7889 -47.66056)
		(stroke
			(width 0.2)
			(type default)
		)
		(layer "In8.Cu")
	)
	(gr_line
		(start 14.15288 -47.21606)
		(end 15.082266 -47.21606)
		(stroke
			(width 0.2)
			(type default)
		)
		(layer "In8.Cu")
	)
	(gr_arc
		(start 14.153134 -46.44898)
		(mid 13.76934 -46.832393)
		(end 14.15288 -47.21606)
		(stroke
			(width 0.2)
			(type default)
		)
		(layer "In8.Cu")
	)
	(gr_arc
		(start 15.082266 -47.21606)
		(mid 15.465806 -46.83252)
		(end 15.082266 -46.44898)
		(stroke
			(width 0.2)
			(type default)
		)
		(layer "In8.Cu")
	)
	(gr_line
		(start 15.082266 -46.44898)
		(end 14.153134 -46.44898)
		(stroke
			(width 0.2)
			(type default)
		)
		(layer "In8.Cu")
	)
	(gr_line
		(start 19.408394 -10.634218)
		(end 20.327874 -10.634218)
		(stroke
			(width 0.2)
			(type default)
		)
		(layer "In8.Cu")
	)
	(gr_arc
		(start 19.408648 -9.867138)
		(mid 19.024854 -10.250551)
		(end 19.408394 -10.634218)
		(stroke
			(width 0.2)
			(type default)
		)
		(layer "In8.Cu")
	)
	(gr_line
		(start 20.09521 -15.872206)
		(end 21.052536 -15.872206)
		(stroke
			(width 0.2)
			(type default)
		)
		(layer "In8.Cu")
	)
	(gr_arc
		(start 20.09521 -15.105126)
		(mid 19.71167 -15.488666)
		(end 20.09521 -15.872206)
		(stroke
			(width 0.2)
			(type default)
		)
		(layer "In8.Cu")
	)
	(gr_arc
		(start 20.327874 -10.634218)
		(mid 20.711414 -10.250678)
		(end 20.327874 -9.867138)
		(stroke
			(width 0.2)
			(type default)
		)
		(layer "In8.Cu")
	)
	(gr_line
		(start 20.327874 -9.867138)
		(end 19.408648 -9.867138)
		(stroke
			(width 0.2)
			(type default)
		)
		(layer "In8.Cu")
	)
	(gr_arc
		(start 21.052536 -15.872206)
		(mid 21.43633 -15.488793)
		(end 21.05279 -15.105126)
		(stroke
			(width 0.2)
			(type default)
		)
		(layer "In8.Cu")
	)
	(gr_line
		(start 21.05279 -15.105126)
		(end 20.09521 -15.105126)
		(stroke
			(width 0.2)
			(type default)
		)
		(layer "In8.Cu")
	)
	(gr_line
		(start 21.6662 -14.20114)
		(end 22.5298 -14.20114)
		(stroke
			(width 0.2)
			(type default)
		)
		(layer "In8.Cu")
	)
	(gr_arc
		(start 21.666454 -13.43406)
		(mid 21.28266 -13.817473)
		(end 21.6662 -14.20114)
		(stroke
			(width 0.2)
			(type default)
		)
		(layer "In8.Cu")
	)
	(gr_arc
		(start 22.5298 -14.20114)
		(mid 22.91334 -13.8176)
		(end 22.5298 -13.43406)
		(stroke
			(width 0.2)
			(type default)
		)
		(layer "In8.Cu")
	)
	(gr_line
		(start 22.5298 -13.43406)
		(end 21.666454 -13.43406)
		(stroke
			(width 0.2)
			(type default)
		)
		(layer "In8.Cu")
	)
	(gr_line
		(start 23.408386 -10.634218)
		(end 24.327866 -10.634218)
		(stroke
			(width 0.2)
			(type default)
		)
		(layer "In8.Cu")
	)
	(gr_arc
		(start 23.40864 -9.867138)
		(mid 23.024846 -10.250551)
		(end 23.408386 -10.634218)
		(stroke
			(width 0.2)
			(type default)
		)
		(layer "In8.Cu")
	)
	(gr_arc
		(start 24.327866 -10.634218)
		(mid 24.711406 -10.250678)
		(end 24.327866 -9.867138)
		(stroke
			(width 0.2)
			(type default)
		)
		(layer "In8.Cu")
	)
	(gr_line
		(start 24.327866 -9.867138)
		(end 23.40864 -9.867138)
		(stroke
			(width 0.2)
			(type default)
		)
		(layer "In8.Cu")
	)
	(gr_line
		(start 25.4127 -14.20114)
		(end 26.276046 -14.20114)
		(stroke
			(width 0.2)
			(type default)
		)
		(layer "In8.Cu")
	)
	(gr_arc
		(start 25.4127 -13.43406)
		(mid 25.02916 -13.8176)
		(end 25.4127 -14.20114)
		(stroke
			(width 0.2)
			(type default)
		)
		(layer "In8.Cu")
	)
	(gr_arc
		(start 26.276046 -14.20114)
		(mid 26.65984 -13.817727)
		(end 26.2763 -13.43406)
		(stroke
			(width 0.2)
			(type default)
		)
		(layer "In8.Cu")
	)
	(gr_line
		(start 26.2763 -13.43406)
		(end 25.4127 -13.43406)
		(stroke
			(width 0.2)
			(type default)
		)
		(layer "In8.Cu")
	)
	(gr_line
		(start 27.408378 -10.634218)
		(end 28.327604 -10.634218)
		(stroke
			(width 0.2)
			(type default)
		)
		(layer "In8.Cu")
	)
	(gr_arc
		(start 27.408378 -9.867138)
		(mid 27.024838 -10.250678)
		(end 27.408378 -10.634218)
		(stroke
			(width 0.2)
			(type default)
		)
		(layer "In8.Cu")
	)
	(gr_arc
		(start 28.327604 -10.634218)
		(mid 28.711398 -10.250805)
		(end 28.327858 -9.867138)
		(stroke
			(width 0.2)
			(type default)
		)
		(layer "In8.Cu")
	)
	(gr_line
		(start 28.327858 -9.867138)
		(end 27.408378 -9.867138)
		(stroke
			(width 0.2)
			(type default)
		)
		(layer "In8.Cu")
	)
	(gr_line
		(start 29.4132 -14.96314)
		(end 30.276546 -14.96314)
		(stroke
			(width 0.2)
			(type default)
		)
		(layer "In8.Cu")
	)
	(gr_arc
		(start 29.4132 -14.19606)
		(mid 29.02966 -14.5796)
		(end 29.4132 -14.96314)
		(stroke
			(width 0.2)
			(type default)
		)
		(layer "In8.Cu")
	)
	(gr_arc
		(start 30.276546 -14.96314)
		(mid 30.66034 -14.579727)
		(end 30.2768 -14.19606)
		(stroke
			(width 0.2)
			(type default)
		)
		(layer "In8.Cu")
	)
	(gr_line
		(start 30.2768 -14.19606)
		(end 29.4132 -14.19606)
		(stroke
			(width 0.2)
			(type default)
		)
		(layer "In8.Cu")
	)
	(gr_line
		(start 31.40837 -10.634218)
		(end 32.327596 -10.634218)
		(stroke
			(width 0.2)
			(type default)
		)
		(layer "In8.Cu")
	)
	(gr_arc
		(start 31.40837 -9.867138)
		(mid 31.02483 -10.250678)
		(end 31.40837 -10.634218)
		(stroke
			(width 0.2)
			(type default)
		)
		(layer "In8.Cu")
	)
	(gr_arc
		(start 32.327596 -10.634218)
		(mid 32.71139 -10.250805)
		(end 32.32785 -9.867138)
		(stroke
			(width 0.2)
			(type default)
		)
		(layer "In8.Cu")
	)
	(gr_line
		(start 32.32785 -9.867138)
		(end 31.40837 -9.867138)
		(stroke
			(width 0.2)
			(type default)
		)
		(layer "In8.Cu")
	)
	(gr_line
		(start 33.4264 -14.96314)
		(end 34.289746 -14.96314)
		(stroke
			(width 0.2)
			(type default)
		)
		(layer "In8.Cu")
	)
	(gr_arc
		(start 33.4264 -14.19606)
		(mid 33.04286 -14.5796)
		(end 33.4264 -14.96314)
		(stroke
			(width 0.2)
			(type default)
		)
		(layer "In8.Cu")
	)
	(gr_arc
		(start 34.289746 -14.96314)
		(mid 34.67354 -14.579727)
		(end 34.29 -14.19606)
		(stroke
			(width 0.2)
			(type default)
		)
		(layer "In8.Cu")
	)
	(gr_line
		(start 34.29 -14.19606)
		(end 33.4264 -14.19606)
		(stroke
			(width 0.2)
			(type default)
		)
		(layer "In8.Cu")
	)
	(gr_line
		(start 35.408362 -10.634218)
		(end 36.327588 -10.634218)
		(stroke
			(width 0.2)
			(type default)
		)
		(layer "In8.Cu")
	)
	(gr_arc
		(start 35.408362 -9.867138)
		(mid 35.024822 -10.250678)
		(end 35.408362 -10.634218)
		(stroke
			(width 0.2)
			(type default)
		)
		(layer "In8.Cu")
	)
	(gr_arc
		(start 36.327588 -10.634218)
		(mid 36.711382 -10.250805)
		(end 36.327842 -9.867138)
		(stroke
			(width 0.2)
			(type default)
		)
		(layer "In8.Cu")
	)
	(gr_line
		(start 36.327842 -9.867138)
		(end 35.408362 -9.867138)
		(stroke
			(width 0.2)
			(type default)
		)
		(layer "In8.Cu")
	)
	(gr_line
		(start 37.41801 -14.20114)
		(end 38.281356 -14.20114)
		(stroke
			(width 0.2)
			(type default)
		)
		(layer "In8.Cu")
	)
	(gr_arc
		(start 37.41801 -13.43406)
		(mid 37.03447 -13.8176)
		(end 37.41801 -14.20114)
		(stroke
			(width 0.2)
			(type default)
		)
		(layer "In8.Cu")
	)
	(gr_arc
		(start 37.88664 -30.2006)
		(mid 38.27018 -30.58414)
		(end 38.65372 -30.2006)
		(stroke
			(width 0.2)
			(type default)
		)
		(layer "In8.Cu")
	)
	(gr_line
		(start 37.88664 -29.337)
		(end 37.88664 -30.2006)
		(stroke
			(width 0.2)
			(type default)
		)
		(layer "In8.Cu")
	)
	(gr_arc
		(start 38.281356 -14.20114)
		(mid 38.66515 -13.817727)
		(end 38.28161 -13.43406)
		(stroke
			(width 0.2)
			(type default)
		)
		(layer "In8.Cu")
	)
	(gr_line
		(start 38.28161 -13.43406)
		(end 37.41801 -13.43406)
		(stroke
			(width 0.2)
			(type default)
		)
		(layer "In8.Cu")
	)
	(gr_line
		(start 38.65372 -30.2006)
		(end 38.65372 -29.337254)
		(stroke
			(width 0.2)
			(type default)
		)
		(layer "In8.Cu")
	)
	(gr_arc
		(start 38.65372 -29.337254)
		(mid 38.270307 -28.95346)
		(end 37.88664 -29.337)
		(stroke
			(width 0.2)
			(type default)
		)
		(layer "In8.Cu")
	)
	(gr_line
		(start 39.408354 -10.634218)
		(end 40.327834 -10.634218)
		(stroke
			(width 0.2)
			(type default)
		)
		(layer "In8.Cu")
	)
	(gr_arc
		(start 39.408608 -9.867138)
		(mid 39.024814 -10.250551)
		(end 39.408354 -10.634218)
		(stroke
			(width 0.2)
			(type default)
		)
		(layer "In8.Cu")
	)
	(gr_line
		(start 39.44366 -12.73048)
		(end 40.40124 -12.73048)
		(stroke
			(width 0.2)
			(type default)
		)
		(layer "In8.Cu")
	)
	(gr_arc
		(start 39.443914 -11.9634)
		(mid 39.06012 -12.346813)
		(end 39.44366 -12.73048)
		(stroke
			(width 0.2)
			(type default)
		)
		(layer "In8.Cu")
	)
	(gr_arc
		(start 40.327834 -10.634218)
		(mid 40.711374 -10.250678)
		(end 40.327834 -9.867138)
		(stroke
			(width 0.2)
			(type default)
		)
		(layer "In8.Cu")
	)
	(gr_line
		(start 40.327834 -9.867138)
		(end 39.408608 -9.867138)
		(stroke
			(width 0.2)
			(type default)
		)
		(layer "In8.Cu")
	)
	(gr_arc
		(start 40.40124 -12.73048)
		(mid 40.78478 -12.34694)
		(end 40.40124 -11.9634)
		(stroke
			(width 0.2)
			(type default)
		)
		(layer "In8.Cu")
	)
	(gr_line
		(start 40.40124 -11.9634)
		(end 39.443914 -11.9634)
		(stroke
			(width 0.2)
			(type default)
		)
		(layer "In8.Cu")
	)
	(gr_line
		(start 41.418002 -14.20114)
		(end 42.281348 -14.20114)
		(stroke
			(width 0.2)
			(type default)
		)
		(layer "In8.Cu")
	)
	(gr_arc
		(start 41.418002 -13.43406)
		(mid 41.034462 -13.8176)
		(end 41.418002 -14.20114)
		(stroke
			(width 0.2)
			(type default)
		)
		(layer "In8.Cu")
	)
	(gr_arc
		(start 42.281348 -14.20114)
		(mid 42.665142 -13.817727)
		(end 42.281602 -13.43406)
		(stroke
			(width 0.2)
			(type default)
		)
		(layer "In8.Cu")
	)
	(gr_line
		(start 42.281602 -13.43406)
		(end 41.418002 -13.43406)
		(stroke
			(width 0.2)
			(type default)
		)
		(layer "In8.Cu")
	)
	(gr_line
		(start 42.45356 -44.5389)
		(end 43.41114 -44.5389)
		(stroke
			(width 0.2)
			(type default)
		)
		(layer "In8.Cu")
	)
	(gr_arc
		(start 42.453814 -43.77182)
		(mid 42.07002 -44.155233)
		(end 42.45356 -44.5389)
		(stroke
			(width 0.2)
			(type default)
		)
		(layer "In8.Cu")
	)
	(gr_line
		(start 43.25366 -12.98194)
		(end 44.210986 -12.98194)
		(stroke
			(width 0.2)
			(type default)
		)
		(layer "In8.Cu")
	)
	(gr_arc
		(start 43.25366 -12.21486)
		(mid 42.87012 -12.5984)
		(end 43.25366 -12.98194)
		(stroke
			(width 0.2)
			(type default)
		)
		(layer "In8.Cu")
	)
	(gr_line
		(start 43.408346 -10.634218)
		(end 44.327826 -10.634218)
		(stroke
			(width 0.2)
			(type default)
		)
		(layer "In8.Cu")
	)
	(gr_arc
		(start 43.4086 -9.867138)
		(mid 43.024806 -10.250551)
		(end 43.408346 -10.634218)
		(stroke
			(width 0.2)
			(type default)
		)
		(layer "In8.Cu")
	)
	(gr_arc
		(start 43.41114 -44.5389)
		(mid 43.79468 -44.15536)
		(end 43.41114 -43.77182)
		(stroke
			(width 0.2)
			(type default)
		)
		(layer "In8.Cu")
	)
	(gr_line
		(start 43.41114 -43.77182)
		(end 42.453814 -43.77182)
		(stroke
			(width 0.2)
			(type default)
		)
		(layer "In8.Cu")
	)
	(gr_arc
		(start 44.210986 -12.98194)
		(mid 44.59478 -12.598527)
		(end 44.21124 -12.21486)
		(stroke
			(width 0.2)
			(type default)
		)
		(layer "In8.Cu")
	)
	(gr_line
		(start 44.21124 -12.21486)
		(end 43.25366 -12.21486)
		(stroke
			(width 0.2)
			(type default)
		)
		(layer "In8.Cu")
	)
	(gr_arc
		(start 44.327826 -10.634218)
		(mid 44.711366 -10.250678)
		(end 44.327826 -9.867138)
		(stroke
			(width 0.2)
			(type default)
		)
		(layer "In8.Cu")
	)
	(gr_line
		(start 44.327826 -9.867138)
		(end 43.4086 -9.867138)
		(stroke
			(width 0.2)
			(type default)
		)
		(layer "In8.Cu")
	)
	(gr_line
		(start 44.98975 -44.30014)
		(end 45.947838 -44.32173)
		(stroke
			(width 0.2)
			(type default)
		)
		(layer "In8.Cu")
	)
	(gr_arc
		(start 45.007276 -43.53306)
		(mid 44.615103 -43.907837)
		(end 44.98975 -44.30014)
		(stroke
			(width 0.2)
			(type default)
		)
		(layer "In8.Cu")
	)
	(gr_line
		(start 45.466 -14.1986)
		(end 46.176946 -14.1986)
		(stroke
			(width 0.2)
			(type default)
		)
		(layer "In8.Cu")
	)
	(gr_arc
		(start 45.466 -13.4366)
		(mid 45.085 -13.8176)
		(end 45.466 -14.1986)
		(stroke
			(width 0.2)
			(type default)
		)
		(layer "In8.Cu")
	)
	(gr_arc
		(start 45.947838 -44.32173)
		(mid 46.340014 -43.946826)
		(end 45.96511 -43.55465)
		(stroke
			(width 0.2)
			(type default)
		)
		(layer "In8.Cu")
	)
	(gr_line
		(start 45.96511 -43.55465)
		(end 45.007276 -43.53306)
		(stroke
			(width 0.2)
			(type default)
		)
		(layer "In8.Cu")
	)
	(gr_arc
		(start 46.176946 -14.1986)
		(mid 46.5582 -13.817727)
		(end 46.1772 -13.4366)
		(stroke
			(width 0.2)
			(type default)
		)
		(layer "In8.Cu")
	)
	(gr_line
		(start 46.1772 -13.4366)
		(end 45.466 -13.4366)
		(stroke
			(width 0.2)
			(type default)
		)
		(layer "In8.Cu")
	)
	(gr_line
		(start 47.408338 -10.634218)
		(end 48.327818 -10.634218)
		(stroke
			(width 0.2)
			(type default)
		)
		(layer "In8.Cu")
	)
	(gr_arc
		(start 47.408592 -9.867138)
		(mid 47.024798 -10.250551)
		(end 47.408338 -10.634218)
		(stroke
			(width 0.2)
			(type default)
		)
		(layer "In8.Cu")
	)
	(gr_line
		(start 47.46371 -14.1732)
		(end 48.183546 -14.1732)
		(stroke
			(width 0.2)
			(type default)
		)
		(layer "In8.Cu")
	)
	(gr_arc
		(start 47.46371 -13.4112)
		(mid 47.08271 -13.7922)
		(end 47.46371 -14.1732)
		(stroke
			(width 0.2)
			(type default)
		)
		(layer "In8.Cu")
	)
	(gr_arc
		(start 48.183546 -14.1732)
		(mid 48.5648 -13.792327)
		(end 48.1838 -13.4112)
		(stroke
			(width 0.2)
			(type default)
		)
		(layer "In8.Cu")
	)
	(gr_line
		(start 48.1838 -13.4112)
		(end 47.46371 -13.4112)
		(stroke
			(width 0.2)
			(type default)
		)
		(layer "In8.Cu")
	)
	(gr_arc
		(start 48.327818 -10.634218)
		(mid 48.711358 -10.250678)
		(end 48.327818 -9.867138)
		(stroke
			(width 0.2)
			(type default)
		)
		(layer "In8.Cu")
	)
	(gr_line
		(start 48.327818 -9.867138)
		(end 47.408592 -9.867138)
		(stroke
			(width 0.2)
			(type default)
		)
		(layer "In8.Cu")
	)
	(gr_line
		(start 49.176432 -38.313614)
		(end 49.81321 -38.892226)
		(stroke
			(width 0.2)
			(type default)
		)
		(layer "In8.Cu")
	)
	(gr_line
		(start 49.29505 -20.79498)
		(end 50.25263 -20.79498)
		(stroke
			(width 0.2)
			(type default)
		)
		(layer "In8.Cu")
	)
	(gr_arc
		(start 49.295304 -20.0279)
		(mid 48.91151 -20.411313)
		(end 49.29505 -20.79498)
		(stroke
			(width 0.2)
			(type default)
		)
		(layer "In8.Cu")
	)
	(gr_line
		(start 49.38903 -10.64387)
		(end 50.310542 -10.64387)
		(stroke
			(width 0.2)
			(type default)
		)
		(layer "In8.Cu")
	)
	(gr_arc
		(start 49.389284 -9.87679)
		(mid 49.00549 -10.260203)
		(end 49.38903 -10.64387)
		(stroke
			(width 0.2)
			(type default)
		)
		(layer "In8.Cu")
	)
	(gr_line
		(start 49.4538 -14.1986)
		(end 50.2158 -14.1986)
		(stroke
			(width 0.2)
			(type default)
		)
		(layer "In8.Cu")
	)
	(gr_arc
		(start 49.454054 -13.4366)
		(mid 49.0728 -13.817473)
		(end 49.4538 -14.1986)
		(stroke
			(width 0.2)
			(type default)
		)
		(layer "In8.Cu")
	)
	(gr_arc
		(start 49.692052 -37.74567)
		(mid 49.15027 -37.771832)
		(end 49.176432 -38.313614)
		(stroke
			(width 0.2)
			(type default)
		)
		(layer "In8.Cu")
	)
	(gr_arc
		(start 49.81321 -38.892226)
		(mid 50.356403 -38.869633)
		(end 50.33137 -38.326568)
		(stroke
			(width 0.2)
			(type default)
		)
		(layer "In8.Cu")
	)
	(gr_arc
		(start 50.2158 -14.1986)
		(mid 50.5968 -13.8176)
		(end 50.2158 -13.4366)
		(stroke
			(width 0.2)
			(type default)
		)
		(layer "In8.Cu")
	)
	(gr_line
		(start 50.2158 -13.4366)
		(end 49.454054 -13.4366)
		(stroke
			(width 0.2)
			(type default)
		)
		(layer "In8.Cu")
	)
	(gr_arc
		(start 50.25263 -20.79498)
		(mid 50.63617 -20.41144)
		(end 50.25263 -20.0279)
		(stroke
			(width 0.2)
			(type default)
		)
		(layer "In8.Cu")
	)
	(gr_line
		(start 50.25263 -20.0279)
		(end 49.295304 -20.0279)
		(stroke
			(width 0.2)
			(type default)
		)
		(layer "In8.Cu")
	)
	(gr_arc
		(start 50.262028 -48.49495)
		(mid 50.63998 -48.884078)
		(end 51.029108 -48.506126)
		(stroke
			(width 0.2)
			(type default)
		)
		(layer "In8.Cu")
	)
	(gr_line
		(start 50.274474 -47.63135)
		(end 50.262028 -48.49495)
		(stroke
			(width 0.2)
			(type default)
		)
		(layer "In8.Cu")
	)
	(gr_arc
		(start 50.310542 -10.64387)
		(mid 50.694082 -10.26033)
		(end 50.310542 -9.87679)
		(stroke
			(width 0.2)
			(type default)
		)
		(layer "In8.Cu")
	)
	(gr_line
		(start 50.310542 -9.87679)
		(end 49.389284 -9.87679)
		(stroke
			(width 0.2)
			(type default)
		)
		(layer "In8.Cu")
	)
	(gr_line
		(start 50.33137 -38.326568)
		(end 49.692052 -37.74567)
		(stroke
			(width 0.2)
			(type default)
		)
		(layer "In8.Cu")
	)
	(gr_line
		(start 51.029108 -48.506126)
		(end 51.041554 -47.64278)
		(stroke
			(width 0.2)
			(type default)
		)
		(layer "In8.Cu")
	)
	(gr_arc
		(start 51.041554 -47.64278)
		(mid 50.663729 -47.253654)
		(end 50.274474 -47.63135)
		(stroke
			(width 0.2)
			(type default)
		)
		(layer "In8.Cu")
	)
	(gr_line
		(start 51.282346 -34.47034)
		(end 52.16652 -34.47034)
		(stroke
			(width 0.2)
			(type default)
		)
		(layer "In8.Cu")
	)
	(gr_arc
		(start 51.2826 -33.70326)
		(mid 50.898806 -34.086673)
		(end 51.282346 -34.47034)
		(stroke
			(width 0.2)
			(type default)
		)
		(layer "In8.Cu")
	)
	(gr_line
		(start 52.1462 -14.32814)
		(end 53.009546 -14.32814)
		(stroke
			(width 0.2)
			(type default)
		)
		(layer "In8.Cu")
	)
	(gr_arc
		(start 52.1462 -13.56106)
		(mid 51.76266 -13.9446)
		(end 52.1462 -14.32814)
		(stroke
			(width 0.2)
			(type default)
		)
		(layer "In8.Cu")
	)
	(gr_arc
		(start 52.16652 -34.47034)
		(mid 52.55006 -34.0868)
		(end 52.16652 -33.70326)
		(stroke
			(width 0.2)
			(type default)
		)
		(layer "In8.Cu")
	)
	(gr_line
		(start 52.16652 -33.70326)
		(end 51.2826 -33.70326)
		(stroke
			(width 0.2)
			(type default)
		)
		(layer "In8.Cu")
	)
	(gr_arc
		(start 52.52339 -34.93262)
		(mid 52.14112 -35.31743)
		(end 52.52593 -35.6997)
		(stroke
			(width 0.2)
			(type default)
		)
		(layer "In8.Cu")
	)
	(gr_line
		(start 52.52593 -35.6997)
		(end 53.479954 -35.696652)
		(stroke
			(width 0.2)
			(type default)
		)
		(layer "In8.Cu")
	)
	(gr_arc
		(start 52.768246 -29.826966)
		(mid 53.151659 -30.21076)
		(end 53.535326 -29.82722)
		(stroke
			(width 0.2)
			(type default)
		)
		(layer "In8.Cu")
	)
	(gr_line
		(start 52.768246 -28.897834)
		(end 52.768246 -29.826966)
		(stroke
			(width 0.2)
			(type default)
		)
		(layer "In8.Cu")
	)
	(gr_arc
		(start 53.009546 -14.32814)
		(mid 53.39334 -13.944727)
		(end 53.0098 -13.56106)
		(stroke
			(width 0.2)
			(type default)
		)
		(layer "In8.Cu")
	)
	(gr_line
		(start 53.0098 -13.56106)
		(end 52.1462 -13.56106)
		(stroke
			(width 0.2)
			(type default)
		)
		(layer "In8.Cu")
	)
	(gr_line
		(start 53.477668 -34.929572)
		(end 52.52339 -34.93262)
		(stroke
			(width 0.2)
			(type default)
		)
		(layer "In8.Cu")
	)
	(gr_arc
		(start 53.479954 -35.696652)
		(mid 53.862478 -35.311969)
		(end 53.477668 -34.929572)
		(stroke
			(width 0.2)
			(type default)
		)
		(layer "In8.Cu")
	)
	(gr_line
		(start 53.535326 -29.82722)
		(end 53.535326 -28.897834)
		(stroke
			(width 0.2)
			(type default)
		)
		(layer "In8.Cu")
	)
	(gr_arc
		(start 53.535326 -28.897834)
		(mid 53.151786 -28.514294)
		(end 52.768246 -28.897834)
		(stroke
			(width 0.2)
			(type default)
		)
		(layer "In8.Cu")
	)
	(gr_line
		(start 59.078114 -11.320018)
		(end 59.997594 -11.320018)
		(stroke
			(width 0.2)
			(type default)
		)
		(layer "In8.Cu")
	)
	(gr_arc
		(start 59.078368 -10.552938)
		(mid 58.694574 -10.936351)
		(end 59.078114 -11.320018)
		(stroke
			(width 0.2)
			(type default)
		)
		(layer "In8.Cu")
	)
	(gr_arc
		(start 59.27471 -36.33724)
		(mid 59.65825 -36.72078)
		(end 60.04179 -36.33724)
		(stroke
			(width 0.2)
			(type default)
		)
		(layer "In8.Cu")
	)
	(gr_line
		(start 59.27471 -35.37966)
		(end 59.27471 -36.33724)
		(stroke
			(width 0.2)
			(type default)
		)
		(layer "In8.Cu")
	)
	(gr_arc
		(start 59.997594 -11.320018)
		(mid 60.381134 -10.936478)
		(end 59.997594 -10.552938)
		(stroke
			(width 0.2)
			(type default)
		)
		(layer "In8.Cu")
	)
	(gr_line
		(start 59.997594 -10.552938)
		(end 59.078368 -10.552938)
		(stroke
			(width 0.2)
			(type default)
		)
		(layer "In8.Cu")
	)
	(gr_line
		(start 60.04179 -36.33724)
		(end 60.04179 -35.379914)
		(stroke
			(width 0.2)
			(type default)
		)
		(layer "In8.Cu")
	)
	(gr_arc
		(start 60.04179 -35.379914)
		(mid 59.658377 -34.99612)
		(end 59.27471 -35.37966)
		(stroke
			(width 0.2)
			(type default)
		)
		(layer "In8.Cu")
	)
	(gr_line
		(start 60.551822 -45.897038)
		(end 60.607448 -46.75886)
		(stroke
			(width 0.2)
			(type default)
		)
		(layer "In8.Cu")
	)
	(gr_arc
		(start 60.607448 -46.75886)
		(mid 61.014864 -47.117)
		(end 61.373004 -46.709584)
		(stroke
			(width 0.2)
			(type default)
		)
		(layer "In8.Cu")
	)
	(gr_arc
		(start 61.317378 -45.848016)
		(mid 60.910088 -45.489868)
		(end 60.551822 -45.897038)
		(stroke
			(width 0.2)
			(type default)
		)
		(layer "In8.Cu")
	)
	(gr_line
		(start 61.373004 -46.709584)
		(end 61.317378 -45.848016)
		(stroke
			(width 0.2)
			(type default)
		)
		(layer "In8.Cu")
	)
	(gr_line
		(start 61.40831 -10.634218)
		(end 62.327536 -10.634218)
		(stroke
			(width 0.2)
			(type default)
		)
		(layer "In8.Cu")
	)
	(gr_arc
		(start 61.40831 -9.867138)
		(mid 61.02477 -10.250678)
		(end 61.40831 -10.634218)
		(stroke
			(width 0.2)
			(type default)
		)
		(layer "In8.Cu")
	)
	(gr_arc
		(start 62.327536 -10.634218)
		(mid 62.71133 -10.250805)
		(end 62.32779 -9.867138)
		(stroke
			(width 0.2)
			(type default)
		)
		(layer "In8.Cu")
	)
	(gr_line
		(start 62.32779 -9.867138)
		(end 61.40831 -9.867138)
		(stroke
			(width 0.2)
			(type default)
		)
		(layer "In8.Cu")
	)
	(gr_line
		(start 63.627 -15.0876)
		(end 64.389 -15.0876)
		(stroke
			(width 0.2)
			(type default)
		)
		(layer "In8.Cu")
	)
	(gr_arc
		(start 63.627254 -14.3256)
		(mid 63.246 -14.706473)
		(end 63.627 -15.0876)
		(stroke
			(width 0.2)
			(type default)
		)
		(layer "In8.Cu")
	)
	(gr_arc
		(start 64.389 -15.0876)
		(mid 64.77 -14.7066)
		(end 64.389 -14.3256)
		(stroke
			(width 0.2)
			(type default)
		)
		(layer "In8.Cu")
	)
	(gr_line
		(start 64.389 -14.3256)
		(end 63.627254 -14.3256)
		(stroke
			(width 0.2)
			(type default)
		)
		(layer "In8.Cu")
	)
	(gr_line
		(start 65.786 -15.0622)
		(end 66.547746 -15.0622)
		(stroke
			(width 0.2)
			(type default)
		)
		(layer "In8.Cu")
	)
	(gr_arc
		(start 65.786 -14.3002)
		(mid 65.405 -14.6812)
		(end 65.786 -15.0622)
		(stroke
			(width 0.2)
			(type default)
		)
		(layer "In8.Cu")
	)
	(gr_arc
		(start 66.547746 -15.0622)
		(mid 66.929 -14.681327)
		(end 66.548 -14.3002)
		(stroke
			(width 0.2)
			(type default)
		)
		(layer "In8.Cu")
	)
	(gr_line
		(start 66.548 -14.3002)
		(end 65.786 -14.3002)
		(stroke
			(width 0.2)
			(type default)
		)
		(layer "In8.Cu")
	)
	(gr_line
		(start 67.34556 -10.668)
		(end 68.302886 -10.668)
		(stroke
			(width 0.2)
			(type default)
		)
		(layer "In8.Cu")
	)
	(gr_arc
		(start 67.34556 -9.90092)
		(mid 66.96202 -10.28446)
		(end 67.34556 -10.668)
		(stroke
			(width 0.2)
			(type default)
		)
		(layer "In8.Cu")
	)
	(gr_line
		(start 68.072 -14.98854)
		(end 68.834 -14.98854)
		(stroke
			(width 0.2)
			(type default)
		)
		(layer "In8.Cu")
	)
	(gr_arc
		(start 68.072254 -14.22146)
		(mid 67.68846 -14.604873)
		(end 68.072 -14.98854)
		(stroke
			(width 0.2)
			(type default)
		)
		(layer "In8.Cu")
	)
	(gr_arc
		(start 68.302886 -10.668)
		(mid 68.68668 -10.284587)
		(end 68.30314 -9.90092)
		(stroke
			(width 0.2)
			(type default)
		)
		(layer "In8.Cu")
	)
	(gr_line
		(start 68.30314 -9.90092)
		(end 67.34556 -9.90092)
		(stroke
			(width 0.2)
			(type default)
		)
		(layer "In8.Cu")
	)
	(gr_arc
		(start 68.75145 -28.403296)
		(mid 69.133212 -28.788614)
		(end 69.51853 -28.406852)
		(stroke
			(width 0.2)
			(type default)
		)
		(layer "In8.Cu")
	)
	(gr_line
		(start 68.75526 -27.51963)
		(end 68.75145 -28.403296)
		(stroke
			(width 0.2)
			(type default)
		)
		(layer "In8.Cu")
	)
	(gr_arc
		(start 68.834 -14.98854)
		(mid 69.21754 -14.605)
		(end 68.834 -14.22146)
		(stroke
			(width 0.2)
			(type default)
		)
		(layer "In8.Cu")
	)
	(gr_line
		(start 68.834 -14.22146)
		(end 68.072254 -14.22146)
		(stroke
			(width 0.2)
			(type default)
		)
		(layer "In8.Cu")
	)
	(gr_line
		(start 69.51853 -28.406852)
		(end 69.52234 -27.52344)
		(stroke
			(width 0.2)
			(type default)
		)
		(layer "In8.Cu")
	)
	(gr_arc
		(start 69.52234 -27.52344)
		(mid 69.140705 -27.138123)
		(end 68.75526 -27.51963)
		(stroke
			(width 0.2)
			(type default)
		)
		(layer "In8.Cu")
	)
	(gr_line
		(start 71.370952 -10.668)
		(end 72.328532 -10.668)
		(stroke
			(width 0.2)
			(type default)
		)
		(layer "In8.Cu")
	)
	(gr_arc
		(start 71.371206 -9.90092)
		(mid 70.987412 -10.284333)
		(end 71.370952 -10.668)
		(stroke
			(width 0.2)
			(type default)
		)
		(layer "In8.Cu")
	)
	(gr_arc
		(start 72.328532 -10.668)
		(mid 72.712072 -10.28446)
		(end 72.328532 -9.90092)
		(stroke
			(width 0.2)
			(type default)
		)
		(layer "In8.Cu")
	)
	(gr_line
		(start 72.328532 -9.90092)
		(end 71.371206 -9.90092)
		(stroke
			(width 0.2)
			(type default)
		)
		(layer "In8.Cu")
	)
	(gr_line
		(start 72.8472 -15.09014)
		(end 73.7108 -15.09014)
		(stroke
			(width 0.2)
			(type default)
		)
		(layer "In8.Cu")
	)
	(gr_arc
		(start 72.847454 -14.32306)
		(mid 72.46366 -14.706473)
		(end 72.8472 -15.09014)
		(stroke
			(width 0.2)
			(type default)
		)
		(layer "In8.Cu")
	)
	(gr_arc
		(start 73.7108 -15.09014)
		(mid 74.09434 -14.7066)
		(end 73.7108 -14.32306)
		(stroke
			(width 0.2)
			(type default)
		)
		(layer "In8.Cu")
	)
	(gr_line
		(start 73.7108 -14.32306)
		(end 72.847454 -14.32306)
		(stroke
			(width 0.2)
			(type default)
		)
		(layer "In8.Cu")
	)
	(gr_line
		(start 75.370944 -10.668)
		(end 76.328524 -10.668)
		(stroke
			(width 0.2)
			(type default)
		)
		(layer "In8.Cu")
	)
	(gr_arc
		(start 75.371198 -9.90092)
		(mid 74.987404 -10.284333)
		(end 75.370944 -10.668)
		(stroke
			(width 0.2)
			(type default)
		)
		(layer "In8.Cu")
	)
	(gr_arc
		(start 76.328524 -10.668)
		(mid 76.712064 -10.28446)
		(end 76.328524 -9.90092)
		(stroke
			(width 0.2)
			(type default)
		)
		(layer "In8.Cu")
	)
	(gr_line
		(start 76.328524 -9.90092)
		(end 75.371198 -9.90092)
		(stroke
			(width 0.2)
			(type default)
		)
		(layer "In8.Cu")
	)
	(gr_line
		(start 77.4192 -14.96314)
		(end 78.2828 -14.96314)
		(stroke
			(width 0.2)
			(type default)
		)
		(layer "In8.Cu")
	)
	(gr_arc
		(start 77.419454 -14.19606)
		(mid 77.03566 -14.579473)
		(end 77.4192 -14.96314)
		(stroke
			(width 0.2)
			(type default)
		)
		(layer "In8.Cu")
	)
	(gr_arc
		(start 77.972666 -29.55925)
		(mid 77.633576 -29.90596)
		(end 77.980286 -30.24505)
		(stroke
			(width 0.2)
			(type default)
		)
		(layer "In8.Cu")
	)
	(gr_line
		(start 77.980286 -30.24505)
		(end 78.538832 -30.2387)
		(stroke
			(width 0.2)
			(type default)
		)
		(layer "In8.Cu")
	)
	(gr_line
		(start 78.090014 -31.508446)
		(end 78.648814 -31.53283)
		(stroke
			(width 0.2)
			(type default)
		)
		(layer "In8.Cu")
	)
	(gr_arc
		(start 78.12024 -30.823154)
		(mid 77.762614 -31.150687)
		(end 78.090014 -31.508446)
		(stroke
			(width 0.2)
			(type default)
		)
		(layer "In8.Cu")
	)
	(gr_arc
		(start 78.2828 -14.96314)
		(mid 78.66634 -14.5796)
		(end 78.2828 -14.19606)
		(stroke
			(width 0.2)
			(type default)
		)
		(layer "In8.Cu")
	)
	(gr_line
		(start 78.2828 -14.19606)
		(end 77.419454 -14.19606)
		(stroke
			(width 0.2)
			(type default)
		)
		(layer "In8.Cu")
	)
	(gr_line
		(start 78.531466 -29.5529)
		(end 77.972666 -29.55925)
		(stroke
			(width 0.2)
			(type default)
		)
		(layer "In8.Cu")
	)
	(gr_arc
		(start 78.538832 -30.2387)
		(mid 78.878175 -29.892117)
		(end 78.531466 -29.5529)
		(stroke
			(width 0.2)
			(type default)
		)
		(layer "In8.Cu")
	)
	(gr_arc
		(start 78.648814 -31.53283)
		(mid 79.006446 -31.20517)
		(end 78.678786 -30.847538)
		(stroke
			(width 0.2)
			(type default)
		)
		(layer "In8.Cu")
	)
	(gr_line
		(start 78.678786 -30.847538)
		(end 78.12024 -30.823154)
		(stroke
			(width 0.2)
			(type default)
		)
		(layer "In8.Cu")
	)
	(gr_line
		(start 79.370936 -10.7188)
		(end 80.328516 -10.7188)
		(stroke
			(width 0.2)
			(type default)
		)
		(layer "In8.Cu")
	)
	(gr_arc
		(start 79.37119 -9.95172)
		(mid 78.987396 -10.335133)
		(end 79.370936 -10.7188)
		(stroke
			(width 0.2)
			(type default)
		)
		(layer "In8.Cu")
	)
	(gr_line
		(start 80.2132 -14.96314)
		(end 81.076546 -14.96314)
		(stroke
			(width 0.2)
			(type default)
		)
		(layer "In8.Cu")
	)
	(gr_arc
		(start 80.2132 -14.19606)
		(mid 79.82966 -14.5796)
		(end 80.2132 -14.96314)
		(stroke
			(width 0.2)
			(type default)
		)
		(layer "In8.Cu")
	)
	(gr_arc
		(start 80.2259 -54.685946)
		(mid 80.568673 -55.0291)
		(end 80.9117 -54.6862)
		(stroke
			(width 0.2)
			(type default)
		)
		(layer "In8.Cu")
	)
	(gr_line
		(start 80.2259 -54.1274)
		(end 80.2259 -54.685946)
		(stroke
			(width 0.2)
			(type default)
		)
		(layer "In8.Cu")
	)
	(gr_line
		(start 80.264 -60.7187)
		(end 81.0514 -60.7187)
		(stroke
			(width 0.2)
			(type default)
		)
		(layer "In8.Cu")
	)
	(gr_arc
		(start 80.264254 -60.0329)
		(mid 79.9211 -60.375673)
		(end 80.264 -60.7187)
		(stroke
			(width 0.2)
			(type default)
		)
		(layer "In8.Cu")
	)
	(gr_arc
		(start 80.328516 -10.7188)
		(mid 80.712056 -10.33526)
		(end 80.328516 -9.95172)
		(stroke
			(width 0.2)
			(type default)
		)
		(layer "In8.Cu")
	)
	(gr_line
		(start 80.328516 -9.95172)
		(end 79.37119 -9.95172)
		(stroke
			(width 0.2)
			(type default)
		)
		(layer "In8.Cu")
	)
	(gr_line
		(start 80.9117 -54.6862)
		(end 80.9117 -54.1274)
		(stroke
			(width 0.2)
			(type default)
		)
		(layer "In8.Cu")
	)
	(gr_arc
		(start 80.9117 -54.1274)
		(mid 80.5688 -53.7845)
		(end 80.2259 -54.1274)
		(stroke
			(width 0.2)
			(type default)
		)
		(layer "In8.Cu")
	)
	(gr_arc
		(start 81.0514 -60.7187)
		(mid 81.3943 -60.3758)
		(end 81.0514 -60.0329)
		(stroke
			(width 0.2)
			(type default)
		)
		(layer "In8.Cu")
	)
	(gr_line
		(start 81.0514 -60.0329)
		(end 80.264254 -60.0329)
		(stroke
			(width 0.2)
			(type default)
		)
		(layer "In8.Cu")
	)
	(gr_arc
		(start 81.076546 -14.96314)
		(mid 81.46034 -14.579727)
		(end 81.0768 -14.19606)
		(stroke
			(width 0.2)
			(type default)
		)
		(layer "In8.Cu")
	)
	(gr_line
		(start 81.0768 -14.19606)
		(end 80.2132 -14.19606)
		(stroke
			(width 0.2)
			(type default)
		)
		(layer "In8.Cu")
	)
	(gr_arc
		(start 81.3435 -53.593746)
		(mid 81.686273 -53.9369)
		(end 82.0293 -53.594)
		(stroke
			(width 0.2)
			(type default)
		)
		(layer "In8.Cu")
	)
	(gr_line
		(start 81.3435 -53.0098)
		(end 81.3435 -53.593746)
		(stroke
			(width 0.2)
			(type default)
		)
		(layer "In8.Cu")
	)
	(gr_line
		(start 82.0293 -53.594)
		(end 82.0293 -53.0098)
		(stroke
			(width 0.2)
			(type default)
		)
		(layer "In8.Cu")
	)
	(gr_arc
		(start 82.0293 -53.0098)
		(mid 81.6864 -52.6669)
		(end 81.3435 -53.0098)
		(stroke
			(width 0.2)
			(type default)
		)
		(layer "In8.Cu")
	)
	(gr_line
		(start 82.296 -14.32814)
		(end 83.1596 -14.32814)
		(stroke
			(width 0.2)
			(type default)
		)
		(layer "In8.Cu")
	)
	(gr_arc
		(start 82.296254 -13.56106)
		(mid 81.91246 -13.944473)
		(end 82.296 -14.32814)
		(stroke
			(width 0.2)
			(type default)
		)
		(layer "In8.Cu")
	)
	(gr_arc
		(start 82.803746 -55.65902)
		(mid 82.83702 -56.146446)
		(end 83.324446 -56.113172)
		(stroke
			(width 0.2)
			(type default)
		)
		(layer "In8.Cu")
	)
	(gr_arc
		(start 83.1596 -14.32814)
		(mid 83.54314 -13.9446)
		(end 83.1596 -13.56106)
		(stroke
			(width 0.2)
			(type default)
		)
		(layer "In8.Cu")
	)
	(gr_line
		(start 83.1596 -13.56106)
		(end 82.296254 -13.56106)
		(stroke
			(width 0.2)
			(type default)
		)
		(layer "In8.Cu")
	)
	(gr_line
		(start 83.18119 -55.226204)
		(end 82.803746 -55.65902)
		(stroke
			(width 0.2)
			(type default)
		)
		(layer "In8.Cu")
	)
	(gr_arc
		(start 83.309968 -59.661806)
		(mid 83.308952 -60.146946)
		(end 83.794092 -60.147962)
		(stroke
			(width 0.2)
			(type default)
		)
		(layer "In8.Cu")
	)
	(gr_line
		(start 83.324446 -56.113172)
		(end 83.701636 -55.68061)
		(stroke
			(width 0.2)
			(type default)
		)
		(layer "In8.Cu")
	)
	(gr_line
		(start 83.388962 -10.79627)
		(end 84.310474 -10.79627)
		(stroke
			(width 0.2)
			(type default)
		)
		(layer "In8.Cu")
	)
	(gr_arc
		(start 83.389216 -10.02919)
		(mid 83.005422 -10.412603)
		(end 83.388962 -10.79627)
		(stroke
			(width 0.2)
			(type default)
		)
		(layer "In8.Cu")
	)
	(gr_arc
		(start 83.701636 -55.68061)
		(mid 83.668625 -55.193446)
		(end 83.18119 -55.226204)
		(stroke
			(width 0.2)
			(type default)
		)
		(layer "In8.Cu")
	)
	(gr_line
		(start 83.794092 -60.147962)
		(end 84.348828 -59.595258)
		(stroke
			(width 0.2)
			(type default)
		)
		(layer "In8.Cu")
	)
	(gr_line
		(start 83.868006 -59.106054)
		(end 83.309968 -59.661806)
		(stroke
			(width 0.2)
			(type default)
		)
		(layer "In8.Cu")
	)
	(gr_arc
		(start 83.885024 -54.567836)
		(mid 84.22386 -54.91988)
		(end 84.575904 -54.581044)
		(stroke
			(width 0.2)
			(type default)
		)
		(layer "In8.Cu")
	)
	(gr_line
		(start 83.895692 -54.009036)
		(end 83.885024 -54.567836)
		(stroke
			(width 0.2)
			(type default)
		)
		(layer "In8.Cu")
	)
	(gr_arc
		(start 84.310474 -10.79627)
		(mid 84.694014 -10.41273)
		(end 84.310474 -10.02919)
		(stroke
			(width 0.2)
			(type default)
		)
		(layer "In8.Cu")
	)
	(gr_line
		(start 84.310474 -10.02919)
		(end 83.389216 -10.02919)
		(stroke
			(width 0.2)
			(type default)
		)
		(layer "In8.Cu")
	)
	(gr_arc
		(start 84.348828 -59.595258)
		(mid 84.354625 -59.108766)
		(end 83.868006 -59.106054)
		(stroke
			(width 0.2)
			(type default)
		)
		(layer "In8.Cu")
	)
	(gr_line
		(start 84.575904 -54.581044)
		(end 84.586572 -54.022498)
		(stroke
			(width 0.2)
			(type default)
		)
		(layer "In8.Cu")
	)
	(gr_arc
		(start 84.586572 -54.022498)
		(mid 84.247863 -53.670456)
		(end 83.895692 -54.009036)
		(stroke
			(width 0.2)
			(type default)
		)
		(layer "In8.Cu")
	)
	(gr_arc
		(start 85.330538 -55.356506)
		(mid 85.670517 -55.707536)
		(end 86.021418 -55.367428)
		(stroke
			(width 0.2)
			(type default)
		)
		(layer "In8.Cu")
	)
	(gr_line
		(start 85.339174 -54.79034)
		(end 85.330538 -55.356506)
		(stroke
			(width 0.2)
			(type default)
		)
		(layer "In8.Cu")
	)
	(gr_arc
		(start 85.741764 -53.758592)
		(mid 86.080727 -54.110638)
		(end 86.432644 -53.771546)
		(stroke
			(width 0.2)
			(type default)
		)
		(layer "In8.Cu")
	)
	(gr_line
		(start 85.752178 -53.19522)
		(end 85.741764 -53.758592)
		(stroke
			(width 0.2)
			(type default)
		)
		(layer "In8.Cu")
	)
	(gr_line
		(start 86.021418 -55.367428)
		(end 86.030054 -54.801008)
		(stroke
			(width 0.2)
			(type default)
		)
		(layer "In8.Cu")
	)
	(gr_arc
		(start 86.030054 -54.801008)
		(mid 85.689948 -54.450234)
		(end 85.339174 -54.79034)
		(stroke
			(width 0.2)
			(type default)
		)
		(layer "In8.Cu")
	)
	(gr_line
		(start 86.432644 -53.771546)
		(end 86.443058 -53.20792)
		(stroke
			(width 0.2)
			(type default)
		)
		(layer "In8.Cu")
	)
	(gr_arc
		(start 86.443058 -53.20792)
		(mid 86.103968 -52.85613)
		(end 85.752178 -53.19522)
		(stroke
			(width 0.2)
			(type default)
		)
		(layer "In8.Cu")
	)
	(gr_arc
		(start 86.826852 -54.834028)
		(mid 87.165307 -55.186583)
		(end 87.517732 -54.847998)
		(stroke
			(width 0.2)
			(type default)
		)
		(layer "In8.Cu")
	)
	(gr_line
		(start 86.838028 -54.270402)
		(end 86.826852 -54.834028)
		(stroke
			(width 0.2)
			(type default)
		)
		(layer "In8.Cu")
	)
	(gr_line
		(start 87.517732 -54.847998)
		(end 87.528908 -54.284118)
		(stroke
			(width 0.2)
			(type default)
		)
		(layer "In8.Cu")
	)
	(gr_arc
		(start 87.528908 -54.284118)
		(mid 87.190326 -53.93182)
		(end 86.838028 -54.270402)
		(stroke
			(width 0.2)
			(type default)
		)
		(layer "In8.Cu")
	)
	(gr_line
		(start 87.940896 -53.421534)
		(end 87.95893 -53.98008)
		(stroke
			(width 0.2)
			(type default)
		)
		(layer "In8.Cu")
	)
	(gr_line
		(start 87.943436 -53.421534)
		(end 87.940896 -53.421534)
		(stroke
			(width 0.2)
			(type default)
		)
		(layer "In8.Cu")
	)
	(gr_line
		(start 87.95893 -53.98008)
		(end 87.96147 -53.98008)
		(stroke
			(width 0.2)
			(type default)
		)
		(layer "In8.Cu")
	)
	(gr_arc
		(start 87.96147 -53.98008)
		(mid 88.317832 -54.31409)
		(end 88.651842 -53.957728)
		(stroke
			(width 0.2)
			(type default)
		)
		(layer "In8.Cu")
	)
	(gr_arc
		(start 88.633808 -53.399182)
		(mid 88.277446 -53.065172)
		(end 87.943436 -53.421534)
		(stroke
			(width 0.2)
			(type default)
		)
		(layer "In8.Cu")
	)
	(gr_line
		(start 88.636094 -53.399182)
		(end 88.633808 -53.399182)
		(stroke
			(width 0.2)
			(type default)
		)
		(layer "In8.Cu")
	)
	(gr_line
		(start 88.636348 -53.399436)
		(end 88.636094 -53.399182)
		(stroke
			(width 0.2)
			(type default)
		)
		(layer "In8.Cu")
	)
	(gr_line
		(start 88.651842 -53.957728)
		(end 88.654382 -53.957728)
		(stroke
			(width 0.2)
			(type default)
		)
		(layer "In8.Cu")
	)
	(gr_line
		(start 88.654382 -53.957728)
		(end 88.636348 -53.399436)
		(stroke
			(width 0.2)
			(type default)
		)
		(layer "In8.Cu")
	)
	(gr_arc
		(start 89.415874 -54.043326)
		(mid 89.727024 -54.420008)
		(end 90.103706 -54.108858)
		(stroke
			(width 0.2)
			(type default)
		)
		(layer "In8.Cu")
	)
	(gr_line
		(start 89.46896 -53.486812)
		(end 89.415874 -54.043326)
		(stroke
			(width 0.2)
			(type default)
		)
		(layer "In8.Cu")
	)
	(gr_line
		(start 90.103706 -54.108858)
		(end 90.156792 -53.552598)
		(stroke
			(width 0.2)
			(type default)
		)
		(layer "In8.Cu")
	)
	(gr_arc
		(start 90.156792 -53.552598)
		(mid 89.845768 -53.175928)
		(end 89.46896 -53.486812)
		(stroke
			(width 0.2)
			(type default)
		)
		(layer "In8.Cu")
	)
	(gr_line
		(start 90.681556 -53.93817)
		(end 90.684096 -53.938424)
		(stroke
			(width 0.2)
			(type default)
		)
		(layer "In8.Cu")
	)
	(gr_arc
		(start 90.684096 -53.938424)
		(mid 91.010994 -54.30139)
		(end 91.37396 -53.974492)
		(stroke
			(width 0.2)
			(type default)
		)
		(layer "In8.Cu")
	)
	(gr_line
		(start 90.71102 -53.377592)
		(end 90.681556 -53.93817)
		(stroke
			(width 0.2)
			(type default)
		)
		(layer "In8.Cu")
	)
	(gr_line
		(start 90.71356 -53.377846)
		(end 90.71102 -53.377592)
		(stroke
			(width 0.2)
			(type default)
		)
		(layer "In8.Cu")
	)
	(gr_line
		(start 90.73769 -54.954932)
		(end 90.73896 -54.956964)
		(stroke
			(width 0.2)
			(type default)
		)
		(layer "In8.Cu")
	)
	(gr_line
		(start 90.73769 -54.954678)
		(end 90.73769 -54.954932)
		(stroke
			(width 0.2)
			(type default)
		)
		(layer "In8.Cu")
	)
	(gr_arc
		(start 90.73896 -54.956964)
		(mid 90.631264 -55.433468)
		(end 91.107768 -55.541164)
		(stroke
			(width 0.2)
			(type default)
		)
		(layer "In8.Cu")
	)
	(gr_line
		(start 91.107768 -55.541164)
		(end 91.109038 -55.543196)
		(stroke
			(width 0.2)
			(type default)
		)
		(layer "In8.Cu")
	)
	(gr_line
		(start 91.109038 -55.543196)
		(end 91.581732 -55.244746)
		(stroke
			(width 0.2)
			(type default)
		)
		(layer "In8.Cu")
	)
	(gr_line
		(start 91.210384 -54.656482)
		(end 90.73769 -54.954678)
		(stroke
			(width 0.2)
			(type default)
		)
		(layer "In8.Cu")
	)
	(gr_line
		(start 91.211654 -54.658514)
		(end 91.210384 -54.656482)
		(stroke
			(width 0.2)
			(type default)
		)
		(layer "In8.Cu")
	)
	(gr_line
		(start 91.37396 -53.974492)
		(end 91.3765 -53.974746)
		(stroke
			(width 0.2)
			(type default)
		)
		(layer "In8.Cu")
	)
	(gr_line
		(start 91.3765 -53.974746)
		(end 91.405964 -53.414422)
		(stroke
			(width 0.2)
			(type default)
		)
		(layer "In8.Cu")
	)
	(gr_arc
		(start 91.403424 -53.414168)
		(mid 91.076653 -53.050941)
		(end 90.71356 -53.377846)
		(stroke
			(width 0.2)
			(type default)
		)
		(layer "In8.Cu")
	)
	(gr_line
		(start 91.40571 -53.414168)
		(end 91.403424 -53.414168)
		(stroke
			(width 0.2)
			(type default)
		)
		(layer "In8.Cu")
	)
	(gr_line
		(start 91.405964 -53.414422)
		(end 91.40571 -53.414168)
		(stroke
			(width 0.2)
			(type default)
		)
		(layer "In8.Cu")
	)
	(gr_arc
		(start 91.580462 -55.242714)
		(mid 91.688158 -54.76621)
		(end 91.211654 -54.658514)
		(stroke
			(width 0.2)
			(type default)
		)
		(layer "In8.Cu")
	)
	(gr_line
		(start 91.581732 -55.244746)
		(end 91.580462 -55.242714)
		(stroke
			(width 0.2)
			(type default)
		)
		(layer "In8.Cu")
	)
	(gr_line
		(start 97.409 -32.004)
		(end 97.663 -32.258)
		(stroke
			(width 0.3048)
			(type default)
		)
		(layer "In8.Cu")
	)
	(gr_line
		(start 97.409 -25.908)
		(end 97.409 -32.004)
		(stroke
			(width 0.3048)
			(type default)
		)
		(layer "In8.Cu")
	)
	(gr_line
		(start 97.663 -32.258)
		(end 99.187 -32.258)
		(stroke
			(width 0.3048)
			(type default)
		)
		(layer "In8.Cu")
	)
	(gr_line
		(start 98.171 -50.292)
		(end 98.171 -45.466)
		(stroke
			(width 0.3048)
			(type default)
		)
		(layer "In8.Cu")
	)
	(gr_line
		(start 98.171 -45.466)
		(end 98.806 -44.831)
		(stroke
			(width 0.3048)
			(type default)
		)
		(layer "In8.Cu")
	)
	(gr_line
		(start 98.425 -57.023)
		(end 98.425 -50.546)
		(stroke
			(width 0.3048)
			(type default)
		)
		(layer "In8.Cu")
	)
	(gr_line
		(start 98.425 -50.546)
		(end 98.171 -50.292)
		(stroke
			(width 0.3048)
			(type default)
		)
		(layer "In8.Cu")
	)
	(gr_line
		(start 98.806 -44.831)
		(end 107.188 -44.831)
		(stroke
			(width 0.3048)
			(type default)
		)
		(layer "In8.Cu")
	)
	(gr_line
		(start 98.806 -24.511)
		(end 97.409 -25.908)
		(stroke
			(width 0.3048)
			(type default)
		)
		(layer "In8.Cu")
	)
	(gr_line
		(start 98.806 -21.717)
		(end 98.806 -24.511)
		(stroke
			(width 0.3048)
			(type default)
		)
		(layer "In8.Cu")
	)
	(gr_line
		(start 99.187 -32.258)
		(end 100.584 -33.655)
		(stroke
			(width 0.3048)
			(type default)
		)
		(layer "In8.Cu")
	)
	(gr_line
		(start 99.24542 -60.922154)
		(end 99.86518 -61.523372)
		(stroke
			(width 0.2)
			(type default)
		)
		(layer "In8.Cu")
	)
	(gr_line
		(start 99.247198 -60.920376)
		(end 99.24542 -60.922154)
		(stroke
			(width 0.2)
			(type default)
		)
		(layer "In8.Cu")
	)
	(gr_arc
		(start 99.781106 -60.369704)
		(mid 99.238816 -60.378086)
		(end 99.247198 -60.920376)
		(stroke
			(width 0.2)
			(type default)
		)
		(layer "In8.Cu")
	)
	(gr_line
		(start 99.782884 -60.367926)
		(end 99.781106 -60.369704)
		(stroke
			(width 0.2)
			(type default)
		)
		(layer "In8.Cu")
	)
	(gr_line
		(start 99.86518 -61.523372)
		(end 99.865434 -61.523372)
		(stroke
			(width 0.2)
			(type default)
		)
		(layer "In8.Cu")
	)
	(gr_line
		(start 99.865434 -61.523372)
		(end 99.866958 -61.521848)
		(stroke
			(width 0.2)
			(type default)
		)
		(layer "In8.Cu")
	)
	(gr_arc
		(start 99.866958 -61.521848)
		(mid 100.409565 -61.513655)
		(end 100.40112 -60.971176)
		(stroke
			(width 0.2)
			(type default)
		)
		(layer "In8.Cu")
	)
	(gr_line
		(start 100.40112 -60.971176)
		(end 100.402898 -60.969398)
		(stroke
			(width 0.2)
			(type default)
		)
		(layer "In8.Cu")
	)
	(gr_line
		(start 100.402898 -60.969398)
		(end 99.782884 -60.367926)
		(stroke
			(width 0.2)
			(type default)
		)
		(layer "In8.Cu")
	)
	(gr_line
		(start 100.584 -33.655)
		(end 104.013 -33.655)
		(stroke
			(width 0.3048)
			(type default)
		)
		(layer "In8.Cu")
	)
	(gr_line
		(start 100.711 -19.685)
		(end 98.806 -21.717)
		(stroke
			(width 0.381)
			(type default)
		)
		(layer "In8.Cu")
	)
	(gr_line
		(start 101.185472 -62.20587)
		(end 101.795072 -62.817756)
		(stroke
			(width 0.2)
			(type default)
		)
		(layer "In8.Cu")
	)
	(gr_arc
		(start 101.734366 -61.66993)
		(mid 101.189299 -61.660676)
		(end 101.185472 -62.20587)
		(stroke
			(width 0.2)
			(type default)
		)
		(layer "In8.Cu")
	)
	(gr_arc
		(start 101.795072 -62.817756)
		(mid 102.337616 -62.818772)
		(end 102.338632 -62.276228)
		(stroke
			(width 0.2)
			(type default)
		)
		(layer "In8.Cu")
	)
	(gr_line
		(start 102.338632 -62.276228)
		(end 101.734366 -61.66993)
		(stroke
			(width 0.2)
			(type default)
		)
		(layer "In8.Cu")
	)
	(gr_line
		(start 102.743 -61.341)
		(end 98.425 -57.023)
		(stroke
			(width 0.381)
			(type default)
		)
		(layer "In8.Cu")
	)
	(gr_line
		(start 104.013 -33.655)
		(end 104.648 -33.02)
		(stroke
			(width 0.3048)
			(type default)
		)
		(layer "In8.Cu")
	)
	(gr_line
		(start 104.648 -33.02)
		(end 109.728 -33.02)
		(stroke
			(width 0.3048)
			(type default)
		)
		(layer "In8.Cu")
	)
	(gr_line
		(start 107.188 -44.831)
		(end 107.442 -44.958)
		(stroke
			(width 0.3048)
			(type default)
		)
		(layer "In8.Cu")
	)
	(gr_line
		(start 107.442 -44.958)
		(end 108.585 -44.958)
		(stroke
			(width 0.3048)
			(type default)
		)
		(layer "In8.Cu")
	)
	(gr_line
		(start 108.331 -19.685)
		(end 100.711 -19.685)
		(stroke
			(width 0.381)
			(type default)
		)
		(layer "In8.Cu")
	)
	(gr_line
		(start 108.585 -44.958)
		(end 109.093 -45.466)
		(stroke
			(width 0.3048)
			(type default)
		)
		(layer "In8.Cu")
	)
	(gr_line
		(start 109.093 -45.466)
		(end 117.602 -45.466)
		(stroke
			(width 0.3048)
			(type default)
		)
		(layer "In8.Cu")
	)
	(gr_line
		(start 109.728 -33.02)
		(end 109.9566 -32.8422)
		(stroke
			(width 0.3048)
			(type default)
		)
		(layer "In8.Cu")
	)
	(gr_line
		(start 109.9566 -32.8422)
		(end 110.7948 -32.8422)
		(stroke
			(width 0.3048)
			(type default)
		)
		(layer "In8.Cu")
	)
	(gr_line
		(start 110.7948 -32.8422)
		(end 111.0996 -33.147)
		(stroke
			(width 0.3048)
			(type default)
		)
		(layer "In8.Cu")
	)
	(gr_line
		(start 111.0996 -33.147)
		(end 112.522 -33.147)
		(stroke
			(width 0.3048)
			(type default)
		)
		(layer "In8.Cu")
	)
	(gr_line
		(start 112.522 -33.147)
		(end 114.681 -30.988)
		(stroke
			(width 0.3048)
			(type default)
		)
		(layer "In8.Cu")
	)
	(gr_line
		(start 114.173 -13.843)
		(end 108.331 -19.685)
		(stroke
			(width 0.381)
			(type default)
		)
		(layer "In8.Cu")
	)
	(gr_line
		(start 114.681 -30.988)
		(end 117.856 -30.988)
		(stroke
			(width 0.3048)
			(type default)
		)
		(layer "In8.Cu")
	)
	(gr_line
		(start 117.602 -45.466)
		(end 117.729 -45.339)
		(stroke
			(width 0.3048)
			(type default)
		)
		(layer "In8.Cu")
	)
	(gr_line
		(start 117.729 -45.339)
		(end 151.511 -45.339)
		(stroke
			(width 0.381)
			(type default)
		)
		(layer "In8.Cu")
	)
	(gr_line
		(start 117.856 -30.988)
		(end 118.999 -29.845)
		(stroke
			(width 0.381)
			(type default)
		)
		(layer "In8.Cu")
	)
	(gr_line
		(start 118.999 -29.845)
		(end 158.369 -29.845)
		(stroke
			(width 0.381)
			(type default)
		)
		(layer "In8.Cu")
	)
	(gr_line
		(start 119.126 -61.341)
		(end 102.743 -61.341)
		(stroke
			(width 0.381)
			(type default)
		)
		(layer "In8.Cu")
	)
	(gr_line
		(start 119.38 -61.595)
		(end 119.126 -61.341)
		(stroke
			(width 0.381)
			(type default)
		)
		(layer "In8.Cu")
	)
	(gr_line
		(start 131.318 -13.843)
		(end 114.173 -13.843)
		(stroke
			(width 0.381)
			(type default)
		)
		(layer "In8.Cu")
	)
	(gr_line
		(start 135.382 -9.779)
		(end 131.318 -13.843)
		(stroke
			(width 0.381)
			(type default)
		)
		(layer "In8.Cu")
	)
	(gr_line
		(start 135.636 -61.595)
		(end 119.38 -61.595)
		(stroke
			(width 0.381)
			(type default)
		)
		(layer "In8.Cu")
	)
	(gr_line
		(start 137.16 -64.77)
		(end 137.16 -63.119)
		(stroke
			(width 0.381)
			(type default)
		)
		(layer "In8.Cu")
	)
	(gr_line
		(start 137.16 -63.119)
		(end 135.636 -61.595)
		(stroke
			(width 0.381)
			(type default)
		)
		(layer "In8.Cu")
	)
	(gr_line
		(start 142.494 -70.104)
		(end 137.16 -64.77)
		(stroke
			(width 0.381)
			(type default)
		)
		(layer "In8.Cu")
	)
	(gr_line
		(start 144.78 -9.779)
		(end 135.382 -9.779)
		(stroke
			(width 0.381)
			(type default)
		)
		(layer "In8.Cu")
	)
	(gr_line
		(start 151.511 -45.339)
		(end 166.37 -60.198)
		(stroke
			(width 0.381)
			(type default)
		)
		(layer "In8.Cu")
	)
	(gr_line
		(start 152.4 -2.159)
		(end 144.78 -9.779)
		(stroke
			(width 0.381)
			(type default)
		)
		(layer "In8.Cu")
	)
	(gr_line
		(start 158.369 -29.845)
		(end 172.974 -15.24)
		(stroke
			(width 0.381)
			(type default)
		)
		(layer "In8.Cu")
	)
	(gr_line
		(start 166.37 -63.627)
		(end 168.783 -66.04)
		(stroke
			(width 0.381)
			(type default)
		)
		(layer "In8.Cu")
	)
	(gr_line
		(start 166.37 -60.198)
		(end 166.37 -63.627)
		(stroke
			(width 0.381)
			(type default)
		)
		(layer "In8.Cu")
	)
	(gr_line
		(start 166.497 -70.104)
		(end 142.494 -70.104)
		(stroke
			(width 0.381)
			(type default)
		)
		(layer "In8.Cu")
	)
	(gr_line
		(start 168.783 -67.818)
		(end 166.497 -70.104)
		(stroke
			(width 0.381)
			(type default)
		)
		(layer "In8.Cu")
	)
	(gr_line
		(start 168.783 -66.04)
		(end 168.783 -67.818)
		(stroke
			(width 0.381)
			(type default)
		)
		(layer "In8.Cu")
	)
	(gr_line
		(start 169.164 -2.159)
		(end 152.4 -2.159)
		(stroke
			(width 0.381)
			(type default)
		)
		(layer "In8.Cu")
	)
	(gr_line
		(start 169.926 -3.683)
		(end 169.926 -2.921)
		(stroke
			(width 0.381)
			(type default)
		)
		(layer "In8.Cu")
	)
	(gr_line
		(start 169.926 -2.921)
		(end 169.164 -2.159)
		(stroke
			(width 0.381)
			(type default)
		)
		(layer "In8.Cu")
	)
	(gr_line
		(start 170.688 -6.223)
		(end 170.688 -4.445)
		(stroke
			(width 0.381)
			(type default)
		)
		(layer "In8.Cu")
	)
	(gr_line
		(start 170.688 -4.445)
		(end 169.926 -3.683)
		(stroke
			(width 0.381)
			(type default)
		)
		(layer "In8.Cu")
	)
	(gr_line
		(start 172.339 -10.795)
		(end 172.339 -7.874)
		(stroke
			(width 0.381)
			(type default)
		)
		(layer "In8.Cu")
	)
	(gr_line
		(start 172.339 -7.874)
		(end 170.688 -6.223)
		(stroke
			(width 0.381)
			(type default)
		)
		(layer "In8.Cu")
	)
	(gr_line
		(start 172.974 -15.24)
		(end 172.974 -11.43)
		(stroke
			(width 0.381)
			(type default)
		)
		(layer "In8.Cu")
	)
	(gr_line
		(start 172.974 -11.43)
		(end 172.339 -10.795)
		(stroke
			(width 0.381)
			(type default)
		)
		(layer "In8.Cu")
	)
	(gr_line
		(start 19.408394 -10.250678)
		(end 19.63293 -10.475214)
		(stroke
			(width 0.05715)
			(type default)
		)
		(layer "In9.Cu")
	)
	(gr_line
		(start 20.103338 -10.475214)
		(end 20.327874 -10.250678)
		(stroke
			(width 0.05715)
			(type default)
		)
		(layer "In9.Cu")
	)
	(gr_line
		(start 22.733 -51.816)
		(end 22.996906 -52.079906)
		(stroke
			(width 0.0635)
			(type default)
		)
		(layer "In9.Cu")
	)
	(gr_line
		(start 23.359872 -52.079906)
		(end 23.5712 -51.868578)
		(stroke
			(width 0.0635)
			(type default)
		)
		(layer "In9.Cu")
	)
	(gr_line
		(start 23.408386 -10.250678)
		(end 23.632922 -10.475214)
		(stroke
			(width 0.05715)
			(type default)
		)
		(layer "In9.Cu")
	)
	(gr_line
		(start 23.5712 -51.843432)
		(end 23.5712 -51.868578)
		(stroke
			(width 0.0635)
			(type default)
		)
		(layer "In9.Cu")
	)
	(gr_line
		(start 23.5712 -51.843432)
		(end 23.5966 -51.818032)
		(stroke
			(width 0.0635)
			(type default)
		)
		(layer "In9.Cu")
	)
	(gr_line
		(start 24.10333 -10.475214)
		(end 24.327866 -10.250678)
		(stroke
			(width 0.05715)
			(type default)
		)
		(layer "In9.Cu")
	)
	(gr_line
		(start 27.408378 -10.250678)
		(end 27.632914 -10.475214)
		(stroke
			(width 0.05715)
			(type default)
		)
		(layer "In9.Cu")
	)
	(gr_line
		(start 27.703018 -11.61415)
		(end 27.703018 -11.71829)
		(stroke
			(width 0.05715)
			(type default)
		)
		(layer "In9.Cu")
	)
	(gr_line
		(start 28.035758 -12.04849)
		(end 28.246578 -11.83767)
		(stroke
			(width 0.05715)
			(type default)
		)
		(layer "In9.Cu")
	)
	(gr_line
		(start 28.035758 -11.28395)
		(end 28.246578 -11.49477)
		(stroke
			(width 0.05715)
			(type default)
		)
		(layer "In9.Cu")
	)
	(gr_line
		(start 28.103322 -10.475214)
		(end 28.327858 -10.250678)
		(stroke
			(width 0.05715)
			(type default)
		)
		(layer "In9.Cu")
	)
	(gr_line
		(start 28.246578 -11.49477)
		(end 28.246578 -11.83767)
		(stroke
			(width 0.05715)
			(type default)
		)
		(layer "In9.Cu")
	)
	(gr_line
		(start 31.40837 -10.250678)
		(end 31.632906 -10.475214)
		(stroke
			(width 0.05715)
			(type default)
		)
		(layer "In9.Cu")
	)
	(gr_line
		(start 32.103314 -10.475214)
		(end 32.32785 -10.250678)
		(stroke
			(width 0.05715)
			(type default)
		)
		(layer "In9.Cu")
	)
	(gr_line
		(start 35.408362 -10.250678)
		(end 35.632898 -10.475214)
		(stroke
			(width 0.05715)
			(type default)
		)
		(layer "In9.Cu")
	)
	(gr_line
		(start 36.103306 -10.475214)
		(end 36.327842 -10.250678)
		(stroke
			(width 0.05715)
			(type default)
		)
		(layer "In9.Cu")
	)
	(gr_line
		(start 39.408354 -10.250678)
		(end 39.63289 -10.475214)
		(stroke
			(width 0.05715)
			(type default)
		)
		(layer "In9.Cu")
	)
	(gr_line
		(start 40.103298 -10.475214)
		(end 40.327834 -10.250678)
		(stroke
			(width 0.05715)
			(type default)
		)
		(layer "In9.Cu")
	)
	(gr_line
		(start 43.408346 -10.250678)
		(end 43.632882 -10.475214)
		(stroke
			(width 0.05715)
			(type default)
		)
		(layer "In9.Cu")
	)
	(gr_line
		(start 44.10329 -10.475214)
		(end 44.327826 -10.250678)
		(stroke
			(width 0.05715)
			(type default)
		)
		(layer "In9.Cu")
	)
	(gr_line
		(start 45.681392 -11.371072)
		(end 45.892212 -11.160252)
		(stroke
			(width 0.05715)
			(type default)
		)
		(layer "In9.Cu")
	)
	(gr_line
		(start 45.892212 -11.160252)
		(end 46.235112 -11.160252)
		(stroke
			(width 0.05715)
			(type default)
		)
		(layer "In9.Cu")
	)
	(gr_line
		(start 46.011592 -11.703812)
		(end 46.115732 -11.703812)
		(stroke
			(width 0.05715)
			(type default)
		)
		(layer "In9.Cu")
	)
	(gr_line
		(start 46.235112 -11.160252)
		(end 46.445932 -11.371072)
		(stroke
			(width 0.05715)
			(type default)
		)
		(layer "In9.Cu")
	)
	(gr_line
		(start 47.408338 -10.250678)
		(end 47.632874 -10.475214)
		(stroke
			(width 0.05715)
			(type default)
		)
		(layer "In9.Cu")
	)
	(gr_line
		(start 48.103282 -10.475214)
		(end 48.327818 -10.250678)
		(stroke
			(width 0.05715)
			(type default)
		)
		(layer "In9.Cu")
	)
	(gr_line
		(start 50.455322 -48.310292)
		(end 50.645568 -48.500538)
		(stroke
			(width 0.05715)
			(type default)
		)
		(layer "In9.Cu")
	)
	(gr_line
		(start 50.455322 -47.83963)
		(end 50.658014 -47.636938)
		(stroke
			(width 0.05715)
			(type default)
		)
		(layer "In9.Cu")
	)
	(gr_line
		(start 55.0164 -13.02131)
		(end 55.084472 -12.953238)
		(stroke
			(width 0.05715)
			(type default)
		)
		(layer "In9.Cu")
	)
	(gr_line
		(start 55.31739 -53.625496)
		(end 55.390796 -53.698902)
		(stroke
			(width 0.05715)
			(type default)
		)
		(layer "In9.Cu")
	)
	(gr_line
		(start 55.319168 -53.156612)
		(end 55.617364 -53.156612)
		(stroke
			(width 0.05715)
			(type default)
		)
		(layer "In9.Cu")
	)
	(gr_line
		(start 55.617364 -53.156612)
		(end 55.85968 -53.398928)
		(stroke
			(width 0.05715)
			(type default)
		)
		(layer "In9.Cu")
	)
	(gr_line
		(start 55.85968 -53.398928)
		(end 55.85968 -53.697124)
		(stroke
			(width 0.05715)
			(type default)
		)
		(layer "In9.Cu")
	)
	(gr_line
		(start 56.523128 -11.981942)
		(end 56.5912 -11.91387)
		(stroke
			(width 0.05715)
			(type default)
		)
		(layer "In9.Cu")
	)
	(gr_line
		(start 57.73674 -29.566108)
		(end 57.804812 -29.498036)
		(stroke
			(width 0.05715)
			(type default)
		)
		(layer "In9.Cu")
	)
	(gr_line
		(start 58.009028 -55.123842)
		(end 58.082688 -55.197502)
		(stroke
			(width 0.05715)
			(type default)
		)
		(layer "In9.Cu")
	)
	(gr_line
		(start 58.010806 -54.654958)
		(end 58.309002 -54.654958)
		(stroke
			(width 0.05715)
			(type default)
		)
		(layer "In9.Cu")
	)
	(gr_line
		(start 58.222134 -30.051502)
		(end 58.290206 -29.98343)
		(stroke
			(width 0.05715)
			(type default)
		)
		(layer "In9.Cu")
	)
	(gr_line
		(start 58.309002 -54.654958)
		(end 58.551572 -54.897528)
		(stroke
			(width 0.05715)
			(type default)
		)
		(layer "In9.Cu")
	)
	(gr_line
		(start 58.551572 -54.897528)
		(end 58.551572 -55.195724)
		(stroke
			(width 0.05715)
			(type default)
		)
		(layer "In9.Cu")
	)
	(gr_line
		(start 58.626502 -28.209494)
		(end 58.694574 -28.141422)
		(stroke
			(width 0.05715)
			(type default)
		)
		(layer "In9.Cu")
	)
	(gr_line
		(start 59.17438 -31.003748)
		(end 59.242452 -30.935676)
		(stroke
			(width 0.05715)
			(type default)
		)
		(layer "In9.Cu")
	)
	(gr_line
		(start 59.579002 -29.161994)
		(end 59.647074 -29.093922)
		(stroke
			(width 0.05715)
			(type default)
		)
		(layer "In9.Cu")
	)
	(gr_line
		(start 59.659774 -31.489142)
		(end 59.727846 -31.42107)
		(stroke
			(width 0.05715)
			(type default)
		)
		(layer "In9.Cu")
	)
	(gr_line
		(start 60.064142 -29.647134)
		(end 60.132214 -29.579062)
		(stroke
			(width 0.05715)
			(type default)
		)
		(layer "In9.Cu")
	)
	(gr_line
		(start 61.016642 -30.599634)
		(end 61.084714 -30.531562)
		(stroke
			(width 0.05715)
			(type default)
		)
		(layer "In9.Cu")
	)
	(gr_line
		(start 61.263276 -32.731964)
		(end 61.26353 -32.731964)
		(stroke
			(width 0.05715)
			(type default)
		)
		(layer "In9.Cu")
	)
	(gr_line
		(start 61.593476 -32.869124)
		(end 61.593476 -33.062164)
		(stroke
			(width 0.05715)
			(type default)
		)
		(layer "In9.Cu")
	)
	(gr_line
		(start 65.21704 -12.47394)
		(end 65.42786 -12.68476)
		(stroke
			(width 0.05715)
			(type default)
		)
		(layer "In9.Cu")
	)
	(gr_line
		(start 65.42786 -12.68476)
		(end 65.77076 -12.68476)
		(stroke
			(width 0.05715)
			(type default)
		)
		(layer "In9.Cu")
	)
	(gr_line
		(start 65.54724 -12.1412)
		(end 65.65138 -12.1412)
		(stroke
			(width 0.05715)
			(type default)
		)
		(layer "In9.Cu")
	)
	(gr_line
		(start 65.77076 -12.68476)
		(end 65.98158 -12.47394)
		(stroke
			(width 0.05715)
			(type default)
		)
		(layer "In9.Cu")
	)
	(gr_line
		(start 66.2051 -39.29126)
		(end 66.2051 -39.3954)
		(stroke
			(width 0.05715)
			(type default)
		)
		(layer "In9.Cu")
	)
	(gr_line
		(start 66.2051 -38.17874)
		(end 66.2051 -38.28288)
		(stroke
			(width 0.05715)
			(type default)
		)
		(layer "In9.Cu")
	)
	(gr_line
		(start 66.2051 -37.06622)
		(end 66.2051 -37.17036)
		(stroke
			(width 0.05715)
			(type default)
		)
		(layer "In9.Cu")
	)
	(gr_line
		(start 66.53784 -39.7256)
		(end 66.74866 -39.51478)
		(stroke
			(width 0.05715)
			(type default)
		)
		(layer "In9.Cu")
	)
	(gr_line
		(start 66.53784 -38.96106)
		(end 66.74866 -39.17188)
		(stroke
			(width 0.05715)
			(type default)
		)
		(layer "In9.Cu")
	)
	(gr_line
		(start 66.53784 -38.61308)
		(end 66.74866 -38.40226)
		(stroke
			(width 0.05715)
			(type default)
		)
		(layer "In9.Cu")
	)
	(gr_line
		(start 66.53784 -37.84854)
		(end 66.74866 -38.05936)
		(stroke
			(width 0.05715)
			(type default)
		)
		(layer "In9.Cu")
	)
	(gr_line
		(start 66.53784 -37.50056)
		(end 66.74866 -37.28974)
		(stroke
			(width 0.05715)
			(type default)
		)
		(layer "In9.Cu")
	)
	(gr_line
		(start 66.53784 -36.73602)
		(end 66.74866 -36.94684)
		(stroke
			(width 0.05715)
			(type default)
		)
		(layer "In9.Cu")
	)
	(gr_line
		(start 66.74866 -39.17188)
		(end 66.74866 -39.51478)
		(stroke
			(width 0.05715)
			(type default)
		)
		(layer "In9.Cu")
	)
	(gr_line
		(start 66.74866 -38.05936)
		(end 66.74866 -38.40226)
		(stroke
			(width 0.05715)
			(type default)
		)
		(layer "In9.Cu")
	)
	(gr_line
		(start 66.74866 -36.94684)
		(end 66.74866 -37.28974)
		(stroke
			(width 0.05715)
			(type default)
		)
		(layer "In9.Cu")
	)
	(gr_line
		(start 66.827654 -11.759946)
		(end 66.90106 -11.68654)
		(stroke
			(width 0.05715)
			(type default)
		)
		(layer "In9.Cu")
	)
	(gr_line
		(start 66.829432 -12.22883)
		(end 67.127628 -12.22883)
		(stroke
			(width 0.05715)
			(type default)
		)
		(layer "In9.Cu")
	)
	(gr_line
		(start 67.127628 -12.22883)
		(end 67.369944 -11.986514)
		(stroke
			(width 0.05715)
			(type default)
		)
		(layer "In9.Cu")
	)
	(gr_line
		(start 67.34556 -10.28446)
		(end 67.589146 -10.528046)
		(stroke
			(width 0.05715)
			(type default)
		)
		(layer "In9.Cu")
	)
	(gr_line
		(start 67.369944 -11.688318)
		(end 67.369944 -11.986514)
		(stroke
			(width 0.05715)
			(type default)
		)
		(layer "In9.Cu")
	)
	(gr_line
		(start 68.059554 -10.528046)
		(end 68.30314 -10.28446)
		(stroke
			(width 0.05715)
			(type default)
		)
		(layer "In9.Cu")
	)
	(gr_line
		(start 69.57949 -31.04769)
		(end 69.79031 -31.25851)
		(stroke
			(width 0.05715)
			(type default)
		)
		(layer "In9.Cu")
	)
	(gr_line
		(start 69.57949 -30.70479)
		(end 69.57949 -31.04769)
		(stroke
			(width 0.05715)
			(type default)
		)
		(layer "In9.Cu")
	)
	(gr_line
		(start 69.57949 -30.70479)
		(end 69.79031 -30.49397)
		(stroke
			(width 0.05715)
			(type default)
		)
		(layer "In9.Cu")
	)
	(gr_line
		(start 69.57949 -29.93517)
		(end 69.79031 -30.14599)
		(stroke
			(width 0.05715)
			(type default)
		)
		(layer "In9.Cu")
	)
	(gr_line
		(start 69.57949 -29.59227)
		(end 69.57949 -29.93517)
		(stroke
			(width 0.05715)
			(type default)
		)
		(layer "In9.Cu")
	)
	(gr_line
		(start 69.57949 -29.59227)
		(end 69.79031 -29.38145)
		(stroke
			(width 0.05715)
			(type default)
		)
		(layer "In9.Cu")
	)
	(gr_line
		(start 70.104 -20.6502)
		(end 70.172072 -20.582128)
		(stroke
			(width 0.05715)
			(type default)
		)
		(layer "In9.Cu")
	)
	(gr_line
		(start 70.12305 -30.82417)
		(end 70.12305 -30.92831)
		(stroke
			(width 0.05715)
			(type default)
		)
		(layer "In9.Cu")
	)
	(gr_line
		(start 70.12305 -29.71165)
		(end 70.12305 -29.81579)
		(stroke
			(width 0.05715)
			(type default)
		)
		(layer "In9.Cu")
	)
	(gr_line
		(start 70.272148 -34.130234)
		(end 70.514464 -34.37255)
		(stroke
			(width 0.05715)
			(type default)
		)
		(layer "In9.Cu")
	)
	(gr_line
		(start 70.272148 -33.832038)
		(end 70.272148 -34.130234)
		(stroke
			(width 0.05715)
			(type default)
		)
		(layer "In9.Cu")
	)
	(gr_line
		(start 70.446646 -20.3073)
		(end 70.4469 -20.3073)
		(stroke
			(width 0.05715)
			(type default)
		)
		(layer "In9.Cu")
	)
	(gr_line
		(start 70.514464 -34.37255)
		(end 70.81266 -34.37255)
		(stroke
			(width 0.05715)
			(type default)
		)
		(layer "In9.Cu")
	)
	(gr_line
		(start 70.680326 -20.54098)
		(end 70.7771 -20.54098)
		(stroke
			(width 0.05715)
			(type default)
		)
		(layer "In9.Cu")
	)
	(gr_line
		(start 70.741032 -33.83026)
		(end 70.814438 -33.903666)
		(stroke
			(width 0.05715)
			(type default)
		)
		(layer "In9.Cu")
	)
	(gr_line
		(start 71.058786 -34.916872)
		(end 71.301102 -35.159188)
		(stroke
			(width 0.05715)
			(type default)
		)
		(layer "In9.Cu")
	)
	(gr_line
		(start 71.058786 -34.618676)
		(end 71.058786 -34.916872)
		(stroke
			(width 0.05715)
			(type default)
		)
		(layer "In9.Cu")
	)
	(gr_line
		(start 71.301102 -35.159188)
		(end 71.599298 -35.159188)
		(stroke
			(width 0.05715)
			(type default)
		)
		(layer "In9.Cu")
	)
	(gr_line
		(start 71.370952 -10.28446)
		(end 71.614538 -10.528046)
		(stroke
			(width 0.05715)
			(type default)
		)
		(layer "In9.Cu")
	)
	(gr_line
		(start 71.52767 -34.616898)
		(end 71.601076 -34.690304)
		(stroke
			(width 0.05715)
			(type default)
		)
		(layer "In9.Cu")
	)
	(gr_line
		(start 72.084946 -10.528046)
		(end 72.328532 -10.28446)
		(stroke
			(width 0.05715)
			(type default)
		)
		(layer "In9.Cu")
	)
	(gr_line
		(start 72.17029 -27.285696)
		(end 72.38111 -27.496516)
		(stroke
			(width 0.05715)
			(type default)
		)
		(layer "In9.Cu")
	)
	(gr_line
		(start 72.17029 -26.942796)
		(end 72.17029 -27.285696)
		(stroke
			(width 0.05715)
			(type default)
		)
		(layer "In9.Cu")
	)
	(gr_line
		(start 72.17029 -26.942796)
		(end 72.38111 -26.731976)
		(stroke
			(width 0.05715)
			(type default)
		)
		(layer "In9.Cu")
	)
	(gr_line
		(start 72.17029 -26.173176)
		(end 72.38111 -26.383996)
		(stroke
			(width 0.05715)
			(type default)
		)
		(layer "In9.Cu")
	)
	(gr_line
		(start 72.17029 -25.830276)
		(end 72.17029 -26.173176)
		(stroke
			(width 0.05715)
			(type default)
		)
		(layer "In9.Cu")
	)
	(gr_line
		(start 72.17029 -25.830276)
		(end 72.38111 -25.619456)
		(stroke
			(width 0.05715)
			(type default)
		)
		(layer "In9.Cu")
	)
	(gr_line
		(start 72.71385 -27.062176)
		(end 72.71385 -27.166316)
		(stroke
			(width 0.05715)
			(type default)
		)
		(layer "In9.Cu")
	)
	(gr_line
		(start 72.71385 -25.949656)
		(end 72.71385 -26.053796)
		(stroke
			(width 0.05715)
			(type default)
		)
		(layer "In9.Cu")
	)
	(gr_line
		(start 75.370944 -10.28446)
		(end 75.61453 -10.528046)
		(stroke
			(width 0.05715)
			(type default)
		)
		(layer "In9.Cu")
	)
	(gr_line
		(start 76.084938 -10.528046)
		(end 76.328524 -10.28446)
		(stroke
			(width 0.05715)
			(type default)
		)
		(layer "In9.Cu")
	)
	(gr_line
		(start 76.45654 -47.85614)
		(end 76.5302 -47.9298)
		(stroke
			(width 0.05715)
			(type default)
		)
		(layer "In9.Cu")
	)
	(gr_line
		(start 76.66736 -47.5234)
		(end 77.08392 -47.93996)
		(stroke
			(width 0.05715)
			(type default)
		)
		(layer "In9.Cu")
	)
	(gr_line
		(start 77.08392 -47.93996)
		(end 77.08392 -48.0314)
		(stroke
			(width 0.05715)
			(type default)
		)
		(layer "In9.Cu")
	)
	(gr_line
		(start 77.597 -52.4129)
		(end 77.616558 -52.393342)
		(stroke
			(width 0.0508)
			(type default)
		)
		(layer "In9.Cu")
	)
	(gr_line
		(start 77.597 -52.0827)
		(end 77.616558 -52.102258)
		(stroke
			(width 0.0508)
			(type default)
		)
		(layer "In9.Cu")
	)
	(gr_line
		(start 77.617066 -18.3134)
		(end 77.71384 -18.3134)
		(stroke
			(width 0.05715)
			(type default)
		)
		(layer "In9.Cu")
	)
	(gr_line
		(start 77.618336 -52.391564)
		(end 77.6605 -52.3494)
		(stroke
			(width 0.0508)
			(type default)
		)
		(layer "In9.Cu")
	)
	(gr_line
		(start 77.618336 -52.104036)
		(end 77.6605 -52.1462)
		(stroke
			(width 0.0508)
			(type default)
		)
		(layer "In9.Cu")
	)
	(gr_line
		(start 77.632306 -16.51)
		(end 77.700378 -16.441928)
		(stroke
			(width 0.05715)
			(type default)
		)
		(layer "In9.Cu")
	)
	(gr_line
		(start 77.851 -18.6436)
		(end 77.920088 -18.574512)
		(stroke
			(width 0.05715)
			(type default)
		)
		(layer "In9.Cu")
	)
	(gr_line
		(start 77.947266 -18.54708)
		(end 77.94752 -18.54708)
		(stroke
			(width 0.05715)
			(type default)
		)
		(layer "In9.Cu")
	)
	(gr_line
		(start 78.105 -47.752)
		(end 78.14945 -47.70755)
		(stroke
			(width 0.05715)
			(type default)
		)
		(layer "In9.Cu")
	)
	(gr_line
		(start 78.138782 -15.536672)
		(end 78.206854 -15.4686)
		(stroke
			(width 0.05715)
			(type default)
		)
		(layer "In9.Cu")
	)
	(gr_line
		(start 78.505812 -51.88966)
		(end 78.602332 -51.79314)
		(stroke
			(width 0.0508)
			(type default)
		)
		(layer "In9.Cu")
	)
	(gr_line
		(start 78.602332 -51.79314)
		(end 78.907132 -51.79314)
		(stroke
			(width 0.0508)
			(type default)
		)
		(layer "In9.Cu")
	)
	(gr_line
		(start 78.620112 -47.70755)
		(end 78.6638 -47.751238)
		(stroke
			(width 0.05715)
			(type default)
		)
		(layer "In9.Cu")
	)
	(gr_line
		(start 78.709012 -52.0954)
		(end 78.800452 -52.0954)
		(stroke
			(width 0.0508)
			(type default)
		)
		(layer "In9.Cu")
	)
	(gr_line
		(start 78.907132 -51.79314)
		(end 79.003652 -51.88966)
		(stroke
			(width 0.0508)
			(type default)
		)
		(layer "In9.Cu")
	)
	(gr_line
		(start 79.10322 -50.10404)
		(end 79.31404 -49.89322)
		(stroke
			(width 0.05715)
			(type default)
		)
		(layer "In9.Cu")
	)
	(gr_line
		(start 79.150464 -54.652926)
		(end 79.22387 -54.726332)
		(stroke
			(width 0.05715)
			(type default)
		)
		(layer "In9.Cu")
	)
	(gr_line
		(start 79.152242 -54.184042)
		(end 79.450438 -54.184042)
		(stroke
			(width 0.05715)
			(type default)
		)
		(layer "In9.Cu")
	)
	(gr_line
		(start 79.313532 -51.88966)
		(end 79.410052 -51.79314)
		(stroke
			(width 0.0508)
			(type default)
		)
		(layer "In9.Cu")
	)
	(gr_line
		(start 79.31404 -49.89322)
		(end 79.65694 -49.89322)
		(stroke
			(width 0.05715)
			(type default)
		)
		(layer "In9.Cu")
	)
	(gr_line
		(start 79.370936 -10.33526)
		(end 79.614522 -10.578846)
		(stroke
			(width 0.05715)
			(type default)
		)
		(layer "In9.Cu")
	)
	(gr_line
		(start 79.410052 -51.79314)
		(end 79.714852 -51.79314)
		(stroke
			(width 0.0508)
			(type default)
		)
		(layer "In9.Cu")
	)
	(gr_line
		(start 79.43342 -50.43678)
		(end 79.53756 -50.43678)
		(stroke
			(width 0.05715)
			(type default)
		)
		(layer "In9.Cu")
	)
	(gr_line
		(start 79.450438 -54.184042)
		(end 79.692754 -54.426358)
		(stroke
			(width 0.05715)
			(type default)
		)
		(layer "In9.Cu")
	)
	(gr_line
		(start 79.516732 -52.0954)
		(end 79.608172 -52.0954)
		(stroke
			(width 0.0508)
			(type default)
		)
		(layer "In9.Cu")
	)
	(gr_line
		(start 79.530448 -16.96339)
		(end 79.59852 -16.895318)
		(stroke
			(width 0.05715)
			(type default)
		)
		(layer "In9.Cu")
	)
	(gr_line
		(start 79.65694 -49.89322)
		(end 79.86776 -50.10404)
		(stroke
			(width 0.05715)
			(type default)
		)
		(layer "In9.Cu")
	)
	(gr_line
		(start 79.692754 -54.426358)
		(end 79.692754 -54.724554)
		(stroke
			(width 0.05715)
			(type default)
		)
		(layer "In9.Cu")
	)
	(gr_line
		(start 79.701644 -55.204106)
		(end 79.747618 -55.204106)
		(stroke
			(width 0.0508)
			(type default)
		)
		(layer "In9.Cu")
	)
	(gr_line
		(start 79.714852 -51.79314)
		(end 79.811372 -51.88966)
		(stroke
			(width 0.0508)
			(type default)
		)
		(layer "In9.Cu")
	)
	(gr_line
		(start 79.750158 -55.204106)
		(end 79.791306 -55.204106)
		(stroke
			(width 0.0508)
			(type default)
		)
		(layer "In9.Cu")
	)
	(gr_line
		(start 79.935324 -54.97068)
		(end 79.953358 -54.988714)
		(stroke
			(width 0.0508)
			(type default)
		)
		(layer "In9.Cu")
	)
	(gr_line
		(start 79.953358 -55.000906)
		(end 79.953358 -55.07863)
		(stroke
			(width 0.0508)
			(type default)
		)
		(layer "In9.Cu")
	)
	(gr_line
		(start 79.953358 -54.988714)
		(end 79.953358 -54.998366)
		(stroke
			(width 0.0508)
			(type default)
		)
		(layer "In9.Cu")
	)
	(gr_line
		(start 80.076802 -43.866308)
		(end 80.150208 -43.939714)
		(stroke
			(width 0.05715)
			(type default)
		)
		(layer "In9.Cu")
	)
	(gr_line
		(start 80.07858 -43.397424)
		(end 80.376776 -43.397424)
		(stroke
			(width 0.05715)
			(type default)
		)
		(layer "In9.Cu")
	)
	(gr_line
		(start 80.08493 -10.578846)
		(end 80.328516 -10.33526)
		(stroke
			(width 0.05715)
			(type default)
		)
		(layer "In9.Cu")
	)
	(gr_line
		(start 80.2132 -50.43678)
		(end 80.2259 -50.43678)
		(stroke
			(width 0.0508)
			(type default)
		)
		(layer "In9.Cu")
	)
	(gr_line
		(start 80.2132 -50.10658)
		(end 80.2259 -50.10658)
		(stroke
			(width 0.0508)
			(type default)
		)
		(layer "In9.Cu")
	)
	(gr_line
		(start 80.2259 -50.43678)
		(end 80.245458 -50.417222)
		(stroke
			(width 0.0508)
			(type default)
		)
		(layer "In9.Cu")
	)
	(gr_line
		(start 80.2259 -50.10658)
		(end 80.245458 -50.126138)
		(stroke
			(width 0.0508)
			(type default)
		)
		(layer "In9.Cu")
	)
	(gr_line
		(start 80.247236 -50.415444)
		(end 80.2894 -50.37328)
		(stroke
			(width 0.0508)
			(type default)
		)
		(layer "In9.Cu")
	)
	(gr_line
		(start 80.247236 -50.127916)
		(end 80.2894 -50.17008)
		(stroke
			(width 0.0508)
			(type default)
		)
		(layer "In9.Cu")
	)
	(gr_line
		(start 80.2894 -51.083972)
		(end 80.3021 -51.083972)
		(stroke
			(width 0.0508)
			(type default)
		)
		(layer "In9.Cu")
	)
	(gr_line
		(start 80.2894 -50.753772)
		(end 80.3021 -50.753772)
		(stroke
			(width 0.0508)
			(type default)
		)
		(layer "In9.Cu")
	)
	(gr_line
		(start 80.3021 -51.083972)
		(end 80.321658 -51.064414)
		(stroke
			(width 0.0508)
			(type default)
		)
		(layer "In9.Cu")
	)
	(gr_line
		(start 80.3021 -50.753772)
		(end 80.321658 -50.77333)
		(stroke
			(width 0.0508)
			(type default)
		)
		(layer "In9.Cu")
	)
	(gr_line
		(start 80.323436 -51.062636)
		(end 80.3656 -51.020472)
		(stroke
			(width 0.0508)
			(type default)
		)
		(layer "In9.Cu")
	)
	(gr_line
		(start 80.323436 -50.775108)
		(end 80.3656 -50.817272)
		(stroke
			(width 0.0508)
			(type default)
		)
		(layer "In9.Cu")
	)
	(gr_line
		(start 80.376776 -43.397424)
		(end 80.619092 -43.63974)
		(stroke
			(width 0.05715)
			(type default)
		)
		(layer "In9.Cu")
	)
	(gr_line
		(start 80.478376 -49.536858)
		(end 80.478376 -49.78654)
		(stroke
			(width 0.05715)
			(type default)
		)
		(layer "In9.Cu")
	)
	(gr_line
		(start 80.50022 -55.31866)
		(end 80.59674 -55.22214)
		(stroke
			(width 0.0508)
			(type default)
		)
		(layer "In9.Cu")
	)
	(gr_line
		(start 80.59674 -55.22214)
		(end 80.90154 -55.22214)
		(stroke
			(width 0.0508)
			(type default)
		)
		(layer "In9.Cu")
	)
	(gr_line
		(start 80.619092 -43.63974)
		(end 80.619092 -43.937936)
		(stroke
			(width 0.05715)
			(type default)
		)
		(layer "In9.Cu")
	)
	(gr_line
		(start 80.67294 -50.814732)
		(end 80.76946 -50.718212)
		(stroke
			(width 0.0508)
			(type default)
		)
		(layer "In9.Cu")
	)
	(gr_line
		(start 80.70342 -55.5244)
		(end 80.79486 -55.5244)
		(stroke
			(width 0.0508)
			(type default)
		)
		(layer "In9.Cu")
	)
	(gr_line
		(start 80.76946 -50.718212)
		(end 81.07426 -50.718212)
		(stroke
			(width 0.0508)
			(type default)
		)
		(layer "In9.Cu")
	)
	(gr_line
		(start 80.86344 -44.652946)
		(end 80.936846 -44.726352)
		(stroke
			(width 0.05715)
			(type default)
		)
		(layer "In9.Cu")
	)
	(gr_line
		(start 80.865218 -44.184062)
		(end 81.163414 -44.184062)
		(stroke
			(width 0.05715)
			(type default)
		)
		(layer "In9.Cu")
	)
	(gr_line
		(start 80.87614 -51.020472)
		(end 80.96758 -51.020472)
		(stroke
			(width 0.0508)
			(type default)
		)
		(layer "In9.Cu")
	)
	(gr_line
		(start 80.90154 -55.22214)
		(end 80.99806 -55.31866)
		(stroke
			(width 0.0508)
			(type default)
		)
		(layer "In9.Cu")
	)
	(gr_line
		(start 80.91424 -49.50206)
		(end 81.229454 -49.50206)
		(stroke
			(width 0.05715)
			(type default)
		)
		(layer "In9.Cu")
	)
	(gr_line
		(start 80.9371 -51.88966)
		(end 81.03362 -51.79314)
		(stroke
			(width 0.0508)
			(type default)
		)
		(layer "In9.Cu")
	)
	(gr_line
		(start 81.03362 -51.79314)
		(end 81.33842 -51.79314)
		(stroke
			(width 0.0508)
			(type default)
		)
		(layer "In9.Cu")
	)
	(gr_line
		(start 81.07426 -50.718212)
		(end 81.17078 -50.814732)
		(stroke
			(width 0.0508)
			(type default)
		)
		(layer "In9.Cu")
	)
	(gr_line
		(start 81.1403 -52.0954)
		(end 81.23174 -52.0954)
		(stroke
			(width 0.0508)
			(type default)
		)
		(layer "In9.Cu")
	)
	(gr_line
		(start 81.163414 -44.184062)
		(end 81.40573 -44.426378)
		(stroke
			(width 0.05715)
			(type default)
		)
		(layer "In9.Cu")
	)
	(gr_line
		(start 81.33842 -51.79314)
		(end 81.43494 -51.88966)
		(stroke
			(width 0.0508)
			(type default)
		)
		(layer "In9.Cu")
	)
	(gr_line
		(start 81.3562 -56.2356)
		(end 81.493106 -56.2356)
		(stroke
			(width 0.0508)
			(type default)
		)
		(layer "In9.Cu")
	)
	(gr_line
		(start 81.3562 -55.9054)
		(end 81.493106 -55.9054)
		(stroke
			(width 0.0508)
			(type default)
		)
		(layer "In9.Cu")
	)
	(gr_line
		(start 81.40573 -44.426378)
		(end 81.40573 -44.724574)
		(stroke
			(width 0.05715)
			(type default)
		)
		(layer "In9.Cu")
	)
	(gr_line
		(start 81.493106 -56.2356)
		(end 81.512664 -56.216042)
		(stroke
			(width 0.0508)
			(type default)
		)
		(layer "In9.Cu")
	)
	(gr_line
		(start 81.493106 -55.9054)
		(end 81.512664 -55.924958)
		(stroke
			(width 0.0508)
			(type default)
		)
		(layer "In9.Cu")
	)
	(gr_line
		(start 81.514442 -56.214264)
		(end 81.556606 -56.1721)
		(stroke
			(width 0.0508)
			(type default)
		)
		(layer "In9.Cu")
	)
	(gr_line
		(start 81.514442 -55.926736)
		(end 81.556606 -55.9689)
		(stroke
			(width 0.0508)
			(type default)
		)
		(layer "In9.Cu")
	)
	(gr_line
		(start 81.521554 -54.964838)
		(end 81.521554 -55.10149)
		(stroke
			(width 0.0508)
			(type default)
		)
		(layer "In9.Cu")
	)
	(gr_line
		(start 81.521554 -54.964838)
		(end 81.7372 -54.749446)
		(stroke
			(width 0.0508)
			(type default)
		)
		(layer "In9.Cu")
	)
	(gr_line
		(start 81.7372 -54.749446)
		(end 81.873598 -54.749446)
		(stroke
			(width 0.0508)
			(type default)
		)
		(layer "In9.Cu")
	)
	(gr_line
		(start 81.74482 -51.88966)
		(end 81.84134 -51.79314)
		(stroke
			(width 0.0508)
			(type default)
		)
		(layer "In9.Cu")
	)
	(gr_line
		(start 81.81086 -55.103268)
		(end 81.875376 -55.038752)
		(stroke
			(width 0.0508)
			(type default)
		)
		(layer "In9.Cu")
	)
	(gr_line
		(start 81.84134 -51.79314)
		(end 82.14614 -51.79314)
		(stroke
			(width 0.0508)
			(type default)
		)
		(layer "In9.Cu")
	)
	(gr_line
		(start 81.8642 -45.3009)
		(end 81.8896 -45.3009)
		(stroke
			(width 0.0508)
			(type default)
		)
		(layer "In9.Cu")
	)
	(gr_line
		(start 81.8642 -44.9707)
		(end 81.8896 -44.9707)
		(stroke
			(width 0.0508)
			(type default)
		)
		(layer "In9.Cu")
	)
	(gr_line
		(start 81.8896 -45.3009)
		(end 81.909158 -45.281342)
		(stroke
			(width 0.0508)
			(type default)
		)
		(layer "In9.Cu")
	)
	(gr_line
		(start 81.8896 -44.9707)
		(end 81.909158 -44.990258)
		(stroke
			(width 0.0508)
			(type default)
		)
		(layer "In9.Cu")
	)
	(gr_line
		(start 81.910936 -45.279564)
		(end 81.9531 -45.2374)
		(stroke
			(width 0.0508)
			(type default)
		)
		(layer "In9.Cu")
	)
	(gr_line
		(start 81.910936 -44.992036)
		(end 81.9531 -45.0342)
		(stroke
			(width 0.0508)
			(type default)
		)
		(layer "In9.Cu")
	)
	(gr_line
		(start 81.94802 -52.0954)
		(end 82.03946 -52.0954)
		(stroke
			(width 0.0508)
			(type default)
		)
		(layer "In9.Cu")
	)
	(gr_line
		(start 82.093562 -55.586884)
		(end 82.093562 -55.723282)
		(stroke
			(width 0.0508)
			(type default)
		)
		(layer "In9.Cu")
	)
	(gr_line
		(start 82.093562 -55.586884)
		(end 82.308954 -55.371238)
		(stroke
			(width 0.0508)
			(type default)
		)
		(layer "In9.Cu")
	)
	(gr_line
		(start 82.14614 -51.79314)
		(end 82.24266 -51.88966)
		(stroke
			(width 0.0508)
			(type default)
		)
		(layer "In9.Cu")
	)
	(gr_line
		(start 82.296 -13.9446)
		(end 82.492596 -14.141196)
		(stroke
			(width 0.05715)
			(type default)
		)
		(layer "In9.Cu")
	)
	(gr_line
		(start 82.308446 -53.7718)
		(end 82.308446 -53.908198)
		(stroke
			(width 0.0508)
			(type default)
		)
		(layer "In9.Cu")
	)
	(gr_line
		(start 82.308446 -53.7718)
		(end 82.523838 -53.556154)
		(stroke
			(width 0.0508)
			(type default)
		)
		(layer "In9.Cu")
	)
	(gr_line
		(start 82.308954 -55.371238)
		(end 82.445606 -55.371238)
		(stroke
			(width 0.0508)
			(type default)
		)
		(layer "In9.Cu")
	)
	(gr_line
		(start 82.382868 -55.72506)
		(end 82.447384 -55.660544)
		(stroke
			(width 0.0508)
			(type default)
		)
		(layer "In9.Cu")
	)
	(gr_line
		(start 82.523838 -53.556154)
		(end 82.66049 -53.556154)
		(stroke
			(width 0.0508)
			(type default)
		)
		(layer "In9.Cu")
	)
	(gr_line
		(start 82.597752 -53.909976)
		(end 82.662268 -53.84546)
		(stroke
			(width 0.0508)
			(type default)
		)
		(layer "In9.Cu")
	)
	(gr_line
		(start 82.664554 -55.015638)
		(end 82.664554 -55.15229)
		(stroke
			(width 0.0508)
			(type default)
		)
		(layer "In9.Cu")
	)
	(gr_line
		(start 82.664554 -55.015638)
		(end 82.8802 -54.800246)
		(stroke
			(width 0.0508)
			(type default)
		)
		(layer "In9.Cu")
	)
	(gr_line
		(start 82.720942 -48.889158)
		(end 82.9437 -48.6664)
		(stroke
			(width 0.0508)
			(type default)
		)
		(layer "In9.Cu")
	)
	(gr_line
		(start 82.72272 -49.178464)
		(end 82.947764 -49.178464)
		(stroke
			(width 0.0508)
			(type default)
		)
		(layer "In9.Cu")
	)
	(gr_line
		(start 82.876898 -56.656986)
		(end 82.922618 -56.656986)
		(stroke
			(width 0.0508)
			(type default)
		)
		(layer "In9.Cu")
	)
	(gr_line
		(start 82.879438 -53.200554)
		(end 82.879438 -53.337206)
		(stroke
			(width 0.0508)
			(type default)
		)
		(layer "In9.Cu")
	)
	(gr_line
		(start 82.879438 -53.200554)
		(end 83.095084 -52.985162)
		(stroke
			(width 0.0508)
			(type default)
		)
		(layer "In9.Cu")
	)
	(gr_line
		(start 82.8802 -54.800246)
		(end 83.016598 -54.800246)
		(stroke
			(width 0.0508)
			(type default)
		)
		(layer "In9.Cu")
	)
	(gr_line
		(start 82.925158 -56.656986)
		(end 82.96656 -56.656986)
		(stroke
			(width 0.0508)
			(type default)
		)
		(layer "In9.Cu")
	)
	(gr_line
		(start 82.947764 -49.178464)
		(end 83.0199 -49.2506)
		(stroke
			(width 0.0508)
			(type default)
		)
		(layer "In9.Cu")
	)
	(gr_line
		(start 82.95386 -55.154068)
		(end 83.018376 -55.089552)
		(stroke
			(width 0.0508)
			(type default)
		)
		(layer "In9.Cu")
	)
	(gr_line
		(start 82.963004 -14.141196)
		(end 83.1596 -13.9446)
		(stroke
			(width 0.05715)
			(type default)
		)
		(layer "In9.Cu")
	)
	(gr_line
		(start 83.095084 -52.985162)
		(end 83.231482 -52.985162)
		(stroke
			(width 0.0508)
			(type default)
		)
		(layer "In9.Cu")
	)
	(gr_line
		(start 83.110578 -56.890666)
		(end 83.128358 -56.872886)
		(stroke
			(width 0.0508)
			(type default)
		)
		(layer "In9.Cu")
	)
	(gr_line
		(start 83.128358 -56.862726)
		(end 83.128358 -56.872886)
		(stroke
			(width 0.0508)
			(type default)
		)
		(layer "In9.Cu")
	)
	(gr_line
		(start 83.128358 -56.78297)
		(end 83.128358 -56.860186)
		(stroke
			(width 0.0508)
			(type default)
		)
		(layer "In9.Cu")
	)
	(gr_line
		(start 83.168744 -53.338984)
		(end 83.23326 -53.274468)
		(stroke
			(width 0.0508)
			(type default)
		)
		(layer "In9.Cu")
	)
	(gr_line
		(start 83.444588 -49.532286)
		(end 83.444588 -49.90211)
		(stroke
			(width 0.0508)
			(type default)
		)
		(layer "In9.Cu")
	)
	(gr_line
		(start 83.444588 -49.532286)
		(end 83.812888 -49.163986)
		(stroke
			(width 0.0508)
			(type default)
		)
		(layer "In9.Cu")
	)
	(gr_line
		(start 83.617562 -53.351684)
		(end 83.617562 -53.488082)
		(stroke
			(width 0.0508)
			(type default)
		)
		(layer "In9.Cu")
	)
	(gr_line
		(start 83.617562 -53.351684)
		(end 83.832954 -53.136038)
		(stroke
			(width 0.0508)
			(type default)
		)
		(layer "In9.Cu")
	)
	(gr_line
		(start 83.733894 -49.903888)
		(end 83.752182 -49.8856)
		(stroke
			(width 0.0508)
			(type default)
		)
		(layer "In9.Cu")
	)
	(gr_line
		(start 83.752182 -49.8856)
		(end 83.812888 -49.8856)
		(stroke
			(width 0.0508)
			(type default)
		)
		(layer "In9.Cu")
	)
	(gr_line
		(start 83.820762 -55.662322)
		(end 83.820762 -55.799482)
		(stroke
			(width 0.0508)
			(type default)
		)
		(layer "In9.Cu")
	)
	(gr_line
		(start 83.820762 -55.662322)
		(end 84.036154 -55.44693)
		(stroke
			(width 0.0508)
			(type default)
		)
		(layer "In9.Cu")
	)
	(gr_line
		(start 83.832954 -53.136038)
		(end 83.969606 -53.136038)
		(stroke
			(width 0.0508)
			(type default)
		)
		(layer "In9.Cu")
	)
	(gr_line
		(start 83.906868 -53.48986)
		(end 83.971384 -53.425344)
		(stroke
			(width 0.0508)
			(type default)
		)
		(layer "In9.Cu")
	)
	(gr_line
		(start 83.934046 -56.629554)
		(end 83.95208 -56.61152)
		(stroke
			(width 0.0508)
			(type default)
		)
		(layer "In9.Cu")
	)
	(gr_line
		(start 83.95208 -56.61152)
		(end 83.979512 -56.61152)
		(stroke
			(width 0.0508)
			(type default)
		)
		(layer "In9.Cu")
	)
	(gr_line
		(start 83.982052 -56.61152)
		(end 84.041996 -56.61152)
		(stroke
			(width 0.0508)
			(type default)
		)
		(layer "In9.Cu")
	)
	(gr_line
		(start 83.985354 -55.925974)
		(end 84.299806 -55.611522)
		(stroke
			(width 0.0508)
			(type default)
		)
		(layer "In9.Cu")
	)
	(gr_line
		(start 84.036154 -55.44693)
		(end 84.173314 -55.44693)
		(stroke
			(width 0.0508)
			(type default)
		)
		(layer "In9.Cu")
	)
	(gr_line
		(start 84.167472 -56.863234)
		(end 84.185506 -56.8452)
		(stroke
			(width 0.0508)
			(type default)
		)
		(layer "In9.Cu")
	)
	(gr_line
		(start 84.185252 -56.844692)
		(end 84.185506 -56.844946)
		(stroke
			(width 0.0508)
			(type default)
		)
		(layer "In9.Cu")
	)
	(gr_line
		(start 84.185252 -56.81726)
		(end 84.185252 -56.844692)
		(stroke
			(width 0.0508)
			(type default)
		)
		(layer "In9.Cu")
	)
	(gr_line
		(start 84.185252 -56.755792)
		(end 84.185252 -56.81472)
		(stroke
			(width 0.0508)
			(type default)
		)
		(layer "In9.Cu")
	)
	(gr_line
		(start 84.185506 -56.844946)
		(end 84.185506 -56.8452)
		(stroke
			(width 0.0508)
			(type default)
		)
		(layer "In9.Cu")
	)
	(gr_line
		(start 84.188554 -52.780438)
		(end 84.188554 -52.91709)
		(stroke
			(width 0.0508)
			(type default)
		)
		(layer "In9.Cu")
	)
	(gr_line
		(start 84.188554 -52.780438)
		(end 84.4042 -52.565046)
		(stroke
			(width 0.0508)
			(type default)
		)
		(layer "In9.Cu")
	)
	(gr_line
		(start 84.201 -49.031144)
		(end 84.201 -49.056544)
		(stroke
			(width 0.0508)
			(type default)
		)
		(layer "In9.Cu")
	)
	(gr_line
		(start 84.310728 -48.827944)
		(end 84.310728 -48.853344)
		(stroke
			(width 0.0508)
			(type default)
		)
		(layer "In9.Cu")
	)
	(gr_line
		(start 84.4042 -52.565046)
		(end 84.540598 -52.565046)
		(stroke
			(width 0.0508)
			(type default)
		)
		(layer "In9.Cu")
	)
	(gr_line
		(start 84.47786 -52.918868)
		(end 84.542376 -52.854352)
		(stroke
			(width 0.0508)
			(type default)
		)
		(layer "In9.Cu")
	)
	(gr_line
		(start 84.601304 -48.550068)
		(end 84.834984 -48.783748)
		(stroke
			(width 0.0508)
			(type default)
		)
		(layer "In9.Cu")
	)
	(gr_line
		(start 84.605622 -57.014872)
		(end 84.695284 -57.014872)
		(stroke
			(width 0.0508)
			(type default)
		)
		(layer "In9.Cu")
	)
	(gr_line
		(start 84.774532 -48.344328)
		(end 85.015578 -48.103282)
		(stroke
			(width 0.0508)
			(type default)
		)
		(layer "In9.Cu")
	)
	(gr_line
		(start 84.834984 -48.783748)
		(end 84.834984 -48.784002)
		(stroke
			(width 0.0508)
			(type default)
		)
		(layer "In9.Cu")
	)
	(gr_line
		(start 84.839302 -57.248298)
		(end 84.93633 -57.15127)
		(stroke
			(width 0.0508)
			(type default)
		)
		(layer "In9.Cu")
	)
	(gr_line
		(start 84.86394 -54.20614)
		(end 84.96046 -54.30266)
		(stroke
			(width 0.0508)
			(type default)
		)
		(layer "In9.Cu")
	)
	(gr_line
		(start 84.86394 -53.90134)
		(end 84.86394 -54.20614)
		(stroke
			(width 0.0508)
			(type default)
		)
		(layer "In9.Cu")
	)
	(gr_line
		(start 84.86394 -53.90134)
		(end 84.96046 -53.80482)
		(stroke
			(width 0.0508)
			(type default)
		)
		(layer "In9.Cu")
	)
	(gr_line
		(start 84.93633 -57.06491)
		(end 84.93633 -57.15127)
		(stroke
			(width 0.0508)
			(type default)
		)
		(layer "In9.Cu")
	)
	(gr_line
		(start 85.1662 -54.00802)
		(end 85.1662 -54.09946)
		(stroke
			(width 0.0508)
			(type default)
		)
		(layer "In9.Cu")
	)
	(gr_line
		(start 85.4837 -48.534828)
		(end 85.504528 -48.514)
		(stroke
			(width 0.0508)
			(type default)
		)
		(layer "In9.Cu")
	)
	(gr_line
		(start 85.5472 -48.3108)
		(end 85.568028 -48.289972)
		(stroke
			(width 0.0508)
			(type default)
		)
		(layer "In9.Cu")
	)
	(gr_line
		(start 85.569806 -48.288194)
		(end 85.8012 -48.0568)
		(stroke
			(width 0.0508)
			(type default)
		)
		(layer "In9.Cu")
	)
	(gr_line
		(start 85.648292 -48.514)
		(end 85.8012 -48.666908)
		(stroke
			(width 0.0508)
			(type default)
		)
		(layer "In9.Cu")
	)
	(gr_line
		(start 85.661754 -50.76571)
		(end 85.661754 -50.902362)
		(stroke
			(width 0.0508)
			(type default)
		)
		(layer "In9.Cu")
	)
	(gr_line
		(start 85.661754 -50.76571)
		(end 85.8774 -50.550318)
		(stroke
			(width 0.0508)
			(type default)
		)
		(layer "In9.Cu")
	)
	(gr_line
		(start 85.8012 -48.666908)
		(end 85.8012 -48.8188)
		(stroke
			(width 0.0508)
			(type default)
		)
		(layer "In9.Cu")
	)
	(gr_line
		(start 85.8774 -50.550318)
		(end 86.013798 -50.550318)
		(stroke
			(width 0.0508)
			(type default)
		)
		(layer "In9.Cu")
	)
	(gr_line
		(start 85.95106 -50.90414)
		(end 86.015576 -50.839624)
		(stroke
			(width 0.0508)
			(type default)
		)
		(layer "In9.Cu")
	)
	(gr_line
		(start 85.975444 -57.29224)
		(end 85.984588 -57.283096)
		(stroke
			(width 0.0508)
			(type default)
		)
		(layer "In9.Cu")
	)
	(gr_line
		(start 85.984588 -57.283096)
		(end 86.00313 -57.283096)
		(stroke
			(width 0.0508)
			(type default)
		)
		(layer "In9.Cu")
	)
	(gr_line
		(start 86.00567 -57.283096)
		(end 86.074504 -57.283096)
		(stroke
			(width 0.0508)
			(type default)
		)
		(layer "In9.Cu")
	)
	(gr_line
		(start 86.20887 -57.488836)
		(end 86.20887 -57.52592)
		(stroke
			(width 0.0508)
			(type default)
		)
		(layer "In9.Cu")
	)
	(gr_line
		(start 86.20887 -57.436258)
		(end 86.20887 -57.486296)
		(stroke
			(width 0.0508)
			(type default)
		)
		(layer "In9.Cu")
	)
	(gr_line
		(start 86.757764 -48.4632)
		(end 86.818724 -48.40224)
		(stroke
			(width 0.0508)
			(type default)
		)
		(layer "In9.Cu")
	)
	(gr_line
		(start 86.795356 -48.6664)
		(end 86.818724 -48.689768)
		(stroke
			(width 0.0508)
			(type default)
		)
		(layer "In9.Cu")
	)
	(gr_line
		(start 86.820502 -48.691546)
		(end 86.954106 -48.82515)
		(stroke
			(width 0.0508)
			(type default)
		)
		(layer "In9.Cu")
	)
	(gr_line
		(start 86.820502 -48.400462)
		(end 86.954868 -48.266096)
		(stroke
			(width 0.0508)
			(type default)
		)
		(layer "In9.Cu")
	)
	(gr_line
		(start 86.887812 -45.97146)
		(end 86.984332 -45.87494)
		(stroke
			(width 0.0508)
			(type default)
		)
		(layer "In9.Cu")
	)
	(gr_line
		(start 86.984332 -45.87494)
		(end 87.289132 -45.87494)
		(stroke
			(width 0.0508)
			(type default)
		)
		(layer "In9.Cu")
	)
	(gr_line
		(start 87.091012 -46.1772)
		(end 87.182452 -46.1772)
		(stroke
			(width 0.0508)
			(type default)
		)
		(layer "In9.Cu")
	)
	(gr_line
		(start 87.289132 -45.87494)
		(end 87.385652 -45.97146)
		(stroke
			(width 0.0508)
			(type default)
		)
		(layer "In9.Cu")
	)
	(gr_line
		(start 87.389462 -48.754538)
		(end 87.389462 -49.101756)
		(stroke
			(width 0.0508)
			(type default)
		)
		(layer "In9.Cu")
	)
	(gr_line
		(start 87.389462 -48.754538)
		(end 87.757 -48.387)
		(stroke
			(width 0.0508)
			(type default)
		)
		(layer "In9.Cu")
	)
	(gr_line
		(start 87.595202 -49.304956)
		(end 87.757762 -49.142396)
		(stroke
			(width 0.0508)
			(type default)
		)
		(layer "In9.Cu")
	)
	(gr_line
		(start 88.114124 -50.145696)
		(end 88.210644 -50.242216)
		(stroke
			(width 0.0508)
			(type default)
		)
		(layer "In9.Cu")
	)
	(gr_line
		(start 88.114124 -49.840896)
		(end 88.114124 -50.145696)
		(stroke
			(width 0.0508)
			(type default)
		)
		(layer "In9.Cu")
	)
	(gr_line
		(start 88.114124 -49.840896)
		(end 88.210644 -49.744376)
		(stroke
			(width 0.0508)
			(type default)
		)
		(layer "In9.Cu")
	)
	(gr_line
		(start 88.134952 -46.478952)
		(end 88.199468 -46.543468)
		(stroke
			(width 0.0508)
			(type default)
		)
		(layer "In9.Cu")
	)
	(gr_line
		(start 88.13673 -46.189646)
		(end 88.273128 -46.189646)
		(stroke
			(width 0.0508)
			(type default)
		)
		(layer "In9.Cu")
	)
	(gr_line
		(start 88.213184 -48.642016)
		(end 88.213184 -48.770794)
		(stroke
			(width 0.0508)
			(type default)
		)
		(layer "In9.Cu")
	)
	(gr_line
		(start 88.213184 -48.642016)
		(end 88.6714 -48.1838)
		(stroke
			(width 0.0508)
			(type default)
		)
		(layer "In9.Cu")
	)
	(gr_line
		(start 88.273128 -46.189646)
		(end 88.488774 -46.405038)
		(stroke
			(width 0.0508)
			(type default)
		)
		(layer "In9.Cu")
	)
	(gr_line
		(start 88.416384 -49.947576)
		(end 88.416384 -50.039016)
		(stroke
			(width 0.0508)
			(type default)
		)
		(layer "In9.Cu")
	)
	(gr_line
		(start 88.418924 -48.973994)
		(end 88.650318 -48.7426)
		(stroke
			(width 0.0508)
			(type default)
		)
		(layer "In9.Cu")
	)
	(gr_line
		(start 88.488774 -46.405038)
		(end 88.488774 -46.54169)
		(stroke
			(width 0.0508)
			(type default)
		)
		(layer "In9.Cu")
	)
	(gr_line
		(start 88.650318 -48.7426)
		(end 88.6714 -48.7426)
		(stroke
			(width 0.0508)
			(type default)
		)
		(layer "In9.Cu")
	)
	(gr_line
		(start 89.217246 -55.1942)
		(end 89.217246 -55.330598)
		(stroke
			(width 0.0508)
			(type default)
		)
		(layer "In9.Cu")
	)
	(gr_line
		(start 89.217246 -55.1942)
		(end 89.432638 -54.978554)
		(stroke
			(width 0.0508)
			(type default)
		)
		(layer "In9.Cu")
	)
	(gr_line
		(start 89.349326 -51.787044)
		(end 89.445846 -51.883564)
		(stroke
			(width 0.0508)
			(type default)
		)
		(layer "In9.Cu")
	)
	(gr_line
		(start 89.349326 -51.482244)
		(end 89.349326 -51.787044)
		(stroke
			(width 0.0508)
			(type default)
		)
		(layer "In9.Cu")
	)
	(gr_line
		(start 89.349326 -51.482244)
		(end 89.445846 -51.385724)
		(stroke
			(width 0.0508)
			(type default)
		)
		(layer "In9.Cu")
	)
	(gr_line
		(start 89.432638 -54.978554)
		(end 89.56929 -54.978554)
		(stroke
			(width 0.0508)
			(type default)
		)
		(layer "In9.Cu")
	)
	(gr_line
		(start 89.442798 -46.776132)
		(end 89.489788 -46.729142)
		(stroke
			(width 0.0508)
			(type default)
		)
		(layer "In9.Cu")
	)
	(gr_line
		(start 89.448386 -49.151794)
		(end 89.448386 -49.504854)
		(stroke
			(width 0.0508)
			(type default)
		)
		(layer "In9.Cu")
	)
	(gr_line
		(start 89.448386 -49.151794)
		(end 89.82075 -48.77943)
		(stroke
			(width 0.0508)
			(type default)
		)
		(layer "In9.Cu")
	)
	(gr_line
		(start 89.452704 -46.979332)
		(end 89.489788 -47.016416)
		(stroke
			(width 0.0508)
			(type default)
		)
		(layer "In9.Cu")
	)
	(gr_line
		(start 89.491566 -47.018194)
		(end 89.748868 -47.275496)
		(stroke
			(width 0.0508)
			(type default)
		)
		(layer "In9.Cu")
	)
	(gr_line
		(start 89.491566 -46.727364)
		(end 89.738708 -46.480222)
		(stroke
			(width 0.0508)
			(type default)
		)
		(layer "In9.Cu")
	)
	(gr_line
		(start 89.506552 -55.332376)
		(end 89.571068 -55.26786)
		(stroke
			(width 0.0508)
			(type default)
		)
		(layer "In9.Cu")
	)
	(gr_line
		(start 89.651586 -51.588924)
		(end 89.651586 -51.680364)
		(stroke
			(width 0.0508)
			(type default)
		)
		(layer "In9.Cu")
	)
	(gr_line
		(start 89.654126 -49.708054)
		(end 89.82075 -49.54143)
		(stroke
			(width 0.0508)
			(type default)
		)
		(layer "In9.Cu")
	)
	(gr_line
		(start 90.18905 -49.51095)
		(end 90.18905 -49.68621)
		(stroke
			(width 0.0508)
			(type default)
		)
		(layer "In9.Cu")
	)
	(gr_line
		(start 90.18905 -49.51095)
		(end 90.6018 -49.0982)
		(stroke
			(width 0.0508)
			(type default)
		)
		(layer "In9.Cu")
	)
	(gr_line
		(start 90.39479 -49.88941)
		(end 90.5764 -49.7078)
		(stroke
			(width 0.0508)
			(type default)
		)
		(layer "In9.Cu")
	)
	(gr_line
		(start 90.41384 -52.635912)
		(end 90.51036 -52.732432)
		(stroke
			(width 0.0508)
			(type default)
		)
		(layer "In9.Cu")
	)
	(gr_line
		(start 90.41384 -52.331112)
		(end 90.41384 -52.635912)
		(stroke
			(width 0.0508)
			(type default)
		)
		(layer "In9.Cu")
	)
	(gr_line
		(start 90.41384 -52.331112)
		(end 90.51036 -52.234592)
		(stroke
			(width 0.0508)
			(type default)
		)
		(layer "In9.Cu")
	)
	(gr_line
		(start 90.41384 -51.828192)
		(end 90.51036 -51.924712)
		(stroke
			(width 0.0508)
			(type default)
		)
		(layer "In9.Cu")
	)
	(gr_line
		(start 90.41384 -51.523392)
		(end 90.41384 -51.828192)
		(stroke
			(width 0.0508)
			(type default)
		)
		(layer "In9.Cu")
	)
	(gr_line
		(start 90.41384 -51.523392)
		(end 90.51036 -51.426872)
		(stroke
			(width 0.0508)
			(type default)
		)
		(layer "In9.Cu")
	)
	(gr_line
		(start 90.7161 -52.437792)
		(end 90.7161 -52.529232)
		(stroke
			(width 0.0508)
			(type default)
		)
		(layer "In9.Cu")
	)
	(gr_line
		(start 90.7161 -51.630072)
		(end 90.7161 -51.721512)
		(stroke
			(width 0.0508)
			(type default)
		)
		(layer "In9.Cu")
	)
	(gr_line
		(start 96.9137 -61.38926)
		(end 97.12452 -61.17844)
		(stroke
			(width 0.05715)
			(type default)
		)
		(layer "In9.Cu")
	)
	(gr_line
		(start 97.12452 -61.17844)
		(end 97.46742 -61.17844)
		(stroke
			(width 0.05715)
			(type default)
		)
		(layer "In9.Cu")
	)
	(gr_line
		(start 97.2439 -61.722)
		(end 97.34804 -61.722)
		(stroke
			(width 0.05715)
			(type default)
		)
		(layer "In9.Cu")
	)
	(gr_line
		(start 97.46742 -61.17844)
		(end 97.67824 -61.38926)
		(stroke
			(width 0.05715)
			(type default)
		)
		(layer "In9.Cu")
	)
	(gr_line
		(start 98.02622 -61.38926)
		(end 98.23704 -61.17844)
		(stroke
			(width 0.05715)
			(type default)
		)
		(layer "In9.Cu")
	)
	(gr_line
		(start 98.23704 -61.17844)
		(end 98.57994 -61.17844)
		(stroke
			(width 0.05715)
			(type default)
		)
		(layer "In9.Cu")
	)
	(gr_line
		(start 98.35642 -61.722)
		(end 98.46056 -61.722)
		(stroke
			(width 0.05715)
			(type default)
		)
		(layer "In9.Cu")
	)
	(gr_line
		(start 98.57994 -61.17844)
		(end 98.79076 -61.38926)
		(stroke
			(width 0.05715)
			(type default)
		)
		(layer "In9.Cu")
	)
	(gr_line
		(start 99.514152 -60.916312)
		(end 99.514152 -61.013848)
		(stroke
			(width 0.05715)
			(type default)
		)
		(layer "In9.Cu")
	)
	(gr_line
		(start 99.514152 -60.64504)
		(end 99.514152 -60.913772)
		(stroke
			(width 0.05715)
			(type default)
		)
		(layer "In9.Cu")
	)
	(gr_line
		(start 99.748594 -61.246512)
		(end 99.844352 -61.246512)
		(stroke
			(width 0.05715)
			(type default)
		)
		(layer "In9.Cu")
	)
	(gr_line
		(start 99.846892 -61.246512)
		(end 100.134166 -61.246512)
		(stroke
			(width 0.05715)
			(type default)
		)
		(layer "In9.Cu")
	)
	(gr_line
		(start 101.456236 -62.36335)
		(end 101.457252 -61.935106)
		(stroke
			(width 0.0635)
			(type default)
		)
		(layer "In9.Cu")
	)
	(gr_line
		(start 101.638354 -62.546992)
		(end 102.066852 -62.546992)
		(stroke
			(width 0.0635)
			(type default)
		)
		(layer "In9.Cu")
	)
	(gr_line
		(start 106.22153 -28.046172)
		(end 106.22153 -28.18257)
		(stroke
			(width 0.0508)
			(type default)
		)
		(layer "In9.Cu")
	)
	(gr_line
		(start 106.22153 -28.046172)
		(end 106.436922 -27.830526)
		(stroke
			(width 0.0508)
			(type default)
		)
		(layer "In9.Cu")
	)
	(gr_line
		(start 106.436922 -27.830526)
		(end 106.573574 -27.830526)
		(stroke
			(width 0.0508)
			(type default)
		)
		(layer "In9.Cu")
	)
	(gr_line
		(start 106.510836 -28.184348)
		(end 106.575352 -28.119832)
		(stroke
			(width 0.0508)
			(type default)
		)
		(layer "In9.Cu")
	)
	(gr_line
		(start 106.747818 -29.80055)
		(end 106.8324 -29.990034)
		(stroke
			(width 0.0508)
			(type default)
		)
		(layer "In9.Cu")
	)
	(gr_line
		(start 106.8324 -29.990034)
		(end 106.8324 -30.0482)
		(stroke
			(width 0.0508)
			(type default)
		)
		(layer "In9.Cu")
	)
	(gr_line
		(start 106.850688 -30.6324)
		(end 107.159044 -30.324044)
		(stroke
			(width 0.0508)
			(type default)
		)
		(layer "In9.Cu")
	)
	(gr_arc
		(start 107.159044 -30.324044)
		(mid 107.236996 -30.195798)
		(end 107.2642 -30.0482)
		(stroke
			(width 0.0508)
			(type default)
		)
		(layer "In9.Cu")
	)
	(gr_arc
		(start 107.1626 -29.7688)
		(mid 107.034167 -29.674991)
		(end 106.878628 -29.6418)
		(stroke
			(width 0.0508)
			(type default)
		)
		(layer "In9.Cu")
	)
	(gr_line
		(start 107.1626 -29.7688)
		(end 107.2134 -29.8196)
		(stroke
			(width 0.0508)
			(type default)
		)
		(layer "In9.Cu")
	)
	(gr_line
		(start 107.198668 -29.266896)
		(end 107.391454 -29.059378)
		(stroke
			(width 0.0508)
			(type default)
		)
		(layer "In9.Cu")
	)
	(gr_arc
		(start 107.2642 -30.0482)
		(mid 107.251348 -29.931111)
		(end 107.2134 -29.8196)
		(stroke
			(width 0.0508)
			(type default)
		)
		(layer "In9.Cu")
	)
	(gr_line
		(start 107.597194 -28.933394)
		(end 107.8738 -29.21)
		(stroke
			(width 0.0508)
			(type default)
		)
		(layer "In9.Cu")
	)
	(gr_line
		(start 108.273342 -27.420316)
		(end 108.369862 -27.323796)
		(stroke
			(width 0.0508)
			(type default)
		)
		(layer "In9.Cu")
	)
	(gr_line
		(start 108.369862 -27.323796)
		(end 108.674662 -27.323796)
		(stroke
			(width 0.0508)
			(type default)
		)
		(layer "In9.Cu")
	)
	(gr_line
		(start 108.476542 -27.626056)
		(end 108.567982 -27.626056)
		(stroke
			(width 0.0508)
			(type default)
		)
		(layer "In9.Cu")
	)
	(gr_line
		(start 108.60024 -26.61158)
		(end 108.8136 -26.61158)
		(stroke
			(width 0.0508)
			(type default)
		)
		(layer "In9.Cu")
	)
	(gr_line
		(start 108.674662 -27.323796)
		(end 108.771182 -27.420316)
		(stroke
			(width 0.0508)
			(type default)
		)
		(layer "In9.Cu")
	)
	(gr_line
		(start 108.6866 -29.0322)
		(end 108.74502 -29.09062)
		(stroke
			(width 0.0508)
			(type default)
		)
		(layer "In9.Cu")
	)
	(gr_line
		(start 108.7374 -29.591)
		(end 108.811568 -29.591)
		(stroke
			(width 0.0508)
			(type default)
		)
		(layer "In9.Cu")
	)
	(gr_line
		(start 108.74502 -29.09062)
		(end 109.020864 -29.09062)
		(stroke
			(width 0.0508)
			(type default)
		)
		(layer "In9.Cu")
	)
	(gr_line
		(start 108.81106 -35.320986)
		(end 109.050074 -35.56)
		(stroke
			(width 0.0508)
			(type default)
		)
		(layer "In9.Cu")
	)
	(gr_line
		(start 108.811568 -29.591)
		(end 109.022642 -29.379926)
		(stroke
			(width 0.0508)
			(type default)
		)
		(layer "In9.Cu")
	)
	(gr_line
		(start 108.8136 -26.61158)
		(end 108.88472 -26.54046)
		(stroke
			(width 0.0508)
			(type default)
		)
		(layer "In9.Cu")
	)
	(gr_line
		(start 108.99267 -27.009598)
		(end 109.09046 -26.911808)
		(stroke
			(width 0.0508)
			(type default)
		)
		(layer "In9.Cu")
	)
	(gr_line
		(start 109.050074 -35.56)
		(end 109.14126 -35.56)
		(stroke
			(width 0.0508)
			(type default)
		)
		(layer "In9.Cu")
	)
	(gr_line
		(start 109.09046 -26.74366)
		(end 109.09046 -26.911808)
		(stroke
			(width 0.0508)
			(type default)
		)
		(layer "In9.Cu")
	)
	(gr_line
		(start 109.1438 -35.56)
		(end 109.241336 -35.56)
		(stroke
			(width 0.0508)
			(type default)
		)
		(layer "In9.Cu")
	)
	(gr_line
		(start 109.347 -36.088574)
		(end 109.396276 -36.13785)
		(stroke
			(width 0.0508)
			(type default)
		)
		(layer "In9.Cu")
	)
	(gr_line
		(start 109.347 -35.76574)
		(end 109.347 -36.088574)
		(stroke
			(width 0.0508)
			(type default)
		)
		(layer "In9.Cu")
	)
	(gr_line
		(start 109.347 -35.741864)
		(end 109.347 -35.7632)
		(stroke
			(width 0.0508)
			(type default)
		)
		(layer "In9.Cu")
	)
	(gr_line
		(start 109.748828 -24.87041)
		(end 109.887512 -24.731726)
		(stroke
			(width 0.0508)
			(type default)
		)
		(layer "In9.Cu")
	)
	(gr_line
		(start 109.757972 -23.2537)
		(end 109.857286 -23.154386)
		(stroke
			(width 0.0508)
			(type default)
		)
		(layer "In9.Cu")
	)
	(gr_line
		(start 109.857286 -23.115016)
		(end 109.857286 -23.154386)
		(stroke
			(width 0.0508)
			(type default)
		)
		(layer "In9.Cu")
	)
	(gr_line
		(start 109.857286 -22.913086)
		(end 109.857286 -23.106888)
		(stroke
			(width 0.0508)
			(type default)
		)
		(layer "In9.Cu")
	)
	(gr_line
		(start 109.887512 -24.638)
		(end 109.887512 -24.731726)
		(stroke
			(width 0.0508)
			(type default)
		)
		(layer "In9.Cu")
	)
	(gr_line
		(start 109.887512 -24.520652)
		(end 109.887512 -24.63546)
		(stroke
			(width 0.0508)
			(type default)
		)
		(layer "In9.Cu")
	)
	(gr_line
		(start 110.065566 -24.8412)
		(end 110.090712 -24.8412)
		(stroke
			(width 0.0508)
			(type default)
		)
		(layer "In9.Cu")
	)
	(gr_line
		(start 110.089696 -23.209504)
		(end 110.153704 -23.209504)
		(stroke
			(width 0.0508)
			(type default)
		)
		(layer "In9.Cu")
	)
	(gr_line
		(start 110.093252 -24.8412)
		(end 110.1598 -24.8412)
		(stroke
			(width 0.0508)
			(type default)
		)
		(layer "In9.Cu")
	)
	(gr_line
		(start 110.153704 -23.209504)
		(end 110.253018 -23.11019)
		(stroke
			(width 0.09525)
			(type default)
		)
		(layer "In9.Cu")
	)
	(gr_line
		(start 110.1598 -24.8412)
		(end 110.298484 -24.702516)
		(stroke
			(width 0.09525)
			(type default)
		)
		(layer "In9.Cu")
	)
	(gr_line
		(start 110.83036 -36.6776)
		(end 110.984792 -36.6776)
		(stroke
			(width 0.0508)
			(type default)
		)
		(layer "In9.Cu")
	)
	(gr_line
		(start 110.884716 -36.47186)
		(end 110.907576 -36.449)
		(stroke
			(width 0.0508)
			(type default)
		)
		(layer "In9.Cu")
	)
	(gr_line
		(start 110.89005 -25.4254)
		(end 110.954058 -25.489408)
		(stroke
			(width 0.0508)
			(type default)
		)
		(layer "In9.Cu")
	)
	(gr_line
		(start 110.907576 -36.449)
		(end 110.920276 -36.4363)
		(stroke
			(width 0.0762)
			(type default)
		)
		(layer "In9.Cu")
	)
	(gr_line
		(start 110.955836 -25.491186)
		(end 111.006636 -25.541986)
		(stroke
			(width 0.0508)
			(type default)
		)
		(layer "In9.Cu")
	)
	(gr_line
		(start 111.006636 -25.541986)
		(end 111.006636 -25.637236)
		(stroke
			(width 0.0508)
			(type default)
		)
		(layer "In9.Cu")
	)
	(gr_line
		(start 111.209836 -25.524714)
		(end 111.243364 -25.491186)
		(stroke
			(width 0.0508)
			(type default)
		)
		(layer "In9.Cu")
	)
	(gr_line
		(start 111.245142 -25.489408)
		(end 111.30915 -25.4254)
		(stroke
			(width 0.0508)
			(type default)
		)
		(layer "In9.Cu")
	)
	(gr_line
		(start 111.30915 -25.272746)
		(end 111.30915 -25.4254)
		(stroke
			(width 0.09525)
			(type default)
		)
		(layer "In9.Cu")
	)
	(gr_line
		(start 111.896144 -26.165302)
		(end 112.030002 -26.031444)
		(stroke
			(width 0.0508)
			(type default)
		)
		(layer "In9.Cu")
	)
	(gr_line
		(start 111.896906 -25.828244)
		(end 111.896906 -25.877012)
		(stroke
			(width 0.0508)
			(type default)
		)
		(layer "In9.Cu")
	)
	(gr_line
		(start 111.896906 -25.74417)
		(end 111.896906 -25.825704)
		(stroke
			(width 0.0508)
			(type default)
		)
		(layer "In9.Cu")
	)
	(gr_line
		(start 111.896906 -25.74417)
		(end 111.90605 -25.735026)
		(stroke
			(width 0.0508)
			(type default)
		)
		(layer "In9.Cu")
	)
	(gr_line
		(start 111.90605 -25.735026)
		(end 112.039908 -25.601168)
		(stroke
			(width 0.09525)
			(type default)
		)
		(layer "In9.Cu")
	)
	(gr_line
		(start 112.030002 -26.031444)
		(end 112.100106 -26.031444)
		(stroke
			(width 0.0508)
			(type default)
		)
		(layer "In9.Cu")
	)
	(gr_line
		(start 112.102646 -26.031444)
		(end 112.202468 -26.031444)
		(stroke
			(width 0.0508)
			(type default)
		)
		(layer "In9.Cu")
	)
	(gr_line
		(start 114.692176 -23.638256)
		(end 114.915696 -23.414736)
		(stroke
			(width 0.09525)
			(type default)
		)
		(layer "In9.Cu")
	)
	(gr_line
		(start 114.915696 -23.414736)
		(end 115.487196 -23.414736)
		(stroke
			(width 0.09525)
			(type default)
		)
		(layer "In9.Cu")
	)
	(gr_line
		(start 115.111276 -24.059896)
		(end 115.291616 -24.059896)
		(stroke
			(width 0.09525)
			(type default)
		)
		(layer "In9.Cu")
	)
	(gr_line
		(start 115.487196 -23.414736)
		(end 115.710716 -23.638256)
		(stroke
			(width 0.09525)
			(type default)
		)
		(layer "In9.Cu")
	)
	(gr_line
		(start 116.232178 -23.640796)
		(end 116.284756 -23.640796)
		(stroke
			(width 0.09525)
			(type default)
		)
		(layer "In9.Cu")
	)
	(gr_line
		(start 116.284756 -23.640796)
		(end 116.510816 -23.414736)
		(stroke
			(width 0.09525)
			(type default)
		)
		(layer "In9.Cu")
	)
	(gr_line
		(start 116.437156 -24.059896)
		(end 116.651278 -23.845774)
		(stroke
			(width 0.09525)
			(type default)
		)
		(layer "In9.Cu")
	)
	(gr_line
		(start 116.510816 -23.414736)
		(end 117.082316 -23.414736)
		(stroke
			(width 0.09525)
			(type default)
		)
		(layer "In9.Cu")
	)
	(gr_line
		(start 116.651278 -23.845774)
		(end 116.703856 -23.845774)
		(stroke
			(width 0.09525)
			(type default)
		)
		(layer "In9.Cu")
	)
	(gr_line
		(start 116.706396 -23.845774)
		(end 116.886736 -23.845774)
		(stroke
			(width 0.09525)
			(type default)
		)
		(layer "In9.Cu")
	)
	(gr_line
		(start 116.889276 -23.845774)
		(end 116.920518 -23.845774)
		(stroke
			(width 0.09525)
			(type default)
		)
		(layer "In9.Cu")
	)
	(gr_line
		(start 117.308376 -23.640796)
		(end 117.339618 -23.640796)
		(stroke
			(width 0.09525)
			(type default)
		)
		(layer "In9.Cu")
	)
	(gr_line
		(start 123.224544 -18.92046)
		(end 123.448064 -18.69694)
		(stroke
			(width 0.09525)
			(type default)
		)
		(layer "In9.Cu")
	)
	(gr_line
		(start 123.448064 -18.69694)
		(end 124.019564 -18.69694)
		(stroke
			(width 0.09525)
			(type default)
		)
		(layer "In9.Cu")
	)
	(gr_line
		(start 123.643644 -19.3421)
		(end 123.823984 -19.3421)
		(stroke
			(width 0.09525)
			(type default)
		)
		(layer "In9.Cu")
	)
	(gr_line
		(start 124.019564 -18.69694)
		(end 124.243084 -18.92046)
		(stroke
			(width 0.09525)
			(type default)
		)
		(layer "In9.Cu")
	)
	(gr_line
		(start 125.71857 -18.92046)
		(end 125.94209 -18.69694)
		(stroke
			(width 0.09525)
			(type default)
		)
		(layer "In9.Cu")
	)
	(gr_line
		(start 125.94209 -18.69694)
		(end 126.51359 -18.69694)
		(stroke
			(width 0.09525)
			(type default)
		)
		(layer "In9.Cu")
	)
	(gr_line
		(start 126.13767 -19.3421)
		(end 126.31801 -19.3421)
		(stroke
			(width 0.09525)
			(type default)
		)
		(layer "In9.Cu")
	)
	(gr_line
		(start 126.51359 -18.69694)
		(end 126.73711 -18.92046)
		(stroke
			(width 0.09525)
			(type default)
		)
		(layer "In9.Cu")
	)
	(gr_line
		(start 127.31369 -18.92046)
		(end 127.53721 -18.69694)
		(stroke
			(width 0.09525)
			(type default)
		)
		(layer "In9.Cu")
	)
	(gr_line
		(start 127.53721 -18.69694)
		(end 128.10871 -18.69694)
		(stroke
			(width 0.09525)
			(type default)
		)
		(layer "In9.Cu")
	)
	(gr_line
		(start 127.73279 -19.3421)
		(end 127.91313 -19.3421)
		(stroke
			(width 0.09525)
			(type default)
		)
		(layer "In9.Cu")
	)
	(gr_line
		(start 128.10871 -18.69694)
		(end 128.33223 -18.92046)
		(stroke
			(width 0.09525)
			(type default)
		)
		(layer "In9.Cu")
	)
	(gr_line
		(start 128.471676 -23.638256)
		(end 128.695196 -23.414736)
		(stroke
			(width 0.09525)
			(type default)
		)
		(layer "In9.Cu")
	)
	(gr_line
		(start 128.695196 -23.414736)
		(end 129.266696 -23.414736)
		(stroke
			(width 0.09525)
			(type default)
		)
		(layer "In9.Cu")
	)
	(gr_line
		(start 128.890776 -24.059896)
		(end 129.071116 -24.059896)
		(stroke
			(width 0.09525)
			(type default)
		)
		(layer "In9.Cu")
	)
	(gr_line
		(start 128.90881 -18.92046)
		(end 129.13233 -18.69694)
		(stroke
			(width 0.09525)
			(type default)
		)
		(layer "In9.Cu")
	)
	(gr_line
		(start 129.13233 -18.69694)
		(end 129.70383 -18.69694)
		(stroke
			(width 0.09525)
			(type default)
		)
		(layer "In9.Cu")
	)
	(gr_line
		(start 129.266696 -23.414736)
		(end 129.490216 -23.638256)
		(stroke
			(width 0.09525)
			(type default)
		)
		(layer "In9.Cu")
	)
	(gr_line
		(start 129.32791 -19.3421)
		(end 129.50825 -19.3421)
		(stroke
			(width 0.09525)
			(type default)
		)
		(layer "In9.Cu")
	)
	(gr_line
		(start 129.70383 -18.69694)
		(end 129.92735 -18.92046)
		(stroke
			(width 0.09525)
			(type default)
		)
		(layer "In9.Cu")
	)
	(gr_line
		(start 130.93827 -18.92046)
		(end 131.16179 -18.69694)
		(stroke
			(width 0.09525)
			(type default)
		)
		(layer "In9.Cu")
	)
	(gr_line
		(start 131.16179 -18.69694)
		(end 131.73329 -18.69694)
		(stroke
			(width 0.09525)
			(type default)
		)
		(layer "In9.Cu")
	)
	(gr_line
		(start 131.35737 -19.3421)
		(end 131.53771 -19.3421)
		(stroke
			(width 0.09525)
			(type default)
		)
		(layer "In9.Cu")
	)
	(gr_line
		(start 131.73329 -18.69694)
		(end 131.95681 -18.92046)
		(stroke
			(width 0.09525)
			(type default)
		)
		(layer "In9.Cu")
	)
	(gr_line
		(start 132.53339 -18.92046)
		(end 132.75691 -18.69694)
		(stroke
			(width 0.09525)
			(type default)
		)
		(layer "In9.Cu")
	)
	(gr_line
		(start 132.75691 -18.69694)
		(end 133.32841 -18.69694)
		(stroke
			(width 0.09525)
			(type default)
		)
		(layer "In9.Cu")
	)
	(gr_line
		(start 132.95249 -19.3421)
		(end 133.13283 -19.3421)
		(stroke
			(width 0.09525)
			(type default)
		)
		(layer "In9.Cu")
	)
	(gr_line
		(start 133.32841 -18.69694)
		(end 133.55193 -18.92046)
		(stroke
			(width 0.09525)
			(type default)
		)
		(layer "In9.Cu")
	)
	(gr_line
		(start 134.12851 -18.92046)
		(end 134.35203 -18.69694)
		(stroke
			(width 0.09525)
			(type default)
		)
		(layer "In9.Cu")
	)
	(gr_line
		(start 134.35203 -18.69694)
		(end 134.92353 -18.69694)
		(stroke
			(width 0.09525)
			(type default)
		)
		(layer "In9.Cu")
	)
	(gr_line
		(start 134.54761 -19.3421)
		(end 134.72795 -19.3421)
		(stroke
			(width 0.09525)
			(type default)
		)
		(layer "In9.Cu")
	)
	(gr_line
		(start 134.92353 -18.69694)
		(end 135.14705 -18.92046)
		(stroke
			(width 0.09525)
			(type default)
		)
		(layer "In9.Cu")
	)
	(gr_line
		(start 135.678164 -36.87826)
		(end 135.800084 -36.75634)
		(stroke
			(width 0.0762)
			(type default)
		)
		(layer "In9.Cu")
	)
	(gr_line
		(start 135.800084 -36.75634)
		(end 136.257284 -36.75634)
		(stroke
			(width 0.0762)
			(type default)
		)
		(layer "In9.Cu")
	)
	(gr_line
		(start 135.957564 -37.1602)
		(end 136.099804 -37.1602)
		(stroke
			(width 0.0762)
			(type default)
		)
		(layer "In9.Cu")
	)
	(gr_line
		(start 136.257284 -36.75634)
		(end 136.379204 -36.87826)
		(stroke
			(width 0.0762)
			(type default)
		)
		(layer "In9.Cu")
	)
	(gr_line
		(start 136.841484 -36.87826)
		(end 136.963404 -36.75634)
		(stroke
			(width 0.0762)
			(type default)
		)
		(layer "In9.Cu")
	)
	(gr_line
		(start 136.963404 -36.75634)
		(end 137.420604 -36.75634)
		(stroke
			(width 0.0762)
			(type default)
		)
		(layer "In9.Cu")
	)
	(gr_line
		(start 137.120884 -37.1602)
		(end 137.263124 -37.1602)
		(stroke
			(width 0.0762)
			(type default)
		)
		(layer "In9.Cu")
	)
	(gr_line
		(start 137.420604 -36.75634)
		(end 137.542524 -36.87826)
		(stroke
			(width 0.0762)
			(type default)
		)
		(layer "In9.Cu")
	)
	(gr_line
		(start 137.804144 -18.92046)
		(end 138.027664 -18.69694)
		(stroke
			(width 0.09525)
			(type default)
		)
		(layer "In9.Cu")
	)
	(gr_line
		(start 138.004804 -36.87826)
		(end 138.126724 -36.75634)
		(stroke
			(width 0.0762)
			(type default)
		)
		(layer "In9.Cu")
	)
	(gr_line
		(start 138.027664 -18.69694)
		(end 138.599164 -18.69694)
		(stroke
			(width 0.09525)
			(type default)
		)
		(layer "In9.Cu")
	)
	(gr_line
		(start 138.126724 -36.75634)
		(end 138.583924 -36.75634)
		(stroke
			(width 0.0762)
			(type default)
		)
		(layer "In9.Cu")
	)
	(gr_line
		(start 138.223244 -19.3421)
		(end 138.403584 -19.3421)
		(stroke
			(width 0.09525)
			(type default)
		)
		(layer "In9.Cu")
	)
	(gr_line
		(start 138.284204 -37.1602)
		(end 138.426444 -37.1602)
		(stroke
			(width 0.0762)
			(type default)
		)
		(layer "In9.Cu")
	)
	(gr_line
		(start 138.583924 -36.75634)
		(end 138.705844 -36.87826)
		(stroke
			(width 0.0762)
			(type default)
		)
		(layer "In9.Cu")
	)
	(gr_line
		(start 138.599164 -18.69694)
		(end 138.822684 -18.92046)
		(stroke
			(width 0.09525)
			(type default)
		)
		(layer "In9.Cu")
	)
	(gr_line
		(start 139.399264 -18.92046)
		(end 139.622784 -18.69694)
		(stroke
			(width 0.09525)
			(type default)
		)
		(layer "In9.Cu")
	)
	(gr_line
		(start 139.622784 -18.69694)
		(end 140.194284 -18.69694)
		(stroke
			(width 0.09525)
			(type default)
		)
		(layer "In9.Cu")
	)
	(gr_line
		(start 139.818364 -19.3421)
		(end 139.998704 -19.3421)
		(stroke
			(width 0.09525)
			(type default)
		)
		(layer "In9.Cu")
	)
	(gr_line
		(start 140.194284 -18.69694)
		(end 140.417804 -18.92046)
		(stroke
			(width 0.09525)
			(type default)
		)
		(layer "In9.Cu")
	)
	(gr_line
		(start 140.994384 -18.92046)
		(end 141.217904 -18.69694)
		(stroke
			(width 0.09525)
			(type default)
		)
		(layer "In9.Cu")
	)
	(gr_line
		(start 141.217904 -18.69694)
		(end 141.789404 -18.69694)
		(stroke
			(width 0.09525)
			(type default)
		)
		(layer "In9.Cu")
	)
	(gr_line
		(start 141.413484 -19.3421)
		(end 141.593824 -19.3421)
		(stroke
			(width 0.09525)
			(type default)
		)
		(layer "In9.Cu")
	)
	(gr_line
		(start 141.789404 -18.69694)
		(end 142.012924 -18.92046)
		(stroke
			(width 0.09525)
			(type default)
		)
		(layer "In9.Cu")
	)
	(gr_line
		(start 144.509744 -20.03806)
		(end 144.733264 -19.81454)
		(stroke
			(width 0.09525)
			(type default)
		)
		(layer "In9.Cu")
	)
	(gr_line
		(start 144.733264 -19.81454)
		(end 145.304764 -19.81454)
		(stroke
			(width 0.09525)
			(type default)
		)
		(layer "In9.Cu")
	)
	(gr_line
		(start 144.928844 -20.4597)
		(end 145.109184 -20.4597)
		(stroke
			(width 0.09525)
			(type default)
		)
		(layer "In9.Cu")
	)
	(gr_line
		(start 145.304764 -19.81454)
		(end 145.528284 -20.03806)
		(stroke
			(width 0.09525)
			(type default)
		)
		(layer "In9.Cu")
	)
	(gr_line
		(start 147.903184 -23.638256)
		(end 148.126704 -23.414736)
		(stroke
			(width 0.09525)
			(type default)
		)
		(layer "In9.Cu")
	)
	(gr_line
		(start 148.126704 -23.414736)
		(end 148.698204 -23.414736)
		(stroke
			(width 0.09525)
			(type default)
		)
		(layer "In9.Cu")
	)
	(gr_line
		(start 148.322284 -24.059896)
		(end 148.502624 -24.059896)
		(stroke
			(width 0.09525)
			(type default)
		)
		(layer "In9.Cu")
	)
	(gr_line
		(start 148.698204 -23.414736)
		(end 148.921724 -23.638256)
		(stroke
			(width 0.09525)
			(type default)
		)
		(layer "In9.Cu")
	)
	(gr_line
		(start 149.0472 -35.9664)
		(end 149.134576 -35.9664)
		(stroke
			(width 0.0762)
			(type default)
		)
		(layer "In9.Cu")
	)
	(gr_line
		(start 149.3266 -36.1696)
		(end 149.413976 -36.1696)
		(stroke
			(width 0.0762)
			(type default)
		)
		(layer "In9.Cu")
	)
	(gr_line
		(start 159.68726 -10.869422)
		(end 159.68726 -11.185652)
		(stroke
			(width 0.09525)
			(type default)
		)
		(layer "In9.Cu")
	)
	(gr_line
		(start 159.68726 -10.869422)
		(end 160.091374 -10.465308)
		(stroke
			(width 0.09525)
			(type default)
		)
		(layer "In9.Cu")
	)
	(gr_line
		(start 160.091374 -10.465308)
		(end 160.407604 -10.465308)
		(stroke
			(width 0.09525)
			(type default)
		)
		(layer "In9.Cu")
	)
	(gr_line
		(start 160.281874 -11.18743)
		(end 160.409382 -11.059922)
		(stroke
			(width 0.09525)
			(type default)
		)
		(layer "In9.Cu")
	)
	(gr_line
		(start 163.3728 -3.5306)
		(end 163.3728 -3.631438)
		(stroke
			(width 0.09525)
			(type default)
		)
		(layer "In9.Cu")
	)
	(gr_line
		(start 163.3728 -3.5306)
		(end 163.625022 -3.278378)
		(stroke
			(width 0.09525)
			(type default)
		)
		(layer "In9.Cu")
	)
	(gr_line
		(start 163.4998 -8.48106)
		(end 163.52901 -8.51027)
		(stroke
			(width 0.09525)
			(type default)
		)
		(layer "In9.Cu")
	)
	(gr_line
		(start 163.4998 -8.45566)
		(end 163.4998 -8.48106)
		(stroke
			(width 0.09525)
			(type default)
		)
		(layer "In9.Cu")
	)
	(gr_line
		(start 163.6014 -7.697978)
		(end 163.95065 -8.047228)
		(stroke
			(width 0.09525)
			(type default)
		)
		(layer "In9.Cu")
	)
	(gr_line
		(start 163.79444 -4.050538)
		(end 163.9062 -3.938778)
		(stroke
			(width 0.09525)
			(type default)
		)
		(layer "In9.Cu")
	)
	(gr_line
		(start 163.95065 -8.047228)
		(end 163.95065 -8.09117)
		(stroke
			(width 0.09525)
			(type default)
		)
		(layer "In9.Cu")
	)
	(gr_line
		(start 164.24275 -7.615428)
		(end 164.24275 -7.727188)
		(stroke
			(width 0.09525)
			(type default)
		)
		(layer "In9.Cu")
	)
	(gr_line
		(start 164.24275 -7.615428)
		(end 164.338 -7.520178)
		(stroke
			(width 0.09525)
			(type default)
		)
		(layer "In9.Cu")
	)
	(gr_line
		(start 164.66439 -8.146288)
		(end 164.9857 -7.824978)
		(stroke
			(width 0.09525)
			(type default)
		)
		(layer "In9.Cu")
	)
	(gr_line
		(start 164.6936 -3.93446)
		(end 164.72916 -3.97002)
		(stroke
			(width 0.09525)
			(type default)
		)
		(layer "In9.Cu")
	)
	(gr_line
		(start 164.7952 -3.227578)
		(end 164.836348 -3.227578)
		(stroke
			(width 0.09525)
			(type default)
		)
		(layer "In9.Cu")
	)
	(gr_line
		(start 164.836348 -3.227578)
		(end 165.1508 -3.54203)
		(stroke
			(width 0.09525)
			(type default)
		)
		(layer "In9.Cu")
	)
	(gr_line
		(start 165.1508 -3.54203)
		(end 165.1508 -3.55092)
		(stroke
			(width 0.09525)
			(type default)
		)
		(layer "In9.Cu")
	)
	(gr_line
		(start 165.52545 -8.902192)
		(end 165.608 -8.819642)
		(stroke
			(width 0.09525)
			(type default)
		)
		(layer "In9.Cu")
	)
	(gr_line
		(start 165.52545 -7.674864)
		(end 165.608 -7.757414)
		(stroke
			(width 0.09525)
			(type default)
		)
		(layer "In9.Cu")
	)
	(gr_line
		(start 165.608 -7.757414)
		(end 165.608 -8.819642)
		(stroke
			(width 0.09525)
			(type default)
		)
		(layer "In9.Cu")
	)
	(gr_line
		(start 165.94455 -7.501128)
		(end 165.94455 -9.075928)
		(stroke
			(width 0.09525)
			(type default)
		)
		(layer "In9.Cu")
	)
	(gr_line
		(start 166.24935 -7.357364)
		(end 166.3192 -7.427214)
		(stroke
			(width 0.09525)
			(type default)
		)
		(layer "In9.Cu")
	)
	(gr_line
		(start 166.3192 -7.427214)
		(end 166.3192 -10.836148)
		(stroke
			(width 0.09525)
			(type default)
		)
		(layer "In9.Cu")
	)
	(gr_line
		(start 166.66845 -10.592562)
		(end 166.7383 -10.662412)
		(stroke
			(width 0.09525)
			(type default)
		)
		(layer "In9.Cu")
	)
	(gr_line
		(start 166.66845 -7.183628)
		(end 166.66845 -10.592562)
		(stroke
			(width 0.09525)
			(type default)
		)
		(layer "In9.Cu")
	)
	(gr_line
		(start 181.63286 -5.818378)
		(end 181.850792 -6.03631)
		(stroke
			(width 0.0762)
			(type default)
		)
		(layer "In9.Cu")
	)
	(gr_line
		(start 182.249318 -6.03631)
		(end 182.46725 -5.818378)
		(stroke
			(width 0.0762)
			(type default)
		)
		(layer "In9.Cu")
	)
	(gr_arc
		(start 1.54686 -67.178682)
		(mid 1.9304 -67.562222)
		(end 2.31394 -67.178682)
		(stroke
			(width 0.2)
			(type default)
		)
		(layer "In10.Cu")
	)
	(gr_line
		(start 1.54686 -66.221102)
		(end 1.54686 -67.178682)
		(stroke
			(width 0.2)
			(type default)
		)
		(layer "In10.Cu")
	)
	(gr_arc
		(start 1.54686 -64.178434)
		(mid 1.930273 -64.562228)
		(end 2.31394 -64.178688)
		(stroke
			(width 0.2)
			(type default)
		)
		(layer "In10.Cu")
	)
	(gr_line
		(start 1.54686 -63.221108)
		(end 1.54686 -64.178434)
		(stroke
			(width 0.2)
			(type default)
		)
		(layer "In10.Cu")
	)
	(gr_arc
		(start 1.54686 -61.178694)
		(mid 1.9304 -61.562234)
		(end 2.31394 -61.178694)
		(stroke
			(width 0.2)
			(type default)
		)
		(layer "In10.Cu")
	)
	(gr_line
		(start 1.54686 -60.221114)
		(end 1.54686 -61.178694)
		(stroke
			(width 0.2)
			(type default)
		)
		(layer "In10.Cu")
	)
	(gr_line
		(start 2.31394 -67.178682)
		(end 2.31394 -66.221356)
		(stroke
			(width 0.2)
			(type default)
		)
		(layer "In10.Cu")
	)
	(gr_arc
		(start 2.31394 -66.221356)
		(mid 1.930527 -65.837562)
		(end 1.54686 -66.221102)
		(stroke
			(width 0.2)
			(type default)
		)
		(layer "In10.Cu")
	)
	(gr_line
		(start 2.31394 -64.178688)
		(end 2.31394 -63.221108)
		(stroke
			(width 0.2)
			(type default)
		)
		(layer "In10.Cu")
	)
	(gr_arc
		(start 2.31394 -63.221108)
		(mid 1.9304 -62.837568)
		(end 1.54686 -63.221108)
		(stroke
			(width 0.2)
			(type default)
		)
		(layer "In10.Cu")
	)
	(gr_line
		(start 2.31394 -61.178694)
		(end 2.31394 -60.221368)
		(stroke
			(width 0.2)
			(type default)
		)
		(layer "In10.Cu")
	)
	(gr_arc
		(start 2.31394 -60.221368)
		(mid 1.930527 -59.837574)
		(end 1.54686 -60.221114)
		(stroke
			(width 0.2)
			(type default)
		)
		(layer "In10.Cu")
	)
	(gr_arc
		(start 2.94132 -59.664092)
		(mid 3.324733 -60.047886)
		(end 3.7084 -59.664346)
		(stroke
			(width 0.2)
			(type default)
		)
		(layer "In10.Cu")
	)
	(gr_line
		(start 2.94132 -58.706766)
		(end 2.94132 -59.664092)
		(stroke
			(width 0.2)
			(type default)
		)
		(layer "In10.Cu")
	)
	(gr_arc
		(start 3.06832 -65.664334)
		(mid 3.45186 -66.047874)
		(end 3.8354 -65.664334)
		(stroke
			(width 0.2)
			(type default)
		)
		(layer "In10.Cu")
	)
	(gr_line
		(start 3.06832 -64.706754)
		(end 3.06832 -65.664334)
		(stroke
			(width 0.2)
			(type default)
		)
		(layer "In10.Cu")
	)
	(gr_arc
		(start 3.06832 -62.66434)
		(mid 3.45186 -63.04788)
		(end 3.8354 -62.66434)
		(stroke
			(width 0.2)
			(type default)
		)
		(layer "In10.Cu")
	)
	(gr_line
		(start 3.06832 -61.70676)
		(end 3.06832 -62.66434)
		(stroke
			(width 0.2)
			(type default)
		)
		(layer "In10.Cu")
	)
	(gr_line
		(start 3.7084 -59.664346)
		(end 3.7084 -58.706766)
		(stroke
			(width 0.2)
			(type default)
		)
		(layer "In10.Cu")
	)
	(gr_arc
		(start 3.7084 -58.706766)
		(mid 3.32486 -58.323226)
		(end 2.94132 -58.706766)
		(stroke
			(width 0.2)
			(type default)
		)
		(layer "In10.Cu")
	)
	(gr_line
		(start 3.8354 -65.664334)
		(end 3.8354 -64.707008)
		(stroke
			(width 0.2)
			(type default)
		)
		(layer "In10.Cu")
	)
	(gr_arc
		(start 3.8354 -64.707008)
		(mid 3.451987 -64.323214)
		(end 3.06832 -64.706754)
		(stroke
			(width 0.2)
			(type default)
		)
		(layer "In10.Cu")
	)
	(gr_line
		(start 3.8354 -62.66434)
		(end 3.8354 -61.707014)
		(stroke
			(width 0.2)
			(type default)
		)
		(layer "In10.Cu")
	)
	(gr_arc
		(start 3.8354 -61.707014)
		(mid 3.451987 -61.32322)
		(end 3.06832 -61.70676)
		(stroke
			(width 0.2)
			(type default)
		)
		(layer "In10.Cu")
	)
	(gr_line
		(start 4.800346 -67.101974)
		(end 4.8006 -67.102228)
		(stroke
			(width 0.2)
			(type default)
		)
		(layer "In10.Cu")
	)
	(gr_line
		(start 4.800346 -66.297556)
		(end 4.800346 -67.101974)
		(stroke
			(width 0.2)
			(type default)
		)
		(layer "In10.Cu")
	)
	(gr_line
		(start 4.800346 -65.602104)
		(end 4.8006 -65.602358)
		(stroke
			(width 0.2)
			(type default)
		)
		(layer "In10.Cu")
	)
	(gr_line
		(start 4.800346 -64.797432)
		(end 4.800346 -65.602104)
		(stroke
			(width 0.2)
			(type default)
		)
		(layer "In10.Cu")
	)
	(gr_line
		(start 4.800346 -64.10198)
		(end 4.8006 -64.102234)
		(stroke
			(width 0.2)
			(type default)
		)
		(layer "In10.Cu")
	)
	(gr_line
		(start 4.800346 -63.297562)
		(end 4.800346 -64.10198)
		(stroke
			(width 0.2)
			(type default)
		)
		(layer "In10.Cu")
	)
	(gr_line
		(start 4.800346 -62.60211)
		(end 4.8006 -62.602364)
		(stroke
			(width 0.2)
			(type default)
		)
		(layer "In10.Cu")
	)
	(gr_line
		(start 4.800346 -61.797438)
		(end 4.800346 -62.60211)
		(stroke
			(width 0.2)
			(type default)
		)
		(layer "In10.Cu")
	)
	(gr_line
		(start 4.800346 -61.101986)
		(end 4.8006 -61.10224)
		(stroke
			(width 0.2)
			(type default)
		)
		(layer "In10.Cu")
	)
	(gr_line
		(start 4.800346 -60.297568)
		(end 4.800346 -61.101986)
		(stroke
			(width 0.2)
			(type default)
		)
		(layer "In10.Cu")
	)
	(gr_line
		(start 4.800346 -59.602116)
		(end 4.8006 -59.60237)
		(stroke
			(width 0.2)
			(type default)
		)
		(layer "In10.Cu")
	)
	(gr_line
		(start 4.800346 -58.797444)
		(end 4.800346 -59.602116)
		(stroke
			(width 0.2)
			(type default)
		)
		(layer "In10.Cu")
	)
	(gr_line
		(start 4.800346 -58.101992)
		(end 4.8006 -58.102246)
		(stroke
			(width 0.2)
			(type default)
		)
		(layer "In10.Cu")
	)
	(gr_line
		(start 4.800346 -57.297574)
		(end 4.800346 -58.101992)
		(stroke
			(width 0.2)
			(type default)
		)
		(layer "In10.Cu")
	)
	(gr_line
		(start 4.800346 -56.602122)
		(end 4.8006 -56.602376)
		(stroke
			(width 0.2)
			(type default)
		)
		(layer "In10.Cu")
	)
	(gr_line
		(start 4.800346 -55.79745)
		(end 4.800346 -56.602122)
		(stroke
			(width 0.2)
			(type default)
		)
		(layer "In10.Cu")
	)
	(gr_line
		(start 4.800346 -55.101998)
		(end 4.8006 -55.102252)
		(stroke
			(width 0.2)
			(type default)
		)
		(layer "In10.Cu")
	)
	(gr_line
		(start 4.800346 -54.29758)
		(end 4.800346 -55.101998)
		(stroke
			(width 0.2)
			(type default)
		)
		(layer "In10.Cu")
	)
	(gr_line
		(start 4.8006 -67.102228)
		(end 6.349746 -67.102228)
		(stroke
			(width 0.2)
			(type default)
		)
		(layer "In10.Cu")
	)
	(gr_line
		(start 4.8006 -65.602358)
		(end 6.349746 -65.602358)
		(stroke
			(width 0.2)
			(type default)
		)
		(layer "In10.Cu")
	)
	(gr_line
		(start 4.8006 -64.102234)
		(end 6.349746 -64.102234)
		(stroke
			(width 0.2)
			(type default)
		)
		(layer "In10.Cu")
	)
	(gr_line
		(start 4.8006 -62.602364)
		(end 6.349746 -62.602364)
		(stroke
			(width 0.2)
			(type default)
		)
		(layer "In10.Cu")
	)
	(gr_line
		(start 4.8006 -61.10224)
		(end 6.349746 -61.10224)
		(stroke
			(width 0.2)
			(type default)
		)
		(layer "In10.Cu")
	)
	(gr_line
		(start 4.8006 -59.60237)
		(end 6.349746 -59.60237)
		(stroke
			(width 0.2)
			(type default)
		)
		(layer "In10.Cu")
	)
	(gr_line
		(start 4.8006 -58.102246)
		(end 6.349746 -58.102246)
		(stroke
			(width 0.2)
			(type default)
		)
		(layer "In10.Cu")
	)
	(gr_line
		(start 4.8006 -56.602376)
		(end 6.349746 -56.602376)
		(stroke
			(width 0.2)
			(type default)
		)
		(layer "In10.Cu")
	)
	(gr_line
		(start 4.8006 -55.102252)
		(end 6.349746 -55.102252)
		(stroke
			(width 0.2)
			(type default)
		)
		(layer "In10.Cu")
	)
	(gr_line
		(start 6.349746 -67.102228)
		(end 6.349746 -66.297556)
		(stroke
			(width 0.2)
			(type default)
		)
		(layer "In10.Cu")
	)
	(gr_line
		(start 6.349746 -66.297556)
		(end 4.800346 -66.297556)
		(stroke
			(width 0.2)
			(type default)
		)
		(layer "In10.Cu")
	)
	(gr_line
		(start 6.349746 -65.602358)
		(end 6.349746 -64.797432)
		(stroke
			(width 0.2)
			(type default)
		)
		(layer "In10.Cu")
	)
	(gr_line
		(start 6.349746 -64.797432)
		(end 4.800346 -64.797432)
		(stroke
			(width 0.2)
			(type default)
		)
		(layer "In10.Cu")
	)
	(gr_line
		(start 6.349746 -64.102234)
		(end 6.349746 -63.297562)
		(stroke
			(width 0.2)
			(type default)
		)
		(layer "In10.Cu")
	)
	(gr_line
		(start 6.349746 -63.297562)
		(end 4.800346 -63.297562)
		(stroke
			(width 0.2)
			(type default)
		)
		(layer "In10.Cu")
	)
	(gr_line
		(start 6.349746 -62.602364)
		(end 6.349746 -61.797438)
		(stroke
			(width 0.2)
			(type default)
		)
		(layer "In10.Cu")
	)
	(gr_line
		(start 6.349746 -61.797438)
		(end 4.800346 -61.797438)
		(stroke
			(width 0.2)
			(type default)
		)
		(layer "In10.Cu")
	)
	(gr_line
		(start 6.349746 -61.10224)
		(end 6.349746 -60.297568)
		(stroke
			(width 0.2)
			(type default)
		)
		(layer "In10.Cu")
	)
	(gr_line
		(start 6.349746 -60.297568)
		(end 4.800346 -60.297568)
		(stroke
			(width 0.2)
			(type default)
		)
		(layer "In10.Cu")
	)
	(gr_line
		(start 6.349746 -59.60237)
		(end 6.349746 -58.797444)
		(stroke
			(width 0.2)
			(type default)
		)
		(layer "In10.Cu")
	)
	(gr_line
		(start 6.349746 -58.797444)
		(end 4.800346 -58.797444)
		(stroke
			(width 0.2)
			(type default)
		)
		(layer "In10.Cu")
	)
	(gr_line
		(start 6.349746 -58.102246)
		(end 6.349746 -57.297574)
		(stroke
			(width 0.2)
			(type default)
		)
		(layer "In10.Cu")
	)
	(gr_line
		(start 6.349746 -57.297574)
		(end 4.800346 -57.297574)
		(stroke
			(width 0.2)
			(type default)
		)
		(layer "In10.Cu")
	)
	(gr_line
		(start 6.349746 -56.602376)
		(end 6.349746 -55.79745)
		(stroke
			(width 0.2)
			(type default)
		)
		(layer "In10.Cu")
	)
	(gr_line
		(start 6.349746 -55.79745)
		(end 4.800346 -55.79745)
		(stroke
			(width 0.2)
			(type default)
		)
		(layer "In10.Cu")
	)
	(gr_line
		(start 6.349746 -55.102252)
		(end 6.349746 -54.29758)
		(stroke
			(width 0.2)
			(type default)
		)
		(layer "In10.Cu")
	)
	(gr_line
		(start 6.349746 -54.29758)
		(end 4.800346 -54.29758)
		(stroke
			(width 0.2)
			(type default)
		)
		(layer "In10.Cu")
	)
	(gr_arc
		(start 7.747 -51.6128)
		(mid 8.128 -51.9938)
		(end 8.509 -51.6128)
		(stroke
			(width 0.2)
			(type default)
		)
		(layer "In10.Cu")
	)
	(gr_line
		(start 7.747 -50.6222)
		(end 7.747 -51.6128)
		(stroke
			(width 0.2)
			(type default)
		)
		(layer "In10.Cu")
	)
	(gr_arc
		(start 8.4582 -53.8988)
		(mid 8.8392 -54.2798)
		(end 9.2202 -53.8988)
		(stroke
			(width 0.2)
			(type default)
		)
		(layer "In10.Cu")
	)
	(gr_line
		(start 8.4582 -52.9082)
		(end 8.4582 -53.8988)
		(stroke
			(width 0.2)
			(type default)
		)
		(layer "In10.Cu")
	)
	(gr_line
		(start 8.509 -51.6128)
		(end 8.509 -50.622454)
		(stroke
			(width 0.2)
			(type default)
		)
		(layer "In10.Cu")
	)
	(gr_arc
		(start 8.509 -50.622454)
		(mid 8.128127 -50.2412)
		(end 7.747 -50.6222)
		(stroke
			(width 0.2)
			(type default)
		)
		(layer "In10.Cu")
	)
	(gr_line
		(start 9.2202 -53.8988)
		(end 9.2202 -52.908454)
		(stroke
			(width 0.2)
			(type default)
		)
		(layer "In10.Cu")
	)
	(gr_arc
		(start 9.2202 -52.908454)
		(mid 8.839327 -52.5272)
		(end 8.4582 -52.9082)
		(stroke
			(width 0.2)
			(type default)
		)
		(layer "In10.Cu")
	)
	(gr_line
		(start 9.240774 -62.748922)
		(end 9.266174 -63.637668)
		(stroke
			(width 0.2)
			(type default)
		)
		(layer "In10.Cu")
	)
	(gr_line
		(start 9.240774 -59.192922)
		(end 9.266174 -60.081668)
		(stroke
			(width 0.2)
			(type default)
		)
		(layer "In10.Cu")
	)
	(gr_arc
		(start 9.24306 -65.405)
		(mid 9.6266 -65.78854)
		(end 10.01014 -65.405)
		(stroke
			(width 0.2)
			(type default)
		)
		(layer "In10.Cu")
	)
	(gr_line
		(start 9.24306 -64.516)
		(end 9.24306 -65.405)
		(stroke
			(width 0.2)
			(type default)
		)
		(layer "In10.Cu")
	)
	(gr_arc
		(start 9.24306 -61.849)
		(mid 9.6266 -62.23254)
		(end 10.01014 -61.849)
		(stroke
			(width 0.2)
			(type default)
		)
		(layer "In10.Cu")
	)
	(gr_line
		(start 9.24306 -60.96)
		(end 9.24306 -61.849)
		(stroke
			(width 0.2)
			(type default)
		)
		(layer "In10.Cu")
	)
	(gr_arc
		(start 9.24306 -58.293)
		(mid 9.6266 -58.67654)
		(end 10.01014 -58.293)
		(stroke
			(width 0.2)
			(type default)
		)
		(layer "In10.Cu")
	)
	(gr_line
		(start 9.24306 -57.404)
		(end 9.24306 -58.293)
		(stroke
			(width 0.2)
			(type default)
		)
		(layer "In10.Cu")
	)
	(gr_arc
		(start 9.24306 -56.515)
		(mid 9.6266 -56.89854)
		(end 10.01014 -56.515)
		(stroke
			(width 0.2)
			(type default)
		)
		(layer "In10.Cu")
	)
	(gr_line
		(start 9.24306 -55.626)
		(end 9.24306 -56.515)
		(stroke
			(width 0.2)
			(type default)
		)
		(layer "In10.Cu")
	)
	(gr_line
		(start 9.243314 -62.748922)
		(end 9.240774 -62.748922)
		(stroke
			(width 0.2)
			(type default)
		)
		(layer "In10.Cu")
	)
	(gr_line
		(start 9.243314 -59.192922)
		(end 9.240774 -59.192922)
		(stroke
			(width 0.2)
			(type default)
		)
		(layer "In10.Cu")
	)
	(gr_line
		(start 9.266174 -63.637668)
		(end 9.266428 -63.637922)
		(stroke
			(width 0.2)
			(type default)
		)
		(layer "In10.Cu")
	)
	(gr_line
		(start 9.266174 -60.081668)
		(end 9.266428 -60.081922)
		(stroke
			(width 0.2)
			(type default)
		)
		(layer "In10.Cu")
	)
	(gr_line
		(start 9.266428 -63.637922)
		(end 9.268714 -63.637922)
		(stroke
			(width 0.2)
			(type default)
		)
		(layer "In10.Cu")
	)
	(gr_line
		(start 9.266428 -60.081922)
		(end 9.268714 -60.081922)
		(stroke
			(width 0.2)
			(type default)
		)
		(layer "In10.Cu")
	)
	(gr_arc
		(start 9.268714 -63.637922)
		(mid 9.662922 -64.010286)
		(end 10.035286 -63.616078)
		(stroke
			(width 0.2)
			(type default)
		)
		(layer "In10.Cu")
	)
	(gr_arc
		(start 9.268714 -60.081922)
		(mid 9.662922 -60.454286)
		(end 10.035286 -60.060078)
		(stroke
			(width 0.2)
			(type default)
		)
		(layer "In10.Cu")
	)
	(gr_circle
		(center 9.5504 -51.7398)
		(end 9.90854 -51.7398)
		(stroke
			(width 0.2)
			(type default)
		)
		(fill no)
		(layer "In10.Cu")
	)
	(gr_circle
		(center 9.5504 -50.4952)
		(end 9.90854 -50.4952)
		(stroke
			(width 0.2)
			(type default)
		)
		(fill no)
		(layer "In10.Cu")
	)
	(gr_arc
		(start 10.009886 -62.727078)
		(mid 9.615678 -62.354714)
		(end 9.243314 -62.748922)
		(stroke
			(width 0.2)
			(type default)
		)
		(layer "In10.Cu")
	)
	(gr_arc
		(start 10.009886 -59.171078)
		(mid 9.615678 -58.798714)
		(end 9.243314 -59.192922)
		(stroke
			(width 0.2)
			(type default)
		)
		(layer "In10.Cu")
	)
	(gr_line
		(start 10.01014 -65.405)
		(end 10.01014 -64.516254)
		(stroke
			(width 0.2)
			(type default)
		)
		(layer "In10.Cu")
	)
	(gr_arc
		(start 10.01014 -64.516254)
		(mid 9.626727 -64.13246)
		(end 9.24306 -64.516)
		(stroke
			(width 0.2)
			(type default)
		)
		(layer "In10.Cu")
	)
	(gr_line
		(start 10.01014 -61.849)
		(end 10.01014 -60.960254)
		(stroke
			(width 0.2)
			(type default)
		)
		(layer "In10.Cu")
	)
	(gr_arc
		(start 10.01014 -60.960254)
		(mid 9.626727 -60.57646)
		(end 9.24306 -60.96)
		(stroke
			(width 0.2)
			(type default)
		)
		(layer "In10.Cu")
	)
	(gr_line
		(start 10.01014 -58.293)
		(end 10.01014 -57.404254)
		(stroke
			(width 0.2)
			(type default)
		)
		(layer "In10.Cu")
	)
	(gr_arc
		(start 10.01014 -57.404254)
		(mid 9.626727 -57.02046)
		(end 9.24306 -57.404)
		(stroke
			(width 0.2)
			(type default)
		)
		(layer "In10.Cu")
	)
	(gr_line
		(start 10.01014 -56.515)
		(end 10.01014 -55.626254)
		(stroke
			(width 0.2)
			(type default)
		)
		(layer "In10.Cu")
	)
	(gr_arc
		(start 10.01014 -55.626254)
		(mid 9.626727 -55.24246)
		(end 9.24306 -55.626)
		(stroke
			(width 0.2)
			(type default)
		)
		(layer "In10.Cu")
	)
	(gr_line
		(start 10.012426 -62.727078)
		(end 10.009886 -62.727078)
		(stroke
			(width 0.2)
			(type default)
		)
		(layer "In10.Cu")
	)
	(gr_line
		(start 10.012426 -59.171078)
		(end 10.009886 -59.171078)
		(stroke
			(width 0.2)
			(type default)
		)
		(layer "In10.Cu")
	)
	(gr_line
		(start 10.035286 -63.616078)
		(end 10.037826 -63.616078)
		(stroke
			(width 0.2)
			(type default)
		)
		(layer "In10.Cu")
	)
	(gr_line
		(start 10.035286 -60.060078)
		(end 10.037826 -60.060078)
		(stroke
			(width 0.2)
			(type default)
		)
		(layer "In10.Cu")
	)
	(gr_line
		(start 10.037826 -63.616078)
		(end 10.012426 -62.727078)
		(stroke
			(width 0.2)
			(type default)
		)
		(layer "In10.Cu")
	)
	(gr_line
		(start 10.037826 -60.060078)
		(end 10.012426 -59.171078)
		(stroke
			(width 0.2)
			(type default)
		)
		(layer "In10.Cu")
	)
	(gr_circle
		(center 10.2616 -54.0258)
		(end 10.61974 -54.0258)
		(stroke
			(width 0.2)
			(type default)
		)
		(fill no)
		(layer "In10.Cu")
	)
	(gr_circle
		(center 10.2616 -52.7812)
		(end 10.61974 -52.7812)
		(stroke
			(width 0.2)
			(type default)
		)
		(fill no)
		(layer "In10.Cu")
	)
	(gr_arc
		(start 12.7889 -48.617886)
		(mid 13.172313 -49.00168)
		(end 13.55598 -48.61814)
		(stroke
			(width 0.2)
			(type default)
		)
		(layer "In10.Cu")
	)
	(gr_line
		(start 12.7889 -47.66056)
		(end 12.7889 -48.617886)
		(stroke
			(width 0.2)
			(type default)
		)
		(layer "In10.Cu")
	)
	(gr_line
		(start 13.55598 -48.61814)
		(end 13.55598 -47.66056)
		(stroke
			(width 0.2)
			(type default)
		)
		(layer "In10.Cu")
	)
	(gr_arc
		(start 13.55598 -47.66056)
		(mid 13.17244 -47.27702)
		(end 12.7889 -47.66056)
		(stroke
			(width 0.2)
			(type default)
		)
		(layer "In10.Cu")
	)
	(gr_line
		(start 14.15288 -47.21606)
		(end 15.082266 -47.21606)
		(stroke
			(width 0.2)
			(type default)
		)
		(layer "In10.Cu")
	)
	(gr_arc
		(start 14.153134 -46.44898)
		(mid 13.76934 -46.832393)
		(end 14.15288 -47.21606)
		(stroke
			(width 0.2)
			(type default)
		)
		(layer "In10.Cu")
	)
	(gr_arc
		(start 15.082266 -47.21606)
		(mid 15.465806 -46.83252)
		(end 15.082266 -46.44898)
		(stroke
			(width 0.2)
			(type default)
		)
		(layer "In10.Cu")
	)
	(gr_line
		(start 15.082266 -46.44898)
		(end 14.153134 -46.44898)
		(stroke
			(width 0.2)
			(type default)
		)
		(layer "In10.Cu")
	)
	(gr_rect
		(start 16.991838 -4.097528)
		(end 17.708118 -8.293608)
		(stroke
			(width 0)
			(type default)
		)
		(fill no)
		(layer "In10.Cu")
	)
	(gr_rect
		(start 17.991836 -4.097528)
		(end 18.708116 -8.293608)
		(stroke
			(width 0)
			(type default)
		)
		(fill no)
		(layer "In10.Cu")
	)
	(gr_line
		(start 19.408394 -10.634218)
		(end 20.327874 -10.634218)
		(stroke
			(width 0.2)
			(type default)
		)
		(layer "In10.Cu")
	)
	(gr_arc
		(start 19.408648 -9.867138)
		(mid 19.024854 -10.250551)
		(end 19.408394 -10.634218)
		(stroke
			(width 0.2)
			(type default)
		)
		(layer "In10.Cu")
	)
	(gr_arc
		(start 19.93646 -13.2588)
		(mid 19.952083 -13.296517)
		(end 19.9898 -13.31214)
		(stroke
			(width 0.2)
			(type default)
		)
		(layer "In10.Cu")
	)
	(gr_line
		(start 19.93646 -12.9032)
		(end 19.93646 -13.2588)
		(stroke
			(width 0.2)
			(type default)
		)
		(layer "In10.Cu")
	)
	(gr_arc
		(start 19.93646 -12.4968)
		(mid 19.952083 -12.534517)
		(end 19.9898 -12.55014)
		(stroke
			(width 0.2)
			(type default)
		)
		(layer "In10.Cu")
	)
	(gr_line
		(start 19.93646 -12.1412)
		(end 19.93646 -12.4968)
		(stroke
			(width 0.2)
			(type default)
		)
		(layer "In10.Cu")
	)
	(gr_line
		(start 19.9898 -13.31214)
		(end 20.3962 -13.31214)
		(stroke
			(width 0.2)
			(type default)
		)
		(layer "In10.Cu")
	)
	(gr_arc
		(start 19.9898 -12.84986)
		(mid 19.952083 -12.865483)
		(end 19.93646 -12.9032)
		(stroke
			(width 0.2)
			(type default)
		)
		(layer "In10.Cu")
	)
	(gr_line
		(start 19.9898 -12.55014)
		(end 20.3962 -12.55014)
		(stroke
			(width 0.2)
			(type default)
		)
		(layer "In10.Cu")
	)
	(gr_arc
		(start 19.9898 -12.08786)
		(mid 19.952083 -12.103483)
		(end 19.93646 -12.1412)
		(stroke
			(width 0.2)
			(type default)
		)
		(layer "In10.Cu")
	)
	(gr_line
		(start 20.09521 -15.872206)
		(end 21.052536 -15.872206)
		(stroke
			(width 0.2)
			(type default)
		)
		(layer "In10.Cu")
	)
	(gr_arc
		(start 20.09521 -15.105126)
		(mid 19.71167 -15.488666)
		(end 20.09521 -15.872206)
		(stroke
			(width 0.2)
			(type default)
		)
		(layer "In10.Cu")
	)
	(gr_arc
		(start 20.327874 -10.634218)
		(mid 20.711414 -10.250678)
		(end 20.327874 -9.867138)
		(stroke
			(width 0.2)
			(type default)
		)
		(layer "In10.Cu")
	)
	(gr_line
		(start 20.327874 -9.867138)
		(end 19.408648 -9.867138)
		(stroke
			(width 0.2)
			(type default)
		)
		(layer "In10.Cu")
	)
	(gr_arc
		(start 20.3962 -13.31214)
		(mid 20.433917 -13.296517)
		(end 20.44954 -13.2588)
		(stroke
			(width 0.2)
			(type default)
		)
		(layer "In10.Cu")
	)
	(gr_line
		(start 20.3962 -12.84986)
		(end 19.9898 -12.84986)
		(stroke
			(width 0.2)
			(type default)
		)
		(layer "In10.Cu")
	)
	(gr_arc
		(start 20.3962 -12.55014)
		(mid 20.433917 -12.534517)
		(end 20.44954 -12.4968)
		(stroke
			(width 0.2)
			(type default)
		)
		(layer "In10.Cu")
	)
	(gr_line
		(start 20.3962 -12.08786)
		(end 19.9898 -12.08786)
		(stroke
			(width 0.2)
			(type default)
		)
		(layer "In10.Cu")
	)
	(gr_line
		(start 20.44954 -13.2588)
		(end 20.44954 -12.9032)
		(stroke
			(width 0.2)
			(type default)
		)
		(layer "In10.Cu")
	)
	(gr_arc
		(start 20.44954 -12.9032)
		(mid 20.433917 -12.865483)
		(end 20.3962 -12.84986)
		(stroke
			(width 0.2)
			(type default)
		)
		(layer "In10.Cu")
	)
	(gr_line
		(start 20.44954 -12.4968)
		(end 20.44954 -12.1412)
		(stroke
			(width 0.2)
			(type default)
		)
		(layer "In10.Cu")
	)
	(gr_arc
		(start 20.44954 -12.1412)
		(mid 20.433917 -12.103483)
		(end 20.3962 -12.08786)
		(stroke
			(width 0.2)
			(type default)
		)
		(layer "In10.Cu")
	)
	(gr_arc
		(start 20.69846 -13.2588)
		(mid 20.714083 -13.296517)
		(end 20.7518 -13.31214)
		(stroke
			(width 0.2)
			(type default)
		)
		(layer "In10.Cu")
	)
	(gr_line
		(start 20.69846 -12.9032)
		(end 20.69846 -13.2588)
		(stroke
			(width 0.2)
			(type default)
		)
		(layer "In10.Cu")
	)
	(gr_arc
		(start 20.69846 -12.4968)
		(mid 20.714083 -12.534517)
		(end 20.7518 -12.55014)
		(stroke
			(width 0.2)
			(type default)
		)
		(layer "In10.Cu")
	)
	(gr_line
		(start 20.69846 -12.1412)
		(end 20.69846 -12.4968)
		(stroke
			(width 0.2)
			(type default)
		)
		(layer "In10.Cu")
	)
	(gr_line
		(start 20.7518 -13.31214)
		(end 21.1582 -13.31214)
		(stroke
			(width 0.2)
			(type default)
		)
		(layer "In10.Cu")
	)
	(gr_arc
		(start 20.7518 -12.84986)
		(mid 20.714083 -12.865483)
		(end 20.69846 -12.9032)
		(stroke
			(width 0.2)
			(type default)
		)
		(layer "In10.Cu")
	)
	(gr_line
		(start 20.7518 -12.55014)
		(end 21.1582 -12.55014)
		(stroke
			(width 0.2)
			(type default)
		)
		(layer "In10.Cu")
	)
	(gr_arc
		(start 20.7518 -12.08786)
		(mid 20.714083 -12.103483)
		(end 20.69846 -12.1412)
		(stroke
			(width 0.2)
			(type default)
		)
		(layer "In10.Cu")
	)
	(gr_rect
		(start 20.99183 -4.097528)
		(end 21.70811 -8.293608)
		(stroke
			(width 0)
			(type default)
		)
		(fill no)
		(layer "In10.Cu")
	)
	(gr_arc
		(start 21.052536 -15.872206)
		(mid 21.43633 -15.488793)
		(end 21.05279 -15.105126)
		(stroke
			(width 0.2)
			(type default)
		)
		(layer "In10.Cu")
	)
	(gr_line
		(start 21.05279 -15.105126)
		(end 20.09521 -15.105126)
		(stroke
			(width 0.2)
			(type default)
		)
		(layer "In10.Cu")
	)
	(gr_arc
		(start 21.1582 -13.31214)
		(mid 21.195917 -13.296517)
		(end 21.21154 -13.2588)
		(stroke
			(width 0.2)
			(type default)
		)
		(layer "In10.Cu")
	)
	(gr_line
		(start 21.1582 -12.84986)
		(end 20.7518 -12.84986)
		(stroke
			(width 0.2)
			(type default)
		)
		(layer "In10.Cu")
	)
	(gr_arc
		(start 21.1582 -12.55014)
		(mid 21.195917 -12.534517)
		(end 21.21154 -12.4968)
		(stroke
			(width 0.2)
			(type default)
		)
		(layer "In10.Cu")
	)
	(gr_line
		(start 21.1582 -12.08786)
		(end 20.7518 -12.08786)
		(stroke
			(width 0.2)
			(type default)
		)
		(layer "In10.Cu")
	)
	(gr_line
		(start 21.21154 -13.2588)
		(end 21.21154 -12.9032)
		(stroke
			(width 0.2)
			(type default)
		)
		(layer "In10.Cu")
	)
	(gr_arc
		(start 21.21154 -12.9032)
		(mid 21.195917 -12.865483)
		(end 21.1582 -12.84986)
		(stroke
			(width 0.2)
			(type default)
		)
		(layer "In10.Cu")
	)
	(gr_line
		(start 21.21154 -12.4968)
		(end 21.21154 -12.1412)
		(stroke
			(width 0.2)
			(type default)
		)
		(layer "In10.Cu")
	)
	(gr_arc
		(start 21.21154 -12.1412)
		(mid 21.195917 -12.103483)
		(end 21.1582 -12.08786)
		(stroke
			(width 0.2)
			(type default)
		)
		(layer "In10.Cu")
	)
	(gr_arc
		(start 21.46046 -13.2588)
		(mid 21.476083 -13.296517)
		(end 21.5138 -13.31214)
		(stroke
			(width 0.2)
			(type default)
		)
		(layer "In10.Cu")
	)
	(gr_line
		(start 21.46046 -12.9032)
		(end 21.46046 -13.2588)
		(stroke
			(width 0.2)
			(type default)
		)
		(layer "In10.Cu")
	)
	(gr_arc
		(start 21.46046 -12.4968)
		(mid 21.476083 -12.534517)
		(end 21.5138 -12.55014)
		(stroke
			(width 0.2)
			(type default)
		)
		(layer "In10.Cu")
	)
	(gr_line
		(start 21.46046 -12.1412)
		(end 21.46046 -12.4968)
		(stroke
			(width 0.2)
			(type default)
		)
		(layer "In10.Cu")
	)
	(gr_line
		(start 21.5138 -13.31214)
		(end 21.9202 -13.31214)
		(stroke
			(width 0.2)
			(type default)
		)
		(layer "In10.Cu")
	)
	(gr_arc
		(start 21.5138 -12.84986)
		(mid 21.476083 -12.865483)
		(end 21.46046 -12.9032)
		(stroke
			(width 0.2)
			(type default)
		)
		(layer "In10.Cu")
	)
	(gr_line
		(start 21.5138 -12.55014)
		(end 21.9202 -12.55014)
		(stroke
			(width 0.2)
			(type default)
		)
		(layer "In10.Cu")
	)
	(gr_arc
		(start 21.5138 -12.08786)
		(mid 21.476083 -12.103483)
		(end 21.46046 -12.1412)
		(stroke
			(width 0.2)
			(type default)
		)
		(layer "In10.Cu")
	)
	(gr_line
		(start 21.6662 -14.20114)
		(end 22.5298 -14.20114)
		(stroke
			(width 0.2)
			(type default)
		)
		(layer "In10.Cu")
	)
	(gr_arc
		(start 21.666454 -13.43406)
		(mid 21.28266 -13.817473)
		(end 21.6662 -14.20114)
		(stroke
			(width 0.2)
			(type default)
		)
		(layer "In10.Cu")
	)
	(gr_arc
		(start 21.9202 -13.31214)
		(mid 21.957917 -13.296517)
		(end 21.97354 -13.2588)
		(stroke
			(width 0.2)
			(type default)
		)
		(layer "In10.Cu")
	)
	(gr_line
		(start 21.9202 -12.84986)
		(end 21.5138 -12.84986)
		(stroke
			(width 0.2)
			(type default)
		)
		(layer "In10.Cu")
	)
	(gr_arc
		(start 21.9202 -12.55014)
		(mid 21.957917 -12.534517)
		(end 21.97354 -12.4968)
		(stroke
			(width 0.2)
			(type default)
		)
		(layer "In10.Cu")
	)
	(gr_line
		(start 21.9202 -12.08786)
		(end 21.5138 -12.08786)
		(stroke
			(width 0.2)
			(type default)
		)
		(layer "In10.Cu")
	)
	(gr_line
		(start 21.97354 -13.2588)
		(end 21.97354 -12.9032)
		(stroke
			(width 0.2)
			(type default)
		)
		(layer "In10.Cu")
	)
	(gr_arc
		(start 21.97354 -12.9032)
		(mid 21.957917 -12.865483)
		(end 21.9202 -12.84986)
		(stroke
			(width 0.2)
			(type default)
		)
		(layer "In10.Cu")
	)
	(gr_line
		(start 21.97354 -12.4968)
		(end 21.97354 -12.1412)
		(stroke
			(width 0.2)
			(type default)
		)
		(layer "In10.Cu")
	)
	(gr_arc
		(start 21.97354 -12.1412)
		(mid 21.957917 -12.103483)
		(end 21.9202 -12.08786)
		(stroke
			(width 0.2)
			(type default)
		)
		(layer "In10.Cu")
	)
	(gr_rect
		(start 21.991828 -4.097528)
		(end 22.708108 -8.293608)
		(stroke
			(width 0)
			(type default)
		)
		(fill no)
		(layer "In10.Cu")
	)
	(gr_arc
		(start 22.22246 -13.2588)
		(mid 22.238083 -13.296517)
		(end 22.2758 -13.31214)
		(stroke
			(width 0.2)
			(type default)
		)
		(layer "In10.Cu")
	)
	(gr_line
		(start 22.22246 -12.9032)
		(end 22.22246 -13.2588)
		(stroke
			(width 0.2)
			(type default)
		)
		(layer "In10.Cu")
	)
	(gr_arc
		(start 22.22246 -12.4968)
		(mid 22.238083 -12.534517)
		(end 22.2758 -12.55014)
		(stroke
			(width 0.2)
			(type default)
		)
		(layer "In10.Cu")
	)
	(gr_line
		(start 22.22246 -12.1412)
		(end 22.22246 -12.4968)
		(stroke
			(width 0.2)
			(type default)
		)
		(layer "In10.Cu")
	)
	(gr_line
		(start 22.2758 -13.31214)
		(end 22.6822 -13.31214)
		(stroke
			(width 0.2)
			(type default)
		)
		(layer "In10.Cu")
	)
	(gr_arc
		(start 22.2758 -12.84986)
		(mid 22.238083 -12.865483)
		(end 22.22246 -12.9032)
		(stroke
			(width 0.2)
			(type default)
		)
		(layer "In10.Cu")
	)
	(gr_line
		(start 22.2758 -12.55014)
		(end 22.6822 -12.55014)
		(stroke
			(width 0.2)
			(type default)
		)
		(layer "In10.Cu")
	)
	(gr_arc
		(start 22.2758 -12.08786)
		(mid 22.238083 -12.103483)
		(end 22.22246 -12.1412)
		(stroke
			(width 0.2)
			(type default)
		)
		(layer "In10.Cu")
	)
	(gr_arc
		(start 22.5298 -14.20114)
		(mid 22.91334 -13.8176)
		(end 22.5298 -13.43406)
		(stroke
			(width 0.2)
			(type default)
		)
		(layer "In10.Cu")
	)
	(gr_line
		(start 22.5298 -13.43406)
		(end 21.666454 -13.43406)
		(stroke
			(width 0.2)
			(type default)
		)
		(layer "In10.Cu")
	)
	(gr_line
		(start 22.606 -73.025)
		(end 22.606 -71.755)
		(stroke
			(width 0.381)
			(type default)
		)
		(layer "In10.Cu")
	)
	(gr_line
		(start 22.606 -71.755)
		(end 23.368 -70.993)
		(stroke
			(width 0.381)
			(type default)
		)
		(layer "In10.Cu")
	)
	(gr_arc
		(start 22.6822 -13.31214)
		(mid 22.719917 -13.296517)
		(end 22.73554 -13.2588)
		(stroke
			(width 0.2)
			(type default)
		)
		(layer "In10.Cu")
	)
	(gr_line
		(start 22.6822 -12.84986)
		(end 22.2758 -12.84986)
		(stroke
			(width 0.2)
			(type default)
		)
		(layer "In10.Cu")
	)
	(gr_arc
		(start 22.6822 -12.55014)
		(mid 22.719917 -12.534517)
		(end 22.73554 -12.4968)
		(stroke
			(width 0.2)
			(type default)
		)
		(layer "In10.Cu")
	)
	(gr_line
		(start 22.6822 -12.08786)
		(end 22.2758 -12.08786)
		(stroke
			(width 0.2)
			(type default)
		)
		(layer "In10.Cu")
	)
	(gr_line
		(start 22.73554 -13.2588)
		(end 22.73554 -12.9032)
		(stroke
			(width 0.2)
			(type default)
		)
		(layer "In10.Cu")
	)
	(gr_arc
		(start 22.73554 -12.9032)
		(mid 22.719917 -12.865483)
		(end 22.6822 -12.84986)
		(stroke
			(width 0.2)
			(type default)
		)
		(layer "In10.Cu")
	)
	(gr_line
		(start 22.73554 -12.4968)
		(end 22.73554 -12.1412)
		(stroke
			(width 0.2)
			(type default)
		)
		(layer "In10.Cu")
	)
	(gr_arc
		(start 22.73554 -12.1412)
		(mid 22.719917 -12.103483)
		(end 22.6822 -12.08786)
		(stroke
			(width 0.2)
			(type default)
		)
		(layer "In10.Cu")
	)
	(gr_line
		(start 23.368 -70.993)
		(end 42.291 -70.993)
		(stroke
			(width 0.381)
			(type default)
		)
		(layer "In10.Cu")
	)
	(gr_line
		(start 23.408386 -10.634218)
		(end 24.327866 -10.634218)
		(stroke
			(width 0.2)
			(type default)
		)
		(layer "In10.Cu")
	)
	(gr_arc
		(start 23.40864 -9.867138)
		(mid 23.024846 -10.250551)
		(end 23.408386 -10.634218)
		(stroke
			(width 0.2)
			(type default)
		)
		(layer "In10.Cu")
	)
	(gr_arc
		(start 24.327866 -10.634218)
		(mid 24.711406 -10.250678)
		(end 24.327866 -9.867138)
		(stroke
			(width 0.2)
			(type default)
		)
		(layer "In10.Cu")
	)
	(gr_line
		(start 24.327866 -9.867138)
		(end 23.40864 -9.867138)
		(stroke
			(width 0.2)
			(type default)
		)
		(layer "In10.Cu")
	)
	(gr_rect
		(start 24.991822 -4.097528)
		(end 25.708102 -8.293608)
		(stroke
			(width 0)
			(type default)
		)
		(fill no)
		(layer "In10.Cu")
	)
	(gr_arc
		(start 25.20696 -13.2588)
		(mid 25.222583 -13.296517)
		(end 25.2603 -13.31214)
		(stroke
			(width 0.2)
			(type default)
		)
		(layer "In10.Cu")
	)
	(gr_line
		(start 25.20696 -12.9032)
		(end 25.20696 -13.2588)
		(stroke
			(width 0.2)
			(type default)
		)
		(layer "In10.Cu")
	)
	(gr_arc
		(start 25.20696 -12.4968)
		(mid 25.222583 -12.534517)
		(end 25.2603 -12.55014)
		(stroke
			(width 0.2)
			(type default)
		)
		(layer "In10.Cu")
	)
	(gr_line
		(start 25.20696 -12.1412)
		(end 25.20696 -12.4968)
		(stroke
			(width 0.2)
			(type default)
		)
		(layer "In10.Cu")
	)
	(gr_line
		(start 25.2603 -13.31214)
		(end 25.6667 -13.31214)
		(stroke
			(width 0.2)
			(type default)
		)
		(layer "In10.Cu")
	)
	(gr_arc
		(start 25.2603 -12.84986)
		(mid 25.222583 -12.865483)
		(end 25.20696 -12.9032)
		(stroke
			(width 0.2)
			(type default)
		)
		(layer "In10.Cu")
	)
	(gr_line
		(start 25.2603 -12.55014)
		(end 25.6667 -12.55014)
		(stroke
			(width 0.2)
			(type default)
		)
		(layer "In10.Cu")
	)
	(gr_arc
		(start 25.2603 -12.08786)
		(mid 25.222583 -12.103483)
		(end 25.20696 -12.1412)
		(stroke
			(width 0.2)
			(type default)
		)
		(layer "In10.Cu")
	)
	(gr_line
		(start 25.4127 -14.20114)
		(end 26.276046 -14.20114)
		(stroke
			(width 0.2)
			(type default)
		)
		(layer "In10.Cu")
	)
	(gr_arc
		(start 25.4127 -13.43406)
		(mid 25.02916 -13.8176)
		(end 25.4127 -14.20114)
		(stroke
			(width 0.2)
			(type default)
		)
		(layer "In10.Cu")
	)
	(gr_arc
		(start 25.6667 -13.31214)
		(mid 25.704417 -13.296517)
		(end 25.72004 -13.2588)
		(stroke
			(width 0.2)
			(type default)
		)
		(layer "In10.Cu")
	)
	(gr_line
		(start 25.6667 -12.84986)
		(end 25.2603 -12.84986)
		(stroke
			(width 0.2)
			(type default)
		)
		(layer "In10.Cu")
	)
	(gr_arc
		(start 25.6667 -12.55014)
		(mid 25.704417 -12.534517)
		(end 25.72004 -12.4968)
		(stroke
			(width 0.2)
			(type default)
		)
		(layer "In10.Cu")
	)
	(gr_line
		(start 25.6667 -12.08786)
		(end 25.2603 -12.08786)
		(stroke
			(width 0.2)
			(type default)
		)
		(layer "In10.Cu")
	)
	(gr_line
		(start 25.72004 -13.2588)
		(end 25.72004 -12.9032)
		(stroke
			(width 0.2)
			(type default)
		)
		(layer "In10.Cu")
	)
	(gr_arc
		(start 25.72004 -12.9032)
		(mid 25.704417 -12.865483)
		(end 25.6667 -12.84986)
		(stroke
			(width 0.2)
			(type default)
		)
		(layer "In10.Cu")
	)
	(gr_line
		(start 25.72004 -12.4968)
		(end 25.72004 -12.1412)
		(stroke
			(width 0.2)
			(type default)
		)
		(layer "In10.Cu")
	)
	(gr_arc
		(start 25.72004 -12.1412)
		(mid 25.704417 -12.103483)
		(end 25.6667 -12.08786)
		(stroke
			(width 0.2)
			(type default)
		)
		(layer "In10.Cu")
	)
	(gr_arc
		(start 25.96896 -13.2588)
		(mid 25.984583 -13.296517)
		(end 26.0223 -13.31214)
		(stroke
			(width 0.2)
			(type default)
		)
		(layer "In10.Cu")
	)
	(gr_line
		(start 25.96896 -12.9032)
		(end 25.96896 -13.2588)
		(stroke
			(width 0.2)
			(type default)
		)
		(layer "In10.Cu")
	)
	(gr_arc
		(start 25.96896 -12.4968)
		(mid 25.984583 -12.534517)
		(end 26.0223 -12.55014)
		(stroke
			(width 0.2)
			(type default)
		)
		(layer "In10.Cu")
	)
	(gr_line
		(start 25.96896 -12.1412)
		(end 25.96896 -12.4968)
		(stroke
			(width 0.2)
			(type default)
		)
		(layer "In10.Cu")
	)
	(gr_rect
		(start 25.99182 -4.097528)
		(end 26.7081 -8.293608)
		(stroke
			(width 0)
			(type default)
		)
		(fill no)
		(layer "In10.Cu")
	)
	(gr_line
		(start 26.0223 -13.31214)
		(end 26.4287 -13.31214)
		(stroke
			(width 0.2)
			(type default)
		)
		(layer "In10.Cu")
	)
	(gr_arc
		(start 26.0223 -12.84986)
		(mid 25.984583 -12.865483)
		(end 25.96896 -12.9032)
		(stroke
			(width 0.2)
			(type default)
		)
		(layer "In10.Cu")
	)
	(gr_line
		(start 26.0223 -12.55014)
		(end 26.4287 -12.55014)
		(stroke
			(width 0.2)
			(type default)
		)
		(layer "In10.Cu")
	)
	(gr_arc
		(start 26.0223 -12.08786)
		(mid 25.984583 -12.103483)
		(end 25.96896 -12.1412)
		(stroke
			(width 0.2)
			(type default)
		)
		(layer "In10.Cu")
	)
	(gr_arc
		(start 26.276046 -14.20114)
		(mid 26.65984 -13.817727)
		(end 26.2763 -13.43406)
		(stroke
			(width 0.2)
			(type default)
		)
		(layer "In10.Cu")
	)
	(gr_line
		(start 26.2763 -13.43406)
		(end 25.4127 -13.43406)
		(stroke
			(width 0.2)
			(type default)
		)
		(layer "In10.Cu")
	)
	(gr_arc
		(start 26.4287 -13.31214)
		(mid 26.466417 -13.296517)
		(end 26.48204 -13.2588)
		(stroke
			(width 0.2)
			(type default)
		)
		(layer "In10.Cu")
	)
	(gr_line
		(start 26.4287 -12.84986)
		(end 26.0223 -12.84986)
		(stroke
			(width 0.2)
			(type default)
		)
		(layer "In10.Cu")
	)
	(gr_arc
		(start 26.4287 -12.55014)
		(mid 26.466417 -12.534517)
		(end 26.48204 -12.4968)
		(stroke
			(width 0.2)
			(type default)
		)
		(layer "In10.Cu")
	)
	(gr_line
		(start 26.4287 -12.08786)
		(end 26.0223 -12.08786)
		(stroke
			(width 0.2)
			(type default)
		)
		(layer "In10.Cu")
	)
	(gr_line
		(start 26.48204 -13.2588)
		(end 26.48204 -12.9032)
		(stroke
			(width 0.2)
			(type default)
		)
		(layer "In10.Cu")
	)
	(gr_arc
		(start 26.48204 -12.9032)
		(mid 26.466417 -12.865483)
		(end 26.4287 -12.84986)
		(stroke
			(width 0.2)
			(type default)
		)
		(layer "In10.Cu")
	)
	(gr_line
		(start 26.48204 -12.4968)
		(end 26.48204 -12.1412)
		(stroke
			(width 0.2)
			(type default)
		)
		(layer "In10.Cu")
	)
	(gr_arc
		(start 26.48204 -12.1412)
		(mid 26.466417 -12.103483)
		(end 26.4287 -12.08786)
		(stroke
			(width 0.2)
			(type default)
		)
		(layer "In10.Cu")
	)
	(gr_line
		(start 27.408378 -10.634218)
		(end 28.327604 -10.634218)
		(stroke
			(width 0.2)
			(type default)
		)
		(layer "In10.Cu")
	)
	(gr_arc
		(start 27.408378 -9.867138)
		(mid 27.024838 -10.250678)
		(end 27.408378 -10.634218)
		(stroke
			(width 0.2)
			(type default)
		)
		(layer "In10.Cu")
	)
	(gr_arc
		(start 28.327604 -10.634218)
		(mid 28.711398 -10.250805)
		(end 28.327858 -9.867138)
		(stroke
			(width 0.2)
			(type default)
		)
		(layer "In10.Cu")
	)
	(gr_line
		(start 28.327858 -9.867138)
		(end 27.408378 -9.867138)
		(stroke
			(width 0.2)
			(type default)
		)
		(layer "In10.Cu")
	)
	(gr_rect
		(start 28.991814 -4.097528)
		(end 29.708094 -8.293608)
		(stroke
			(width 0)
			(type default)
		)
		(fill no)
		(layer "In10.Cu")
	)
	(gr_arc
		(start 29.20746 -13.2588)
		(mid 29.223083 -13.296517)
		(end 29.2608 -13.31214)
		(stroke
			(width 0.2)
			(type default)
		)
		(layer "In10.Cu")
	)
	(gr_line
		(start 29.20746 -12.9032)
		(end 29.20746 -13.2588)
		(stroke
			(width 0.2)
			(type default)
		)
		(layer "In10.Cu")
	)
	(gr_arc
		(start 29.20746 -12.4968)
		(mid 29.223083 -12.534517)
		(end 29.2608 -12.55014)
		(stroke
			(width 0.2)
			(type default)
		)
		(layer "In10.Cu")
	)
	(gr_line
		(start 29.20746 -12.1412)
		(end 29.20746 -12.4968)
		(stroke
			(width 0.2)
			(type default)
		)
		(layer "In10.Cu")
	)
	(gr_line
		(start 29.2608 -13.31214)
		(end 29.6672 -13.31214)
		(stroke
			(width 0.2)
			(type default)
		)
		(layer "In10.Cu")
	)
	(gr_arc
		(start 29.2608 -12.84986)
		(mid 29.223083 -12.865483)
		(end 29.20746 -12.9032)
		(stroke
			(width 0.2)
			(type default)
		)
		(layer "In10.Cu")
	)
	(gr_line
		(start 29.2608 -12.55014)
		(end 29.6672 -12.55014)
		(stroke
			(width 0.2)
			(type default)
		)
		(layer "In10.Cu")
	)
	(gr_arc
		(start 29.2608 -12.08786)
		(mid 29.223083 -12.103483)
		(end 29.20746 -12.1412)
		(stroke
			(width 0.2)
			(type default)
		)
		(layer "In10.Cu")
	)
	(gr_line
		(start 29.4132 -14.96314)
		(end 30.276546 -14.96314)
		(stroke
			(width 0.2)
			(type default)
		)
		(layer "In10.Cu")
	)
	(gr_arc
		(start 29.4132 -14.19606)
		(mid 29.02966 -14.5796)
		(end 29.4132 -14.96314)
		(stroke
			(width 0.2)
			(type default)
		)
		(layer "In10.Cu")
	)
	(gr_arc
		(start 29.6672 -13.31214)
		(mid 29.704917 -13.296517)
		(end 29.72054 -13.2588)
		(stroke
			(width 0.2)
			(type default)
		)
		(layer "In10.Cu")
	)
	(gr_line
		(start 29.6672 -12.84986)
		(end 29.2608 -12.84986)
		(stroke
			(width 0.2)
			(type default)
		)
		(layer "In10.Cu")
	)
	(gr_arc
		(start 29.6672 -12.55014)
		(mid 29.704917 -12.534517)
		(end 29.72054 -12.4968)
		(stroke
			(width 0.2)
			(type default)
		)
		(layer "In10.Cu")
	)
	(gr_line
		(start 29.6672 -12.08786)
		(end 29.2608 -12.08786)
		(stroke
			(width 0.2)
			(type default)
		)
		(layer "In10.Cu")
	)
	(gr_line
		(start 29.72054 -13.2588)
		(end 29.72054 -12.9032)
		(stroke
			(width 0.2)
			(type default)
		)
		(layer "In10.Cu")
	)
	(gr_arc
		(start 29.72054 -12.9032)
		(mid 29.704917 -12.865483)
		(end 29.6672 -12.84986)
		(stroke
			(width 0.2)
			(type default)
		)
		(layer "In10.Cu")
	)
	(gr_line
		(start 29.72054 -12.4968)
		(end 29.72054 -12.1412)
		(stroke
			(width 0.2)
			(type default)
		)
		(layer "In10.Cu")
	)
	(gr_arc
		(start 29.72054 -12.1412)
		(mid 29.704917 -12.103483)
		(end 29.6672 -12.08786)
		(stroke
			(width 0.2)
			(type default)
		)
		(layer "In10.Cu")
	)
	(gr_arc
		(start 29.96946 -13.2588)
		(mid 29.985083 -13.296517)
		(end 30.0228 -13.31214)
		(stroke
			(width 0.2)
			(type default)
		)
		(layer "In10.Cu")
	)
	(gr_line
		(start 29.96946 -12.9032)
		(end 29.96946 -13.2588)
		(stroke
			(width 0.2)
			(type default)
		)
		(layer "In10.Cu")
	)
	(gr_arc
		(start 29.96946 -12.4968)
		(mid 29.985083 -12.534517)
		(end 30.0228 -12.55014)
		(stroke
			(width 0.2)
			(type default)
		)
		(layer "In10.Cu")
	)
	(gr_line
		(start 29.96946 -12.1412)
		(end 29.96946 -12.4968)
		(stroke
			(width 0.2)
			(type default)
		)
		(layer "In10.Cu")
	)
	(gr_rect
		(start 29.991812 -4.097528)
		(end 30.708092 -8.293608)
		(stroke
			(width 0)
			(type default)
		)
		(fill no)
		(layer "In10.Cu")
	)
	(gr_line
		(start 30.0228 -13.31214)
		(end 30.4292 -13.31214)
		(stroke
			(width 0.2)
			(type default)
		)
		(layer "In10.Cu")
	)
	(gr_arc
		(start 30.0228 -12.84986)
		(mid 29.985083 -12.865483)
		(end 29.96946 -12.9032)
		(stroke
			(width 0.2)
			(type default)
		)
		(layer "In10.Cu")
	)
	(gr_line
		(start 30.0228 -12.55014)
		(end 30.4292 -12.55014)
		(stroke
			(width 0.2)
			(type default)
		)
		(layer "In10.Cu")
	)
	(gr_arc
		(start 30.0228 -12.08786)
		(mid 29.985083 -12.103483)
		(end 29.96946 -12.1412)
		(stroke
			(width 0.2)
			(type default)
		)
		(layer "In10.Cu")
	)
	(gr_arc
		(start 30.276546 -14.96314)
		(mid 30.66034 -14.579727)
		(end 30.2768 -14.19606)
		(stroke
			(width 0.2)
			(type default)
		)
		(layer "In10.Cu")
	)
	(gr_line
		(start 30.2768 -14.19606)
		(end 29.4132 -14.19606)
		(stroke
			(width 0.2)
			(type default)
		)
		(layer "In10.Cu")
	)
	(gr_arc
		(start 30.4292 -13.31214)
		(mid 30.466917 -13.296517)
		(end 30.48254 -13.2588)
		(stroke
			(width 0.2)
			(type default)
		)
		(layer "In10.Cu")
	)
	(gr_line
		(start 30.4292 -12.84986)
		(end 30.0228 -12.84986)
		(stroke
			(width 0.2)
			(type default)
		)
		(layer "In10.Cu")
	)
	(gr_arc
		(start 30.4292 -12.55014)
		(mid 30.466917 -12.534517)
		(end 30.48254 -12.4968)
		(stroke
			(width 0.2)
			(type default)
		)
		(layer "In10.Cu")
	)
	(gr_line
		(start 30.4292 -12.08786)
		(end 30.0228 -12.08786)
		(stroke
			(width 0.2)
			(type default)
		)
		(layer "In10.Cu")
	)
	(gr_line
		(start 30.48254 -13.2588)
		(end 30.48254 -12.9032)
		(stroke
			(width 0.2)
			(type default)
		)
		(layer "In10.Cu")
	)
	(gr_arc
		(start 30.48254 -12.9032)
		(mid 30.466917 -12.865483)
		(end 30.4292 -12.84986)
		(stroke
			(width 0.2)
			(type default)
		)
		(layer "In10.Cu")
	)
	(gr_line
		(start 30.48254 -12.4968)
		(end 30.48254 -12.1412)
		(stroke
			(width 0.2)
			(type default)
		)
		(layer "In10.Cu")
	)
	(gr_arc
		(start 30.48254 -12.1412)
		(mid 30.466917 -12.103483)
		(end 30.4292 -12.08786)
		(stroke
			(width 0.2)
			(type default)
		)
		(layer "In10.Cu")
	)
	(gr_line
		(start 31.40837 -10.634218)
		(end 32.327596 -10.634218)
		(stroke
			(width 0.2)
			(type default)
		)
		(layer "In10.Cu")
	)
	(gr_arc
		(start 31.40837 -9.867138)
		(mid 31.02483 -10.250678)
		(end 31.40837 -10.634218)
		(stroke
			(width 0.2)
			(type default)
		)
		(layer "In10.Cu")
	)
	(gr_arc
		(start 32.327596 -10.634218)
		(mid 32.71139 -10.250805)
		(end 32.32785 -9.867138)
		(stroke
			(width 0.2)
			(type default)
		)
		(layer "In10.Cu")
	)
	(gr_line
		(start 32.32785 -9.867138)
		(end 31.40837 -9.867138)
		(stroke
			(width 0.2)
			(type default)
		)
		(layer "In10.Cu")
	)
	(gr_rect
		(start 32.991806 -4.097528)
		(end 33.708086 -8.293608)
		(stroke
			(width 0)
			(type default)
		)
		(fill no)
		(layer "In10.Cu")
	)
	(gr_arc
		(start 33.22066 -13.2588)
		(mid 33.236283 -13.296517)
		(end 33.274 -13.31214)
		(stroke
			(width 0.2)
			(type default)
		)
		(layer "In10.Cu")
	)
	(gr_line
		(start 33.22066 -12.9032)
		(end 33.22066 -13.2588)
		(stroke
			(width 0.2)
			(type default)
		)
		(layer "In10.Cu")
	)
	(gr_arc
		(start 33.22066 -12.4968)
		(mid 33.236283 -12.534517)
		(end 33.274 -12.55014)
		(stroke
			(width 0.2)
			(type default)
		)
		(layer "In10.Cu")
	)
	(gr_line
		(start 33.22066 -12.1412)
		(end 33.22066 -12.4968)
		(stroke
			(width 0.2)
			(type default)
		)
		(layer "In10.Cu")
	)
	(gr_line
		(start 33.274 -13.31214)
		(end 33.6804 -13.31214)
		(stroke
			(width 0.2)
			(type default)
		)
		(layer "In10.Cu")
	)
	(gr_arc
		(start 33.274 -12.84986)
		(mid 33.236283 -12.865483)
		(end 33.22066 -12.9032)
		(stroke
			(width 0.2)
			(type default)
		)
		(layer "In10.Cu")
	)
	(gr_line
		(start 33.274 -12.55014)
		(end 33.6804 -12.55014)
		(stroke
			(width 0.2)
			(type default)
		)
		(layer "In10.Cu")
	)
	(gr_arc
		(start 33.274 -12.08786)
		(mid 33.236283 -12.103483)
		(end 33.22066 -12.1412)
		(stroke
			(width 0.2)
			(type default)
		)
		(layer "In10.Cu")
	)
	(gr_line
		(start 33.4264 -14.96314)
		(end 34.289746 -14.96314)
		(stroke
			(width 0.2)
			(type default)
		)
		(layer "In10.Cu")
	)
	(gr_arc
		(start 33.4264 -14.19606)
		(mid 33.04286 -14.5796)
		(end 33.4264 -14.96314)
		(stroke
			(width 0.2)
			(type default)
		)
		(layer "In10.Cu")
	)
	(gr_arc
		(start 33.6804 -13.31214)
		(mid 33.718117 -13.296517)
		(end 33.73374 -13.2588)
		(stroke
			(width 0.2)
			(type default)
		)
		(layer "In10.Cu")
	)
	(gr_line
		(start 33.6804 -12.84986)
		(end 33.274 -12.84986)
		(stroke
			(width 0.2)
			(type default)
		)
		(layer "In10.Cu")
	)
	(gr_arc
		(start 33.6804 -12.55014)
		(mid 33.718117 -12.534517)
		(end 33.73374 -12.4968)
		(stroke
			(width 0.2)
			(type default)
		)
		(layer "In10.Cu")
	)
	(gr_line
		(start 33.6804 -12.08786)
		(end 33.274 -12.08786)
		(stroke
			(width 0.2)
			(type default)
		)
		(layer "In10.Cu")
	)
	(gr_line
		(start 33.73374 -13.2588)
		(end 33.73374 -12.9032)
		(stroke
			(width 0.2)
			(type default)
		)
		(layer "In10.Cu")
	)
	(gr_arc
		(start 33.73374 -12.9032)
		(mid 33.718117 -12.865483)
		(end 33.6804 -12.84986)
		(stroke
			(width 0.2)
			(type default)
		)
		(layer "In10.Cu")
	)
	(gr_line
		(start 33.73374 -12.4968)
		(end 33.73374 -12.1412)
		(stroke
			(width 0.2)
			(type default)
		)
		(layer "In10.Cu")
	)
	(gr_arc
		(start 33.73374 -12.1412)
		(mid 33.718117 -12.103483)
		(end 33.6804 -12.08786)
		(stroke
			(width 0.2)
			(type default)
		)
		(layer "In10.Cu")
	)
	(gr_arc
		(start 33.98266 -13.2588)
		(mid 33.998283 -13.296517)
		(end 34.036 -13.31214)
		(stroke
			(width 0.2)
			(type default)
		)
		(layer "In10.Cu")
	)
	(gr_line
		(start 33.98266 -12.9032)
		(end 33.98266 -13.2588)
		(stroke
			(width 0.2)
			(type default)
		)
		(layer "In10.Cu")
	)
	(gr_arc
		(start 33.98266 -12.4968)
		(mid 33.998283 -12.534517)
		(end 34.036 -12.55014)
		(stroke
			(width 0.2)
			(type default)
		)
		(layer "In10.Cu")
	)
	(gr_line
		(start 33.98266 -12.1412)
		(end 33.98266 -12.4968)
		(stroke
			(width 0.2)
			(type default)
		)
		(layer "In10.Cu")
	)
	(gr_rect
		(start 33.991804 -4.097528)
		(end 34.708084 -8.293608)
		(stroke
			(width 0)
			(type default)
		)
		(fill no)
		(layer "In10.Cu")
	)
	(gr_line
		(start 34.036 -13.31214)
		(end 34.4424 -13.31214)
		(stroke
			(width 0.2)
			(type default)
		)
		(layer "In10.Cu")
	)
	(gr_arc
		(start 34.036 -12.84986)
		(mid 33.998283 -12.865483)
		(end 33.98266 -12.9032)
		(stroke
			(width 0.2)
			(type default)
		)
		(layer "In10.Cu")
	)
	(gr_line
		(start 34.036 -12.55014)
		(end 34.4424 -12.55014)
		(stroke
			(width 0.2)
			(type default)
		)
		(layer "In10.Cu")
	)
	(gr_arc
		(start 34.036 -12.08786)
		(mid 33.998283 -12.103483)
		(end 33.98266 -12.1412)
		(stroke
			(width 0.2)
			(type default)
		)
		(layer "In10.Cu")
	)
	(gr_arc
		(start 34.289746 -14.96314)
		(mid 34.67354 -14.579727)
		(end 34.29 -14.19606)
		(stroke
			(width 0.2)
			(type default)
		)
		(layer "In10.Cu")
	)
	(gr_line
		(start 34.29 -14.19606)
		(end 33.4264 -14.19606)
		(stroke
			(width 0.2)
			(type default)
		)
		(layer "In10.Cu")
	)
	(gr_arc
		(start 34.4424 -13.31214)
		(mid 34.480117 -13.296517)
		(end 34.49574 -13.2588)
		(stroke
			(width 0.2)
			(type default)
		)
		(layer "In10.Cu")
	)
	(gr_line
		(start 34.4424 -12.84986)
		(end 34.036 -12.84986)
		(stroke
			(width 0.2)
			(type default)
		)
		(layer "In10.Cu")
	)
	(gr_arc
		(start 34.4424 -12.55014)
		(mid 34.480117 -12.534517)
		(end 34.49574 -12.4968)
		(stroke
			(width 0.2)
			(type default)
		)
		(layer "In10.Cu")
	)
	(gr_line
		(start 34.4424 -12.08786)
		(end 34.036 -12.08786)
		(stroke
			(width 0.2)
			(type default)
		)
		(layer "In10.Cu")
	)
	(gr_line
		(start 34.49574 -13.2588)
		(end 34.49574 -12.9032)
		(stroke
			(width 0.2)
			(type default)
		)
		(layer "In10.Cu")
	)
	(gr_arc
		(start 34.49574 -12.9032)
		(mid 34.480117 -12.865483)
		(end 34.4424 -12.84986)
		(stroke
			(width 0.2)
			(type default)
		)
		(layer "In10.Cu")
	)
	(gr_line
		(start 34.49574 -12.4968)
		(end 34.49574 -12.1412)
		(stroke
			(width 0.2)
			(type default)
		)
		(layer "In10.Cu")
	)
	(gr_arc
		(start 34.49574 -12.1412)
		(mid 34.480117 -12.103483)
		(end 34.4424 -12.08786)
		(stroke
			(width 0.2)
			(type default)
		)
		(layer "In10.Cu")
	)
	(gr_line
		(start 35.408362 -10.634218)
		(end 36.327588 -10.634218)
		(stroke
			(width 0.2)
			(type default)
		)
		(layer "In10.Cu")
	)
	(gr_arc
		(start 35.408362 -9.867138)
		(mid 35.024822 -10.250678)
		(end 35.408362 -10.634218)
		(stroke
			(width 0.2)
			(type default)
		)
		(layer "In10.Cu")
	)
	(gr_arc
		(start 36.327588 -10.634218)
		(mid 36.711382 -10.250805)
		(end 36.327842 -9.867138)
		(stroke
			(width 0.2)
			(type default)
		)
		(layer "In10.Cu")
	)
	(gr_line
		(start 36.327842 -9.867138)
		(end 35.408362 -9.867138)
		(stroke
			(width 0.2)
			(type default)
		)
		(layer "In10.Cu")
	)
	(gr_rect
		(start 36.991798 -4.097528)
		(end 37.708078 -8.293608)
		(stroke
			(width 0)
			(type default)
		)
		(fill no)
		(layer "In10.Cu")
	)
	(gr_arc
		(start 37.21227 -13.2588)
		(mid 37.227893 -13.296517)
		(end 37.26561 -13.31214)
		(stroke
			(width 0.2)
			(type default)
		)
		(layer "In10.Cu")
	)
	(gr_line
		(start 37.21227 -12.9032)
		(end 37.21227 -13.2588)
		(stroke
			(width 0.2)
			(type default)
		)
		(layer "In10.Cu")
	)
	(gr_arc
		(start 37.21227 -12.4968)
		(mid 37.227893 -12.534517)
		(end 37.26561 -12.55014)
		(stroke
			(width 0.2)
			(type default)
		)
		(layer "In10.Cu")
	)
	(gr_line
		(start 37.21227 -12.1412)
		(end 37.21227 -12.4968)
		(stroke
			(width 0.2)
			(type default)
		)
		(layer "In10.Cu")
	)
	(gr_line
		(start 37.26561 -13.31214)
		(end 37.67201 -13.31214)
		(stroke
			(width 0.2)
			(type default)
		)
		(layer "In10.Cu")
	)
	(gr_arc
		(start 37.26561 -12.84986)
		(mid 37.227893 -12.865483)
		(end 37.21227 -12.9032)
		(stroke
			(width 0.2)
			(type default)
		)
		(layer "In10.Cu")
	)
	(gr_line
		(start 37.26561 -12.55014)
		(end 37.67201 -12.55014)
		(stroke
			(width 0.2)
			(type default)
		)
		(layer "In10.Cu")
	)
	(gr_arc
		(start 37.26561 -12.08786)
		(mid 37.227893 -12.103483)
		(end 37.21227 -12.1412)
		(stroke
			(width 0.2)
			(type default)
		)
		(layer "In10.Cu")
	)
	(gr_line
		(start 37.41801 -14.20114)
		(end 38.281356 -14.20114)
		(stroke
			(width 0.2)
			(type default)
		)
		(layer "In10.Cu")
	)
	(gr_arc
		(start 37.41801 -13.43406)
		(mid 37.03447 -13.8176)
		(end 37.41801 -14.20114)
		(stroke
			(width 0.2)
			(type default)
		)
		(layer "In10.Cu")
	)
	(gr_arc
		(start 37.67201 -13.31214)
		(mid 37.709727 -13.296517)
		(end 37.72535 -13.2588)
		(stroke
			(width 0.2)
			(type default)
		)
		(layer "In10.Cu")
	)
	(gr_line
		(start 37.67201 -12.84986)
		(end 37.26561 -12.84986)
		(stroke
			(width 0.2)
			(type default)
		)
		(layer "In10.Cu")
	)
	(gr_arc
		(start 37.67201 -12.55014)
		(mid 37.709727 -12.534517)
		(end 37.72535 -12.4968)
		(stroke
			(width 0.2)
			(type default)
		)
		(layer "In10.Cu")
	)
	(gr_line
		(start 37.67201 -12.08786)
		(end 37.26561 -12.08786)
		(stroke
			(width 0.2)
			(type default)
		)
		(layer "In10.Cu")
	)
	(gr_line
		(start 37.72535 -13.2588)
		(end 37.72535 -12.9032)
		(stroke
			(width 0.2)
			(type default)
		)
		(layer "In10.Cu")
	)
	(gr_arc
		(start 37.72535 -12.9032)
		(mid 37.709727 -12.865483)
		(end 37.67201 -12.84986)
		(stroke
			(width 0.2)
			(type default)
		)
		(layer "In10.Cu")
	)
	(gr_line
		(start 37.72535 -12.4968)
		(end 37.72535 -12.1412)
		(stroke
			(width 0.2)
			(type default)
		)
		(layer "In10.Cu")
	)
	(gr_arc
		(start 37.72535 -12.1412)
		(mid 37.709727 -12.103483)
		(end 37.67201 -12.08786)
		(stroke
			(width 0.2)
			(type default)
		)
		(layer "In10.Cu")
	)
	(gr_arc
		(start 37.88664 -30.2006)
		(mid 38.27018 -30.58414)
		(end 38.65372 -30.2006)
		(stroke
			(width 0.2)
			(type default)
		)
		(layer "In10.Cu")
	)
	(gr_line
		(start 37.88664 -29.337)
		(end 37.88664 -30.2006)
		(stroke
			(width 0.2)
			(type default)
		)
		(layer "In10.Cu")
	)
	(gr_arc
		(start 37.97427 -13.2588)
		(mid 37.989893 -13.296517)
		(end 38.02761 -13.31214)
		(stroke
			(width 0.2)
			(type default)
		)
		(layer "In10.Cu")
	)
	(gr_line
		(start 37.97427 -12.9032)
		(end 37.97427 -13.2588)
		(stroke
			(width 0.2)
			(type default)
		)
		(layer "In10.Cu")
	)
	(gr_arc
		(start 37.97427 -12.4968)
		(mid 37.989893 -12.534517)
		(end 38.02761 -12.55014)
		(stroke
			(width 0.2)
			(type default)
		)
		(layer "In10.Cu")
	)
	(gr_line
		(start 37.97427 -12.1412)
		(end 37.97427 -12.4968)
		(stroke
			(width 0.2)
			(type default)
		)
		(layer "In10.Cu")
	)
	(gr_rect
		(start 37.991796 -4.097528)
		(end 38.708076 -8.293608)
		(stroke
			(width 0)
			(type default)
		)
		(fill no)
		(layer "In10.Cu")
	)
	(gr_line
		(start 38.02761 -13.31214)
		(end 38.43401 -13.31214)
		(stroke
			(width 0.2)
			(type default)
		)
		(layer "In10.Cu")
	)
	(gr_arc
		(start 38.02761 -12.84986)
		(mid 37.989893 -12.865483)
		(end 37.97427 -12.9032)
		(stroke
			(width 0.2)
			(type default)
		)
		(layer "In10.Cu")
	)
	(gr_line
		(start 38.02761 -12.55014)
		(end 38.43401 -12.55014)
		(stroke
			(width 0.2)
			(type default)
		)
		(layer "In10.Cu")
	)
	(gr_arc
		(start 38.02761 -12.08786)
		(mid 37.989893 -12.103483)
		(end 37.97427 -12.1412)
		(stroke
			(width 0.2)
			(type default)
		)
		(layer "In10.Cu")
	)
	(gr_arc
		(start 38.281356 -14.20114)
		(mid 38.66515 -13.817727)
		(end 38.28161 -13.43406)
		(stroke
			(width 0.2)
			(type default)
		)
		(layer "In10.Cu")
	)
	(gr_line
		(start 38.28161 -13.43406)
		(end 37.41801 -13.43406)
		(stroke
			(width 0.2)
			(type default)
		)
		(layer "In10.Cu")
	)
	(gr_arc
		(start 38.43401 -13.31214)
		(mid 38.471727 -13.296517)
		(end 38.48735 -13.2588)
		(stroke
			(width 0.2)
			(type default)
		)
		(layer "In10.Cu")
	)
	(gr_line
		(start 38.43401 -12.84986)
		(end 38.02761 -12.84986)
		(stroke
			(width 0.2)
			(type default)
		)
		(layer "In10.Cu")
	)
	(gr_arc
		(start 38.43401 -12.55014)
		(mid 38.471727 -12.534517)
		(end 38.48735 -12.4968)
		(stroke
			(width 0.2)
			(type default)
		)
		(layer "In10.Cu")
	)
	(gr_line
		(start 38.43401 -12.08786)
		(end 38.02761 -12.08786)
		(stroke
			(width 0.2)
			(type default)
		)
		(layer "In10.Cu")
	)
	(gr_line
		(start 38.48735 -13.2588)
		(end 38.48735 -12.9032)
		(stroke
			(width 0.2)
			(type default)
		)
		(layer "In10.Cu")
	)
	(gr_arc
		(start 38.48735 -12.9032)
		(mid 38.471727 -12.865483)
		(end 38.43401 -12.84986)
		(stroke
			(width 0.2)
			(type default)
		)
		(layer "In10.Cu")
	)
	(gr_line
		(start 38.48735 -12.4968)
		(end 38.48735 -12.1412)
		(stroke
			(width 0.2)
			(type default)
		)
		(layer "In10.Cu")
	)
	(gr_arc
		(start 38.48735 -12.1412)
		(mid 38.471727 -12.103483)
		(end 38.43401 -12.08786)
		(stroke
			(width 0.2)
			(type default)
		)
		(layer "In10.Cu")
	)
	(gr_line
		(start 38.65372 -30.2006)
		(end 38.65372 -29.337254)
		(stroke
			(width 0.2)
			(type default)
		)
		(layer "In10.Cu")
	)
	(gr_arc
		(start 38.65372 -29.337254)
		(mid 38.270307 -28.95346)
		(end 37.88664 -29.337)
		(stroke
			(width 0.2)
			(type default)
		)
		(layer "In10.Cu")
	)
	(gr_line
		(start 39.408354 -10.634218)
		(end 40.327834 -10.634218)
		(stroke
			(width 0.2)
			(type default)
		)
		(layer "In10.Cu")
	)
	(gr_arc
		(start 39.408608 -9.867138)
		(mid 39.024814 -10.250551)
		(end 39.408354 -10.634218)
		(stroke
			(width 0.2)
			(type default)
		)
		(layer "In10.Cu")
	)
	(gr_line
		(start 39.44366 -12.73048)
		(end 40.40124 -12.73048)
		(stroke
			(width 0.2)
			(type default)
		)
		(layer "In10.Cu")
	)
	(gr_arc
		(start 39.443914 -11.9634)
		(mid 39.06012 -12.346813)
		(end 39.44366 -12.73048)
		(stroke
			(width 0.2)
			(type default)
		)
		(layer "In10.Cu")
	)
	(gr_arc
		(start 40.327834 -10.634218)
		(mid 40.711374 -10.250678)
		(end 40.327834 -9.867138)
		(stroke
			(width 0.2)
			(type default)
		)
		(layer "In10.Cu")
	)
	(gr_line
		(start 40.327834 -9.867138)
		(end 39.408608 -9.867138)
		(stroke
			(width 0.2)
			(type default)
		)
		(layer "In10.Cu")
	)
	(gr_arc
		(start 40.40124 -12.73048)
		(mid 40.78478 -12.34694)
		(end 40.40124 -11.9634)
		(stroke
			(width 0.2)
			(type default)
		)
		(layer "In10.Cu")
	)
	(gr_line
		(start 40.40124 -11.9634)
		(end 39.443914 -11.9634)
		(stroke
			(width 0.2)
			(type default)
		)
		(layer "In10.Cu")
	)
	(gr_rect
		(start 40.99179 -4.097528)
		(end 41.70807 -8.293608)
		(stroke
			(width 0)
			(type default)
		)
		(fill no)
		(layer "In10.Cu")
	)
	(gr_arc
		(start 41.212262 -13.2588)
		(mid 41.227885 -13.296517)
		(end 41.265602 -13.31214)
		(stroke
			(width 0.2)
			(type default)
		)
		(layer "In10.Cu")
	)
	(gr_line
		(start 41.212262 -12.9032)
		(end 41.212262 -13.2588)
		(stroke
			(width 0.2)
			(type default)
		)
		(layer "In10.Cu")
	)
	(gr_arc
		(start 41.212262 -12.4968)
		(mid 41.227885 -12.534517)
		(end 41.265602 -12.55014)
		(stroke
			(width 0.2)
			(type default)
		)
		(layer "In10.Cu")
	)
	(gr_line
		(start 41.212262 -12.1412)
		(end 41.212262 -12.4968)
		(stroke
			(width 0.2)
			(type default)
		)
		(layer "In10.Cu")
	)
	(gr_line
		(start 41.265602 -13.31214)
		(end 41.672002 -13.31214)
		(stroke
			(width 0.2)
			(type default)
		)
		(layer "In10.Cu")
	)
	(gr_arc
		(start 41.265602 -12.84986)
		(mid 41.227885 -12.865483)
		(end 41.212262 -12.9032)
		(stroke
			(width 0.2)
			(type default)
		)
		(layer "In10.Cu")
	)
	(gr_line
		(start 41.265602 -12.55014)
		(end 41.672002 -12.55014)
		(stroke
			(width 0.2)
			(type default)
		)
		(layer "In10.Cu")
	)
	(gr_arc
		(start 41.265602 -12.08786)
		(mid 41.227885 -12.103483)
		(end 41.212262 -12.1412)
		(stroke
			(width 0.2)
			(type default)
		)
		(layer "In10.Cu")
	)
	(gr_line
		(start 41.418002 -14.20114)
		(end 42.281348 -14.20114)
		(stroke
			(width 0.2)
			(type default)
		)
		(layer "In10.Cu")
	)
	(gr_arc
		(start 41.418002 -13.43406)
		(mid 41.034462 -13.8176)
		(end 41.418002 -14.20114)
		(stroke
			(width 0.2)
			(type default)
		)
		(layer "In10.Cu")
	)
	(gr_arc
		(start 41.672002 -13.31214)
		(mid 41.709719 -13.296517)
		(end 41.725342 -13.2588)
		(stroke
			(width 0.2)
			(type default)
		)
		(layer "In10.Cu")
	)
	(gr_line
		(start 41.672002 -12.84986)
		(end 41.265602 -12.84986)
		(stroke
			(width 0.2)
			(type default)
		)
		(layer "In10.Cu")
	)
	(gr_arc
		(start 41.672002 -12.55014)
		(mid 41.709719 -12.534517)
		(end 41.725342 -12.4968)
		(stroke
			(width 0.2)
			(type default)
		)
		(layer "In10.Cu")
	)
	(gr_line
		(start 41.672002 -12.08786)
		(end 41.265602 -12.08786)
		(stroke
			(width 0.2)
			(type default)
		)
		(layer "In10.Cu")
	)
	(gr_line
		(start 41.725342 -13.2588)
		(end 41.725342 -12.9032)
		(stroke
			(width 0.2)
			(type default)
		)
		(layer "In10.Cu")
	)
	(gr_arc
		(start 41.725342 -12.9032)
		(mid 41.709719 -12.865483)
		(end 41.672002 -12.84986)
		(stroke
			(width 0.2)
			(type default)
		)
		(layer "In10.Cu")
	)
	(gr_line
		(start 41.725342 -12.4968)
		(end 41.725342 -12.1412)
		(stroke
			(width 0.2)
			(type default)
		)
		(layer "In10.Cu")
	)
	(gr_arc
		(start 41.725342 -12.1412)
		(mid 41.709719 -12.103483)
		(end 41.672002 -12.08786)
		(stroke
			(width 0.2)
			(type default)
		)
		(layer "In10.Cu")
	)
	(gr_arc
		(start 41.974262 -13.2588)
		(mid 41.989885 -13.296517)
		(end 42.027602 -13.31214)
		(stroke
			(width 0.2)
			(type default)
		)
		(layer "In10.Cu")
	)
	(gr_line
		(start 41.974262 -12.9032)
		(end 41.974262 -13.2588)
		(stroke
			(width 0.2)
			(type default)
		)
		(layer "In10.Cu")
	)
	(gr_arc
		(start 41.974262 -12.4968)
		(mid 41.989885 -12.534517)
		(end 42.027602 -12.55014)
		(stroke
			(width 0.2)
			(type default)
		)
		(layer "In10.Cu")
	)
	(gr_line
		(start 41.974262 -12.1412)
		(end 41.974262 -12.4968)
		(stroke
			(width 0.2)
			(type default)
		)
		(layer "In10.Cu")
	)
	(gr_rect
		(start 41.991788 -4.097528)
		(end 42.708068 -8.293608)
		(stroke
			(width 0)
			(type default)
		)
		(fill no)
		(layer "In10.Cu")
	)
	(gr_line
		(start 42.027602 -13.31214)
		(end 42.434002 -13.31214)
		(stroke
			(width 0.2)
			(type default)
		)
		(layer "In10.Cu")
	)
	(gr_arc
		(start 42.027602 -12.84986)
		(mid 41.989885 -12.865483)
		(end 41.974262 -12.9032)
		(stroke
			(width 0.2)
			(type default)
		)
		(layer "In10.Cu")
	)
	(gr_line
		(start 42.027602 -12.55014)
		(end 42.434002 -12.55014)
		(stroke
			(width 0.2)
			(type default)
		)
		(layer "In10.Cu")
	)
	(gr_arc
		(start 42.027602 -12.08786)
		(mid 41.989885 -12.103483)
		(end 41.974262 -12.1412)
		(stroke
			(width 0.2)
			(type default)
		)
		(layer "In10.Cu")
	)
	(gr_arc
		(start 42.281348 -14.20114)
		(mid 42.665142 -13.817727)
		(end 42.281602 -13.43406)
		(stroke
			(width 0.2)
			(type default)
		)
		(layer "In10.Cu")
	)
	(gr_line
		(start 42.281602 -13.43406)
		(end 41.418002 -13.43406)
		(stroke
			(width 0.2)
			(type default)
		)
		(layer "In10.Cu")
	)
	(gr_line
		(start 42.291 -70.993)
		(end 46.101 -67.183)
		(stroke
			(width 0.381)
			(type default)
		)
		(layer "In10.Cu")
	)
	(gr_arc
		(start 42.434002 -13.31214)
		(mid 42.471719 -13.296517)
		(end 42.487342 -13.2588)
		(stroke
			(width 0.2)
			(type default)
		)
		(layer "In10.Cu")
	)
	(gr_line
		(start 42.434002 -12.84986)
		(end 42.027602 -12.84986)
		(stroke
			(width 0.2)
			(type default)
		)
		(layer "In10.Cu")
	)
	(gr_arc
		(start 42.434002 -12.55014)
		(mid 42.471719 -12.534517)
		(end 42.487342 -12.4968)
		(stroke
			(width 0.2)
			(type default)
		)
		(layer "In10.Cu")
	)
	(gr_line
		(start 42.434002 -12.08786)
		(end 42.027602 -12.08786)
		(stroke
			(width 0.2)
			(type default)
		)
		(layer "In10.Cu")
	)
	(gr_line
		(start 42.45356 -44.5389)
		(end 43.41114 -44.5389)
		(stroke
			(width 0.2)
			(type default)
		)
		(layer "In10.Cu")
	)
	(gr_arc
		(start 42.453814 -43.77182)
		(mid 42.07002 -44.155233)
		(end 42.45356 -44.5389)
		(stroke
			(width 0.2)
			(type default)
		)
		(layer "In10.Cu")
	)
	(gr_line
		(start 42.487342 -13.2588)
		(end 42.487342 -12.9032)
		(stroke
			(width 0.2)
			(type default)
		)
		(layer "In10.Cu")
	)
	(gr_arc
		(start 42.487342 -12.9032)
		(mid 42.471719 -12.865483)
		(end 42.434002 -12.84986)
		(stroke
			(width 0.2)
			(type default)
		)
		(layer "In10.Cu")
	)
	(gr_line
		(start 42.487342 -12.4968)
		(end 42.487342 -12.1412)
		(stroke
			(width 0.2)
			(type default)
		)
		(layer "In10.Cu")
	)
	(gr_arc
		(start 42.487342 -12.1412)
		(mid 42.471719 -12.103483)
		(end 42.434002 -12.08786)
		(stroke
			(width 0.2)
			(type default)
		)
		(layer "In10.Cu")
	)
	(gr_line
		(start 43.25366 -12.98194)
		(end 44.210986 -12.98194)
		(stroke
			(width 0.2)
			(type default)
		)
		(layer "In10.Cu")
	)
	(gr_arc
		(start 43.25366 -12.21486)
		(mid 42.87012 -12.5984)
		(end 43.25366 -12.98194)
		(stroke
			(width 0.2)
			(type default)
		)
		(layer "In10.Cu")
	)
	(gr_line
		(start 43.408346 -10.634218)
		(end 44.327826 -10.634218)
		(stroke
			(width 0.2)
			(type default)
		)
		(layer "In10.Cu")
	)
	(gr_arc
		(start 43.4086 -9.867138)
		(mid 43.024806 -10.250551)
		(end 43.408346 -10.634218)
		(stroke
			(width 0.2)
			(type default)
		)
		(layer "In10.Cu")
	)
	(gr_arc
		(start 43.41114 -44.5389)
		(mid 43.79468 -44.15536)
		(end 43.41114 -43.77182)
		(stroke
			(width 0.2)
			(type default)
		)
		(layer "In10.Cu")
	)
	(gr_line
		(start 43.41114 -43.77182)
		(end 42.453814 -43.77182)
		(stroke
			(width 0.2)
			(type default)
		)
		(layer "In10.Cu")
	)
	(gr_arc
		(start 44.210986 -12.98194)
		(mid 44.59478 -12.598527)
		(end 44.21124 -12.21486)
		(stroke
			(width 0.2)
			(type default)
		)
		(layer "In10.Cu")
	)
	(gr_line
		(start 44.21124 -12.21486)
		(end 43.25366 -12.21486)
		(stroke
			(width 0.2)
			(type default)
		)
		(layer "In10.Cu")
	)
	(gr_arc
		(start 44.327826 -10.634218)
		(mid 44.711366 -10.250678)
		(end 44.327826 -9.867138)
		(stroke
			(width 0.2)
			(type default)
		)
		(layer "In10.Cu")
	)
	(gr_line
		(start 44.327826 -9.867138)
		(end 43.4086 -9.867138)
		(stroke
			(width 0.2)
			(type default)
		)
		(layer "In10.Cu")
	)
	(gr_line
		(start 44.98975 -44.30014)
		(end 45.947838 -44.32173)
		(stroke
			(width 0.2)
			(type default)
		)
		(layer "In10.Cu")
	)
	(gr_rect
		(start 44.991782 -4.097528)
		(end 45.708062 -8.293608)
		(stroke
			(width 0)
			(type default)
		)
		(fill no)
		(layer "In10.Cu")
	)
	(gr_arc
		(start 45.007276 -43.53306)
		(mid 44.615103 -43.907837)
		(end 44.98975 -44.30014)
		(stroke
			(width 0.2)
			(type default)
		)
		(layer "In10.Cu")
	)
	(gr_arc
		(start 45.20946 -13.2588)
		(mid 45.225083 -13.296517)
		(end 45.2628 -13.31214)
		(stroke
			(width 0.2)
			(type default)
		)
		(layer "In10.Cu")
	)
	(gr_line
		(start 45.20946 -12.9032)
		(end 45.20946 -13.2588)
		(stroke
			(width 0.2)
			(type default)
		)
		(layer "In10.Cu")
	)
	(gr_arc
		(start 45.20946 -12.4968)
		(mid 45.225083 -12.534517)
		(end 45.2628 -12.55014)
		(stroke
			(width 0.2)
			(type default)
		)
		(layer "In10.Cu")
	)
	(gr_line
		(start 45.20946 -12.1412)
		(end 45.20946 -12.4968)
		(stroke
			(width 0.2)
			(type default)
		)
		(layer "In10.Cu")
	)
	(gr_line
		(start 45.2628 -13.31214)
		(end 45.6692 -13.31214)
		(stroke
			(width 0.2)
			(type default)
		)
		(layer "In10.Cu")
	)
	(gr_arc
		(start 45.2628 -12.84986)
		(mid 45.225083 -12.865483)
		(end 45.20946 -12.9032)
		(stroke
			(width 0.2)
			(type default)
		)
		(layer "In10.Cu")
	)
	(gr_line
		(start 45.2628 -12.55014)
		(end 45.6692 -12.55014)
		(stroke
			(width 0.2)
			(type default)
		)
		(layer "In10.Cu")
	)
	(gr_arc
		(start 45.2628 -12.08786)
		(mid 45.225083 -12.103483)
		(end 45.20946 -12.1412)
		(stroke
			(width 0.2)
			(type default)
		)
		(layer "In10.Cu")
	)
	(gr_line
		(start 45.466 -14.1986)
		(end 46.176946 -14.1986)
		(stroke
			(width 0.2)
			(type default)
		)
		(layer "In10.Cu")
	)
	(gr_arc
		(start 45.466 -13.4366)
		(mid 45.085 -13.8176)
		(end 45.466 -14.1986)
		(stroke
			(width 0.2)
			(type default)
		)
		(layer "In10.Cu")
	)
	(gr_arc
		(start 45.6692 -13.31214)
		(mid 45.706917 -13.296517)
		(end 45.72254 -13.2588)
		(stroke
			(width 0.2)
			(type default)
		)
		(layer "In10.Cu")
	)
	(gr_line
		(start 45.6692 -12.84986)
		(end 45.2628 -12.84986)
		(stroke
			(width 0.2)
			(type default)
		)
		(layer "In10.Cu")
	)
	(gr_arc
		(start 45.6692 -12.55014)
		(mid 45.706917 -12.534517)
		(end 45.72254 -12.4968)
		(stroke
			(width 0.2)
			(type default)
		)
		(layer "In10.Cu")
	)
	(gr_line
		(start 45.6692 -12.08786)
		(end 45.2628 -12.08786)
		(stroke
			(width 0.2)
			(type default)
		)
		(layer "In10.Cu")
	)
	(gr_line
		(start 45.72254 -13.2588)
		(end 45.72254 -12.9032)
		(stroke
			(width 0.2)
			(type default)
		)
		(layer "In10.Cu")
	)
	(gr_arc
		(start 45.72254 -12.9032)
		(mid 45.706917 -12.865483)
		(end 45.6692 -12.84986)
		(stroke
			(width 0.2)
			(type default)
		)
		(layer "In10.Cu")
	)
	(gr_line
		(start 45.72254 -12.4968)
		(end 45.72254 -12.1412)
		(stroke
			(width 0.2)
			(type default)
		)
		(layer "In10.Cu")
	)
	(gr_arc
		(start 45.72254 -12.1412)
		(mid 45.706917 -12.103483)
		(end 45.6692 -12.08786)
		(stroke
			(width 0.2)
			(type default)
		)
		(layer "In10.Cu")
	)
	(gr_arc
		(start 45.947838 -44.32173)
		(mid 46.340014 -43.946826)
		(end 45.96511 -43.55465)
		(stroke
			(width 0.2)
			(type default)
		)
		(layer "In10.Cu")
	)
	(gr_line
		(start 45.96511 -43.55465)
		(end 45.007276 -43.53306)
		(stroke
			(width 0.2)
			(type default)
		)
		(layer "In10.Cu")
	)
	(gr_arc
		(start 45.97146 -13.2588)
		(mid 45.987083 -13.296517)
		(end 46.0248 -13.31214)
		(stroke
			(width 0.2)
			(type default)
		)
		(layer "In10.Cu")
	)
	(gr_line
		(start 45.97146 -12.9032)
		(end 45.97146 -13.2588)
		(stroke
			(width 0.2)
			(type default)
		)
		(layer "In10.Cu")
	)
	(gr_arc
		(start 45.97146 -12.4968)
		(mid 45.987083 -12.534517)
		(end 46.0248 -12.55014)
		(stroke
			(width 0.2)
			(type default)
		)
		(layer "In10.Cu")
	)
	(gr_line
		(start 45.97146 -12.1412)
		(end 45.97146 -12.4968)
		(stroke
			(width 0.2)
			(type default)
		)
		(layer "In10.Cu")
	)
	(gr_rect
		(start 45.99178 -4.097528)
		(end 46.70806 -8.293608)
		(stroke
			(width 0)
			(type default)
		)
		(fill no)
		(layer "In10.Cu")
	)
	(gr_line
		(start 46.0248 -13.31214)
		(end 46.4312 -13.31214)
		(stroke
			(width 0.2)
			(type default)
		)
		(layer "In10.Cu")
	)
	(gr_arc
		(start 46.0248 -12.84986)
		(mid 45.987083 -12.865483)
		(end 45.97146 -12.9032)
		(stroke
			(width 0.2)
			(type default)
		)
		(layer "In10.Cu")
	)
	(gr_line
		(start 46.0248 -12.55014)
		(end 46.4312 -12.55014)
		(stroke
			(width 0.2)
			(type default)
		)
		(layer "In10.Cu")
	)
	(gr_arc
		(start 46.0248 -12.08786)
		(mid 45.987083 -12.103483)
		(end 45.97146 -12.1412)
		(stroke
			(width 0.2)
			(type default)
		)
		(layer "In10.Cu")
	)
	(gr_line
		(start 46.101 -67.183)
		(end 55.753 -67.183)
		(stroke
			(width 0.381)
			(type default)
		)
		(layer "In10.Cu")
	)
	(gr_arc
		(start 46.176946 -14.1986)
		(mid 46.5582 -13.817727)
		(end 46.1772 -13.4366)
		(stroke
			(width 0.2)
			(type default)
		)
		(layer "In10.Cu")
	)
	(gr_line
		(start 46.1772 -13.4366)
		(end 45.466 -13.4366)
		(stroke
			(width 0.2)
			(type default)
		)
		(layer "In10.Cu")
	)
	(gr_arc
		(start 46.4312 -13.31214)
		(mid 46.468917 -13.296517)
		(end 46.48454 -13.2588)
		(stroke
			(width 0.2)
			(type default)
		)
		(layer "In10.Cu")
	)
	(gr_line
		(start 46.4312 -12.84986)
		(end 46.0248 -12.84986)
		(stroke
			(width 0.2)
			(type default)
		)
		(layer "In10.Cu")
	)
	(gr_arc
		(start 46.4312 -12.55014)
		(mid 46.468917 -12.534517)
		(end 46.48454 -12.4968)
		(stroke
			(width 0.2)
			(type default)
		)
		(layer "In10.Cu")
	)
	(gr_line
		(start 46.4312 -12.08786)
		(end 46.0248 -12.08786)
		(stroke
			(width 0.2)
			(type default)
		)
		(layer "In10.Cu")
	)
	(gr_line
		(start 46.48454 -13.2588)
		(end 46.48454 -12.9032)
		(stroke
			(width 0.2)
			(type default)
		)
		(layer "In10.Cu")
	)
	(gr_arc
		(start 46.48454 -12.9032)
		(mid 46.468917 -12.865483)
		(end 46.4312 -12.84986)
		(stroke
			(width 0.2)
			(type default)
		)
		(layer "In10.Cu")
	)
	(gr_line
		(start 46.48454 -12.4968)
		(end 46.48454 -12.1412)
		(stroke
			(width 0.2)
			(type default)
		)
		(layer "In10.Cu")
	)
	(gr_arc
		(start 46.48454 -12.1412)
		(mid 46.468917 -12.103483)
		(end 46.4312 -12.08786)
		(stroke
			(width 0.2)
			(type default)
		)
		(layer "In10.Cu")
	)
	(gr_line
		(start 47.408338 -10.634218)
		(end 48.327818 -10.634218)
		(stroke
			(width 0.2)
			(type default)
		)
		(layer "In10.Cu")
	)
	(gr_arc
		(start 47.408592 -9.867138)
		(mid 47.024798 -10.250551)
		(end 47.408338 -10.634218)
		(stroke
			(width 0.2)
			(type default)
		)
		(layer "In10.Cu")
	)
	(gr_line
		(start 47.46371 -14.1732)
		(end 48.183546 -14.1732)
		(stroke
			(width 0.2)
			(type default)
		)
		(layer "In10.Cu")
	)
	(gr_arc
		(start 47.46371 -13.4112)
		(mid 47.08271 -13.7922)
		(end 47.46371 -14.1732)
		(stroke
			(width 0.2)
			(type default)
		)
		(layer "In10.Cu")
	)
	(gr_arc
		(start 48.183546 -14.1732)
		(mid 48.5648 -13.792327)
		(end 48.1838 -13.4112)
		(stroke
			(width 0.2)
			(type default)
		)
		(layer "In10.Cu")
	)
	(gr_line
		(start 48.1838 -13.4112)
		(end 47.46371 -13.4112)
		(stroke
			(width 0.2)
			(type default)
		)
		(layer "In10.Cu")
	)
	(gr_arc
		(start 48.327818 -10.634218)
		(mid 48.711358 -10.250678)
		(end 48.327818 -9.867138)
		(stroke
			(width 0.2)
			(type default)
		)
		(layer "In10.Cu")
	)
	(gr_line
		(start 48.327818 -9.867138)
		(end 47.408592 -9.867138)
		(stroke
			(width 0.2)
			(type default)
		)
		(layer "In10.Cu")
	)
	(gr_rect
		(start 48.991774 -4.097528)
		(end 49.708054 -8.293608)
		(stroke
			(width 0)
			(type default)
		)
		(fill no)
		(layer "In10.Cu")
	)
	(gr_line
		(start 49.176432 -38.313614)
		(end 49.81321 -38.892226)
		(stroke
			(width 0.2)
			(type default)
		)
		(layer "In10.Cu")
	)
	(gr_line
		(start 49.29505 -20.79498)
		(end 50.25263 -20.79498)
		(stroke
			(width 0.2)
			(type default)
		)
		(layer "In10.Cu")
	)
	(gr_arc
		(start 49.295304 -20.0279)
		(mid 48.91151 -20.411313)
		(end 49.29505 -20.79498)
		(stroke
			(width 0.2)
			(type default)
		)
		(layer "In10.Cu")
	)
	(gr_line
		(start 49.38903 -10.64387)
		(end 50.310542 -10.64387)
		(stroke
			(width 0.2)
			(type default)
		)
		(layer "In10.Cu")
	)
	(gr_arc
		(start 49.389284 -9.87679)
		(mid 49.00549 -10.260203)
		(end 49.38903 -10.64387)
		(stroke
			(width 0.2)
			(type default)
		)
		(layer "In10.Cu")
	)
	(gr_line
		(start 49.4538 -14.1986)
		(end 50.2158 -14.1986)
		(stroke
			(width 0.2)
			(type default)
		)
		(layer "In10.Cu")
	)
	(gr_arc
		(start 49.454054 -13.4366)
		(mid 49.0728 -13.817473)
		(end 49.4538 -14.1986)
		(stroke
			(width 0.2)
			(type default)
		)
		(layer "In10.Cu")
	)
	(gr_arc
		(start 49.692052 -37.74567)
		(mid 49.15027 -37.771832)
		(end 49.176432 -38.313614)
		(stroke
			(width 0.2)
			(type default)
		)
		(layer "In10.Cu")
	)
	(gr_arc
		(start 49.81321 -38.892226)
		(mid 50.356403 -38.869633)
		(end 50.33137 -38.326568)
		(stroke
			(width 0.2)
			(type default)
		)
		(layer "In10.Cu")
	)
	(gr_rect
		(start 49.991772 -4.097528)
		(end 50.708052 -8.293608)
		(stroke
			(width 0)
			(type default)
		)
		(fill no)
		(layer "In10.Cu")
	)
	(gr_arc
		(start 50.2158 -14.1986)
		(mid 50.5968 -13.8176)
		(end 50.2158 -13.4366)
		(stroke
			(width 0.2)
			(type default)
		)
		(layer "In10.Cu")
	)
	(gr_line
		(start 50.2158 -13.4366)
		(end 49.454054 -13.4366)
		(stroke
			(width 0.2)
			(type default)
		)
		(layer "In10.Cu")
	)
	(gr_arc
		(start 50.25263 -20.79498)
		(mid 50.63617 -20.41144)
		(end 50.25263 -20.0279)
		(stroke
			(width 0.2)
			(type default)
		)
		(layer "In10.Cu")
	)
	(gr_line
		(start 50.25263 -20.0279)
		(end 49.295304 -20.0279)
		(stroke
			(width 0.2)
			(type default)
		)
		(layer "In10.Cu")
	)
	(gr_arc
		(start 50.262028 -48.49495)
		(mid 50.63998 -48.884078)
		(end 51.029108 -48.506126)
		(stroke
			(width 0.2)
			(type default)
		)
		(layer "In10.Cu")
	)
	(gr_line
		(start 50.274474 -47.63135)
		(end 50.262028 -48.49495)
		(stroke
			(width 0.2)
			(type default)
		)
		(layer "In10.Cu")
	)
	(gr_arc
		(start 50.310542 -10.64387)
		(mid 50.694082 -10.26033)
		(end 50.310542 -9.87679)
		(stroke
			(width 0.2)
			(type default)
		)
		(layer "In10.Cu")
	)
	(gr_line
		(start 50.310542 -9.87679)
		(end 49.389284 -9.87679)
		(stroke
			(width 0.2)
			(type default)
		)
		(layer "In10.Cu")
	)
	(gr_line
		(start 50.33137 -38.326568)
		(end 49.692052 -37.74567)
		(stroke
			(width 0.2)
			(type default)
		)
		(layer "In10.Cu")
	)
	(gr_line
		(start 51.029108 -48.506126)
		(end 51.041554 -47.64278)
		(stroke
			(width 0.2)
			(type default)
		)
		(layer "In10.Cu")
	)
	(gr_arc
		(start 51.041554 -47.64278)
		(mid 50.663729 -47.253654)
		(end 50.274474 -47.63135)
		(stroke
			(width 0.2)
			(type default)
		)
		(layer "In10.Cu")
	)
	(gr_line
		(start 51.282346 -34.47034)
		(end 52.16652 -34.47034)
		(stroke
			(width 0.2)
			(type default)
		)
		(layer "In10.Cu")
	)
	(gr_arc
		(start 51.2826 -33.70326)
		(mid 50.898806 -34.086673)
		(end 51.282346 -34.47034)
		(stroke
			(width 0.2)
			(type default)
		)
		(layer "In10.Cu")
	)
	(gr_line
		(start 52.1462 -14.32814)
		(end 53.009546 -14.32814)
		(stroke
			(width 0.2)
			(type default)
		)
		(layer "In10.Cu")
	)
	(gr_arc
		(start 52.1462 -13.56106)
		(mid 51.76266 -13.9446)
		(end 52.1462 -14.32814)
		(stroke
			(width 0.2)
			(type default)
		)
		(layer "In10.Cu")
	)
	(gr_arc
		(start 52.16652 -34.47034)
		(mid 52.55006 -34.0868)
		(end 52.16652 -33.70326)
		(stroke
			(width 0.2)
			(type default)
		)
		(layer "In10.Cu")
	)
	(gr_line
		(start 52.16652 -33.70326)
		(end 51.2826 -33.70326)
		(stroke
			(width 0.2)
			(type default)
		)
		(layer "In10.Cu")
	)
	(gr_arc
		(start 52.52339 -34.93262)
		(mid 52.14112 -35.31743)
		(end 52.52593 -35.6997)
		(stroke
			(width 0.2)
			(type default)
		)
		(layer "In10.Cu")
	)
	(gr_line
		(start 52.52593 -35.6997)
		(end 53.479954 -35.696652)
		(stroke
			(width 0.2)
			(type default)
		)
		(layer "In10.Cu")
	)
	(gr_arc
		(start 52.768246 -29.826966)
		(mid 53.151659 -30.21076)
		(end 53.535326 -29.82722)
		(stroke
			(width 0.2)
			(type default)
		)
		(layer "In10.Cu")
	)
	(gr_line
		(start 52.768246 -28.897834)
		(end 52.768246 -29.826966)
		(stroke
			(width 0.2)
			(type default)
		)
		(layer "In10.Cu")
	)
	(gr_arc
		(start 53.009546 -14.32814)
		(mid 53.39334 -13.944727)
		(end 53.0098 -13.56106)
		(stroke
			(width 0.2)
			(type default)
		)
		(layer "In10.Cu")
	)
	(gr_line
		(start 53.0098 -13.56106)
		(end 52.1462 -13.56106)
		(stroke
			(width 0.2)
			(type default)
		)
		(layer "In10.Cu")
	)
	(gr_line
		(start 53.477668 -34.929572)
		(end 52.52339 -34.93262)
		(stroke
			(width 0.2)
			(type default)
		)
		(layer "In10.Cu")
	)
	(gr_arc
		(start 53.479954 -35.696652)
		(mid 53.862478 -35.311969)
		(end 53.477668 -34.929572)
		(stroke
			(width 0.2)
			(type default)
		)
		(layer "In10.Cu")
	)
	(gr_line
		(start 53.535326 -29.82722)
		(end 53.535326 -28.897834)
		(stroke
			(width 0.2)
			(type default)
		)
		(layer "In10.Cu")
	)
	(gr_arc
		(start 53.535326 -28.897834)
		(mid 53.151786 -28.514294)
		(end 52.768246 -28.897834)
		(stroke
			(width 0.2)
			(type default)
		)
		(layer "In10.Cu")
	)
	(gr_line
		(start 53.848 -67.183)
		(end 54.102 -67.183)
		(stroke
			(width 0.381)
			(type default)
		)
		(layer "In10.Cu")
	)
	(gr_line
		(start 54.102 -67.183)
		(end 54.864 -66.421)
		(stroke
			(width 0.381)
			(type default)
		)
		(layer "In10.Cu")
	)
	(gr_line
		(start 54.483 -66.548)
		(end 53.848 -67.183)
		(stroke
			(width 0.381)
			(type default)
		)
		(layer "In10.Cu")
	)
	(gr_line
		(start 54.483 -65.913)
		(end 54.483 -66.548)
		(stroke
			(width 0.381)
			(type default)
		)
		(layer "In10.Cu")
	)
	(gr_line
		(start 54.483 -65.913)
		(end 54.483 -63.881)
		(stroke
			(width 0.381)
			(type default)
		)
		(layer "In10.Cu")
	)
	(gr_line
		(start 54.483 -65.913)
		(end 58.801 -70.231)
		(stroke
			(width 0.381)
			(type default)
		)
		(layer "In10.Cu")
	)
	(gr_line
		(start 54.483 -63.881)
		(end 54.864 -63.5)
		(stroke
			(width 0.381)
			(type default)
		)
		(layer "In10.Cu")
	)
	(gr_line
		(start 54.61 -67.056)
		(end 54.991 -67.056)
		(stroke
			(width 0.381)
			(type default)
		)
		(layer "In10.Cu")
	)
	(gr_line
		(start 54.864 -66.802)
		(end 54.61 -67.056)
		(stroke
			(width 0.381)
			(type default)
		)
		(layer "In10.Cu")
	)
	(gr_line
		(start 54.864 -66.421)
		(end 54.864 -66.802)
		(stroke
			(width 0.381)
			(type default)
		)
		(layer "In10.Cu")
	)
	(gr_line
		(start 54.864 -63.5)
		(end 65.659 -63.5)
		(stroke
			(width 0.381)
			(type default)
		)
		(layer "In10.Cu")
	)
	(gr_line
		(start 54.991 -67.056)
		(end 55.245 -66.802)
		(stroke
			(width 0.381)
			(type default)
		)
		(layer "In10.Cu")
	)
	(gr_line
		(start 55.753 -67.183)
		(end 54.483 -65.913)
		(stroke
			(width 0.381)
			(type default)
		)
		(layer "In10.Cu")
	)
	(gr_line
		(start 58.801 -70.231)
		(end 74.549 -70.231)
		(stroke
			(width 0.381)
			(type default)
		)
		(layer "In10.Cu")
	)
	(gr_line
		(start 59.078114 -11.320018)
		(end 59.997594 -11.320018)
		(stroke
			(width 0.2)
			(type default)
		)
		(layer "In10.Cu")
	)
	(gr_arc
		(start 59.078368 -10.552938)
		(mid 58.694574 -10.936351)
		(end 59.078114 -11.320018)
		(stroke
			(width 0.2)
			(type default)
		)
		(layer "In10.Cu")
	)
	(gr_arc
		(start 59.27471 -36.33724)
		(mid 59.65825 -36.72078)
		(end 60.04179 -36.33724)
		(stroke
			(width 0.2)
			(type default)
		)
		(layer "In10.Cu")
	)
	(gr_line
		(start 59.27471 -35.37966)
		(end 59.27471 -36.33724)
		(stroke
			(width 0.2)
			(type default)
		)
		(layer "In10.Cu")
	)
	(gr_arc
		(start 59.997594 -11.320018)
		(mid 60.381134 -10.936478)
		(end 59.997594 -10.552938)
		(stroke
			(width 0.2)
			(type default)
		)
		(layer "In10.Cu")
	)
	(gr_line
		(start 59.997594 -10.552938)
		(end 59.078368 -10.552938)
		(stroke
			(width 0.2)
			(type default)
		)
		(layer "In10.Cu")
	)
	(gr_line
		(start 60.04179 -36.33724)
		(end 60.04179 -35.379914)
		(stroke
			(width 0.2)
			(type default)
		)
		(layer "In10.Cu")
	)
	(gr_arc
		(start 60.04179 -35.379914)
		(mid 59.658377 -34.99612)
		(end 59.27471 -35.37966)
		(stroke
			(width 0.2)
			(type default)
		)
		(layer "In10.Cu")
	)
	(gr_line
		(start 60.551822 -45.897038)
		(end 60.607448 -46.75886)
		(stroke
			(width 0.2)
			(type default)
		)
		(layer "In10.Cu")
	)
	(gr_arc
		(start 60.607448 -46.75886)
		(mid 61.014864 -47.117)
		(end 61.373004 -46.709584)
		(stroke
			(width 0.2)
			(type default)
		)
		(layer "In10.Cu")
	)
	(gr_rect
		(start 60.99175 -4.097528)
		(end 61.70803 -8.293608)
		(stroke
			(width 0)
			(type default)
		)
		(fill no)
		(layer "In10.Cu")
	)
	(gr_arc
		(start 61.317378 -45.848016)
		(mid 60.910088 -45.489868)
		(end 60.551822 -45.897038)
		(stroke
			(width 0.2)
			(type default)
		)
		(layer "In10.Cu")
	)
	(gr_line
		(start 61.373004 -46.709584)
		(end 61.317378 -45.848016)
		(stroke
			(width 0.2)
			(type default)
		)
		(layer "In10.Cu")
	)
	(gr_line
		(start 61.40831 -10.634218)
		(end 62.327536 -10.634218)
		(stroke
			(width 0.2)
			(type default)
		)
		(layer "In10.Cu")
	)
	(gr_arc
		(start 61.40831 -9.867138)
		(mid 61.02477 -10.250678)
		(end 61.40831 -10.634218)
		(stroke
			(width 0.2)
			(type default)
		)
		(layer "In10.Cu")
	)
	(gr_rect
		(start 61.991748 -4.097528)
		(end 62.708028 -8.293608)
		(stroke
			(width 0)
			(type default)
		)
		(fill no)
		(layer "In10.Cu")
	)
	(gr_arc
		(start 62.327536 -10.634218)
		(mid 62.71133 -10.250805)
		(end 62.32779 -9.867138)
		(stroke
			(width 0.2)
			(type default)
		)
		(layer "In10.Cu")
	)
	(gr_line
		(start 62.32779 -9.867138)
		(end 61.40831 -9.867138)
		(stroke
			(width 0.2)
			(type default)
		)
		(layer "In10.Cu")
	)
	(gr_line
		(start 63.627 -15.0876)
		(end 64.389 -15.0876)
		(stroke
			(width 0.2)
			(type default)
		)
		(layer "In10.Cu")
	)
	(gr_arc
		(start 63.627254 -14.3256)
		(mid 63.246 -14.706473)
		(end 63.627 -15.0876)
		(stroke
			(width 0.2)
			(type default)
		)
		(layer "In10.Cu")
	)
	(gr_arc
		(start 64.389 -15.0876)
		(mid 64.77 -14.7066)
		(end 64.389 -14.3256)
		(stroke
			(width 0.2)
			(type default)
		)
		(layer "In10.Cu")
	)
	(gr_line
		(start 64.389 -14.3256)
		(end 63.627254 -14.3256)
		(stroke
			(width 0.2)
			(type default)
		)
		(layer "In10.Cu")
	)
	(gr_rect
		(start 64.991742 -4.097528)
		(end 65.708022 -8.293608)
		(stroke
			(width 0)
			(type default)
		)
		(fill no)
		(layer "In10.Cu")
	)
	(gr_arc
		(start 65.52946 -14.1478)
		(mid 65.545083 -14.185517)
		(end 65.5828 -14.20114)
		(stroke
			(width 0.2)
			(type default)
		)
		(layer "In10.Cu")
	)
	(gr_line
		(start 65.52946 -13.7922)
		(end 65.52946 -14.1478)
		(stroke
			(width 0.2)
			(type default)
		)
		(layer "In10.Cu")
	)
	(gr_arc
		(start 65.52946 -13.3858)
		(mid 65.545083 -13.423517)
		(end 65.5828 -13.43914)
		(stroke
			(width 0.2)
			(type default)
		)
		(layer "In10.Cu")
	)
	(gr_line
		(start 65.52946 -13.0302)
		(end 65.52946 -13.3858)
		(stroke
			(width 0.2)
			(type default)
		)
		(layer "In10.Cu")
	)
	(gr_line
		(start 65.5828 -14.20114)
		(end 65.9892 -14.20114)
		(stroke
			(width 0.2)
			(type default)
		)
		(layer "In10.Cu")
	)
	(gr_arc
		(start 65.5828 -13.73886)
		(mid 65.545083 -13.754483)
		(end 65.52946 -13.7922)
		(stroke
			(width 0.2)
			(type default)
		)
		(layer "In10.Cu")
	)
	(gr_line
		(start 65.5828 -13.43914)
		(end 65.9892 -13.43914)
		(stroke
			(width 0.2)
			(type default)
		)
		(layer "In10.Cu")
	)
	(gr_arc
		(start 65.5828 -12.97686)
		(mid 65.545083 -12.992483)
		(end 65.52946 -13.0302)
		(stroke
			(width 0.2)
			(type default)
		)
		(layer "In10.Cu")
	)
	(gr_line
		(start 65.659 -63.5)
		(end 67.31 -65.151)
		(stroke
			(width 0.381)
			(type default)
		)
		(layer "In10.Cu")
	)
	(gr_line
		(start 65.786 -15.0622)
		(end 66.547746 -15.0622)
		(stroke
			(width 0.2)
			(type default)
		)
		(layer "In10.Cu")
	)
	(gr_arc
		(start 65.786 -14.3002)
		(mid 65.405 -14.6812)
		(end 65.786 -15.0622)
		(stroke
			(width 0.2)
			(type default)
		)
		(layer "In10.Cu")
	)
	(gr_arc
		(start 65.9892 -14.20114)
		(mid 66.026917 -14.185517)
		(end 66.04254 -14.1478)
		(stroke
			(width 0.2)
			(type default)
		)
		(layer "In10.Cu")
	)
	(gr_line
		(start 65.9892 -13.73886)
		(end 65.5828 -13.73886)
		(stroke
			(width 0.2)
			(type default)
		)
		(layer "In10.Cu")
	)
	(gr_arc
		(start 65.9892 -13.43914)
		(mid 66.026917 -13.423517)
		(end 66.04254 -13.3858)
		(stroke
			(width 0.2)
			(type default)
		)
		(layer "In10.Cu")
	)
	(gr_line
		(start 65.9892 -12.97686)
		(end 65.5828 -12.97686)
		(stroke
			(width 0.2)
			(type default)
		)
		(layer "In10.Cu")
	)
	(gr_rect
		(start 65.99174 -4.097528)
		(end 66.70802 -8.293608)
		(stroke
			(width 0)
			(type default)
		)
		(fill no)
		(layer "In10.Cu")
	)
	(gr_line
		(start 66.04254 -14.1478)
		(end 66.04254 -13.7922)
		(stroke
			(width 0.2)
			(type default)
		)
		(layer "In10.Cu")
	)
	(gr_arc
		(start 66.04254 -13.7922)
		(mid 66.026917 -13.754483)
		(end 65.9892 -13.73886)
		(stroke
			(width 0.2)
			(type default)
		)
		(layer "In10.Cu")
	)
	(gr_line
		(start 66.04254 -13.3858)
		(end 66.04254 -13.0302)
		(stroke
			(width 0.2)
			(type default)
		)
		(layer "In10.Cu")
	)
	(gr_arc
		(start 66.04254 -13.0302)
		(mid 66.026917 -12.992483)
		(end 65.9892 -12.97686)
		(stroke
			(width 0.2)
			(type default)
		)
		(layer "In10.Cu")
	)
	(gr_arc
		(start 66.29146 -14.1478)
		(mid 66.307083 -14.185517)
		(end 66.3448 -14.20114)
		(stroke
			(width 0.2)
			(type default)
		)
		(layer "In10.Cu")
	)
	(gr_line
		(start 66.29146 -13.7922)
		(end 66.29146 -14.1478)
		(stroke
			(width 0.2)
			(type default)
		)
		(layer "In10.Cu")
	)
	(gr_arc
		(start 66.29146 -13.3858)
		(mid 66.307083 -13.423517)
		(end 66.3448 -13.43914)
		(stroke
			(width 0.2)
			(type default)
		)
		(layer "In10.Cu")
	)
	(gr_line
		(start 66.29146 -13.0302)
		(end 66.29146 -13.3858)
		(stroke
			(width 0.2)
			(type default)
		)
		(layer "In10.Cu")
	)
	(gr_line
		(start 66.3448 -14.20114)
		(end 66.7512 -14.20114)
		(stroke
			(width 0.2)
			(type default)
		)
		(layer "In10.Cu")
	)
	(gr_arc
		(start 66.3448 -13.73886)
		(mid 66.307083 -13.754483)
		(end 66.29146 -13.7922)
		(stroke
			(width 0.2)
			(type default)
		)
		(layer "In10.Cu")
	)
	(gr_line
		(start 66.3448 -13.43914)
		(end 66.7512 -13.43914)
		(stroke
			(width 0.2)
			(type default)
		)
		(layer "In10.Cu")
	)
	(gr_arc
		(start 66.3448 -12.97686)
		(mid 66.307083 -12.992483)
		(end 66.29146 -13.0302)
		(stroke
			(width 0.2)
			(type default)
		)
		(layer "In10.Cu")
	)
	(gr_arc
		(start 66.547746 -15.0622)
		(mid 66.929 -14.681327)
		(end 66.548 -14.3002)
		(stroke
			(width 0.2)
			(type default)
		)
		(layer "In10.Cu")
	)
	(gr_line
		(start 66.548 -14.3002)
		(end 65.786 -14.3002)
		(stroke
			(width 0.2)
			(type default)
		)
		(layer "In10.Cu")
	)
	(gr_arc
		(start 66.57086 -30.734)
		(mid 66.586483 -30.771717)
		(end 66.6242 -30.78734)
		(stroke
			(width 0.2)
			(type default)
		)
		(layer "In10.Cu")
	)
	(gr_line
		(start 66.57086 -30.3276)
		(end 66.57086 -30.734)
		(stroke
			(width 0.2)
			(type default)
		)
		(layer "In10.Cu")
	)
	(gr_arc
		(start 66.57086 -29.972)
		(mid 66.586483 -30.009717)
		(end 66.6242 -30.02534)
		(stroke
			(width 0.2)
			(type default)
		)
		(layer "In10.Cu")
	)
	(gr_line
		(start 66.57086 -29.5656)
		(end 66.57086 -29.972)
		(stroke
			(width 0.2)
			(type default)
		)
		(layer "In10.Cu")
	)
	(gr_arc
		(start 66.57086 -28.5242)
		(mid 66.586483 -28.561917)
		(end 66.6242 -28.57754)
		(stroke
			(width 0.2)
			(type default)
		)
		(layer "In10.Cu")
	)
	(gr_line
		(start 66.57086 -28.1178)
		(end 66.57086 -28.5242)
		(stroke
			(width 0.2)
			(type default)
		)
		(layer "In10.Cu")
	)
	(gr_arc
		(start 66.57086 -27.7622)
		(mid 66.586483 -27.799917)
		(end 66.6242 -27.81554)
		(stroke
			(width 0.2)
			(type default)
		)
		(layer "In10.Cu")
	)
	(gr_line
		(start 66.57086 -27.3558)
		(end 66.57086 -27.7622)
		(stroke
			(width 0.2)
			(type default)
		)
		(layer "In10.Cu")
	)
	(gr_line
		(start 66.6242 -30.78734)
		(end 66.9798 -30.78734)
		(stroke
			(width 0.2)
			(type default)
		)
		(layer "In10.Cu")
	)
	(gr_arc
		(start 66.6242 -30.27426)
		(mid 66.586483 -30.289883)
		(end 66.57086 -30.3276)
		(stroke
			(width 0.2)
			(type default)
		)
		(layer "In10.Cu")
	)
	(gr_line
		(start 66.6242 -30.02534)
		(end 66.9798 -30.02534)
		(stroke
			(width 0.2)
			(type default)
		)
		(layer "In10.Cu")
	)
	(gr_arc
		(start 66.6242 -29.51226)
		(mid 66.586483 -29.527883)
		(end 66.57086 -29.5656)
		(stroke
			(width 0.2)
			(type default)
		)
		(layer "In10.Cu")
	)
	(gr_line
		(start 66.6242 -28.57754)
		(end 66.9798 -28.57754)
		(stroke
			(width 0.2)
			(type default)
		)
		(layer "In10.Cu")
	)
	(gr_arc
		(start 66.6242 -28.06446)
		(mid 66.586483 -28.080083)
		(end 66.57086 -28.1178)
		(stroke
			(width 0.2)
			(type default)
		)
		(layer "In10.Cu")
	)
	(gr_line
		(start 66.6242 -27.81554)
		(end 66.9798 -27.81554)
		(stroke
			(width 0.2)
			(type default)
		)
		(layer "In10.Cu")
	)
	(gr_arc
		(start 66.6242 -27.30246)
		(mid 66.586483 -27.318083)
		(end 66.57086 -27.3558)
		(stroke
			(width 0.2)
			(type default)
		)
		(layer "In10.Cu")
	)
	(gr_arc
		(start 66.7512 -14.20114)
		(mid 66.788917 -14.185517)
		(end 66.80454 -14.1478)
		(stroke
			(width 0.2)
			(type default)
		)
		(layer "In10.Cu")
	)
	(gr_line
		(start 66.7512 -13.73886)
		(end 66.3448 -13.73886)
		(stroke
			(width 0.2)
			(type default)
		)
		(layer "In10.Cu")
	)
	(gr_arc
		(start 66.7512 -13.43914)
		(mid 66.788917 -13.423517)
		(end 66.80454 -13.3858)
		(stroke
			(width 0.2)
			(type default)
		)
		(layer "In10.Cu")
	)
	(gr_line
		(start 66.7512 -12.97686)
		(end 66.3448 -12.97686)
		(stroke
			(width 0.2)
			(type default)
		)
		(layer "In10.Cu")
	)
	(gr_line
		(start 66.80454 -14.1478)
		(end 66.80454 -13.7922)
		(stroke
			(width 0.2)
			(type default)
		)
		(layer "In10.Cu")
	)
	(gr_arc
		(start 66.80454 -13.7922)
		(mid 66.788917 -13.754483)
		(end 66.7512 -13.73886)
		(stroke
			(width 0.2)
			(type default)
		)
		(layer "In10.Cu")
	)
	(gr_line
		(start 66.80454 -13.3858)
		(end 66.80454 -13.0302)
		(stroke
			(width 0.2)
			(type default)
		)
		(layer "In10.Cu")
	)
	(gr_arc
		(start 66.80454 -13.0302)
		(mid 66.788917 -12.992483)
		(end 66.7512 -12.97686)
		(stroke
			(width 0.2)
			(type default)
		)
		(layer "In10.Cu")
	)
	(gr_arc
		(start 66.9798 -30.78734)
		(mid 67.017517 -30.771717)
		(end 67.03314 -30.734)
		(stroke
			(width 0.2)
			(type default)
		)
		(layer "In10.Cu")
	)
	(gr_line
		(start 66.9798 -30.27426)
		(end 66.6242 -30.27426)
		(stroke
			(width 0.2)
			(type default)
		)
		(layer "In10.Cu")
	)
	(gr_arc
		(start 66.9798 -30.02534)
		(mid 67.017517 -30.009717)
		(end 67.03314 -29.972)
		(stroke
			(width 0.2)
			(type default)
		)
		(layer "In10.Cu")
	)
	(gr_line
		(start 66.9798 -29.51226)
		(end 66.6242 -29.51226)
		(stroke
			(width 0.2)
			(type default)
		)
		(layer "In10.Cu")
	)
	(gr_arc
		(start 66.9798 -28.57754)
		(mid 67.017517 -28.561917)
		(end 67.03314 -28.5242)
		(stroke
			(width 0.2)
			(type default)
		)
		(layer "In10.Cu")
	)
	(gr_line
		(start 66.9798 -28.06446)
		(end 66.6242 -28.06446)
		(stroke
			(width 0.2)
			(type default)
		)
		(layer "In10.Cu")
	)
	(gr_arc
		(start 66.9798 -27.81554)
		(mid 67.017517 -27.799917)
		(end 67.03314 -27.7622)
		(stroke
			(width 0.2)
			(type default)
		)
		(layer "In10.Cu")
	)
	(gr_line
		(start 66.9798 -27.30246)
		(end 66.6242 -27.30246)
		(stroke
			(width 0.2)
			(type default)
		)
		(layer "In10.Cu")
	)
	(gr_line
		(start 67.03314 -30.734)
		(end 67.03314 -30.3276)
		(stroke
			(width 0.2)
			(type default)
		)
		(layer "In10.Cu")
	)
	(gr_arc
		(start 67.03314 -30.3276)
		(mid 67.017517 -30.289883)
		(end 66.9798 -30.27426)
		(stroke
			(width 0.2)
			(type default)
		)
		(layer "In10.Cu")
	)
	(gr_line
		(start 67.03314 -29.972)
		(end 67.03314 -29.5656)
		(stroke
			(width 0.2)
			(type default)
		)
		(layer "In10.Cu")
	)
	(gr_arc
		(start 67.03314 -29.5656)
		(mid 67.017517 -29.527883)
		(end 66.9798 -29.51226)
		(stroke
			(width 0.2)
			(type default)
		)
		(layer "In10.Cu")
	)
	(gr_line
		(start 67.03314 -28.5242)
		(end 67.03314 -28.1178)
		(stroke
			(width 0.2)
			(type default)
		)
		(layer "In10.Cu")
	)
	(gr_arc
		(start 67.03314 -28.1178)
		(mid 67.017517 -28.080083)
		(end 66.9798 -28.06446)
		(stroke
			(width 0.2)
			(type default)
		)
		(layer "In10.Cu")
	)
	(gr_line
		(start 67.03314 -27.7622)
		(end 67.03314 -27.3558)
		(stroke
			(width 0.2)
			(type default)
		)
		(layer "In10.Cu")
	)
	(gr_arc
		(start 67.03314 -27.3558)
		(mid 67.017517 -27.318083)
		(end 66.9798 -27.30246)
		(stroke
			(width 0.2)
			(type default)
		)
		(layer "In10.Cu")
	)
	(gr_line
		(start 67.31 -65.151)
		(end 79.121 -65.151)
		(stroke
			(width 0.381)
			(type default)
		)
		(layer "In10.Cu")
	)
	(gr_arc
		(start 67.33286 -30.734)
		(mid 67.348483 -30.771717)
		(end 67.3862 -30.78734)
		(stroke
			(width 0.2)
			(type default)
		)
		(layer "In10.Cu")
	)
	(gr_line
		(start 67.33286 -30.3276)
		(end 67.33286 -30.734)
		(stroke
			(width 0.2)
			(type default)
		)
		(layer "In10.Cu")
	)
	(gr_arc
		(start 67.33286 -29.972)
		(mid 67.348483 -30.009717)
		(end 67.3862 -30.02534)
		(stroke
			(width 0.2)
			(type default)
		)
		(layer "In10.Cu")
	)
	(gr_line
		(start 67.33286 -29.5656)
		(end 67.33286 -29.972)
		(stroke
			(width 0.2)
			(type default)
		)
		(layer "In10.Cu")
	)
	(gr_arc
		(start 67.33286 -28.5242)
		(mid 67.348483 -28.561917)
		(end 67.3862 -28.57754)
		(stroke
			(width 0.2)
			(type default)
		)
		(layer "In10.Cu")
	)
	(gr_line
		(start 67.33286 -28.1178)
		(end 67.33286 -28.5242)
		(stroke
			(width 0.2)
			(type default)
		)
		(layer "In10.Cu")
	)
	(gr_arc
		(start 67.33286 -27.7622)
		(mid 67.348483 -27.799917)
		(end 67.3862 -27.81554)
		(stroke
			(width 0.2)
			(type default)
		)
		(layer "In10.Cu")
	)
	(gr_line
		(start 67.33286 -27.3558)
		(end 67.33286 -27.7622)
		(stroke
			(width 0.2)
			(type default)
		)
		(layer "In10.Cu")
	)
	(gr_line
		(start 67.34556 -10.668)
		(end 68.302886 -10.668)
		(stroke
			(width 0.2)
			(type default)
		)
		(layer "In10.Cu")
	)
	(gr_arc
		(start 67.34556 -9.90092)
		(mid 66.96202 -10.28446)
		(end 67.34556 -10.668)
		(stroke
			(width 0.2)
			(type default)
		)
		(layer "In10.Cu")
	)
	(gr_line
		(start 67.3862 -30.78734)
		(end 67.7418 -30.78734)
		(stroke
			(width 0.2)
			(type default)
		)
		(layer "In10.Cu")
	)
	(gr_arc
		(start 67.3862 -30.27426)
		(mid 67.348483 -30.289883)
		(end 67.33286 -30.3276)
		(stroke
			(width 0.2)
			(type default)
		)
		(layer "In10.Cu")
	)
	(gr_line
		(start 67.3862 -30.02534)
		(end 67.7418 -30.02534)
		(stroke
			(width 0.2)
			(type default)
		)
		(layer "In10.Cu")
	)
	(gr_arc
		(start 67.3862 -29.51226)
		(mid 67.348483 -29.527883)
		(end 67.33286 -29.5656)
		(stroke
			(width 0.2)
			(type default)
		)
		(layer "In10.Cu")
	)
	(gr_line
		(start 67.3862 -28.57754)
		(end 67.7418 -28.57754)
		(stroke
			(width 0.2)
			(type default)
		)
		(layer "In10.Cu")
	)
	(gr_arc
		(start 67.3862 -28.06446)
		(mid 67.348483 -28.080083)
		(end 67.33286 -28.1178)
		(stroke
			(width 0.2)
			(type default)
		)
		(layer "In10.Cu")
	)
	(gr_line
		(start 67.3862 -27.81554)
		(end 67.7418 -27.81554)
		(stroke
			(width 0.2)
			(type default)
		)
		(layer "In10.Cu")
	)
	(gr_arc
		(start 67.3862 -27.30246)
		(mid 67.348483 -27.318083)
		(end 67.33286 -27.3558)
		(stroke
			(width 0.2)
			(type default)
		)
		(layer "In10.Cu")
	)
	(gr_arc
		(start 67.7418 -30.78734)
		(mid 67.779517 -30.771717)
		(end 67.79514 -30.734)
		(stroke
			(width 0.2)
			(type default)
		)
		(layer "In10.Cu")
	)
	(gr_line
		(start 67.7418 -30.27426)
		(end 67.3862 -30.27426)
		(stroke
			(width 0.2)
			(type default)
		)
		(layer "In10.Cu")
	)
	(gr_arc
		(start 67.7418 -30.02534)
		(mid 67.779517 -30.009717)
		(end 67.79514 -29.972)
		(stroke
			(width 0.2)
			(type default)
		)
		(layer "In10.Cu")
	)
	(gr_line
		(start 67.7418 -29.51226)
		(end 67.3862 -29.51226)
		(stroke
			(width 0.2)
			(type default)
		)
		(layer "In10.Cu")
	)
	(gr_arc
		(start 67.7418 -28.57754)
		(mid 67.779517 -28.561917)
		(end 67.79514 -28.5242)
		(stroke
			(width 0.2)
			(type default)
		)
		(layer "In10.Cu")
	)
	(gr_line
		(start 67.7418 -28.06446)
		(end 67.3862 -28.06446)
		(stroke
			(width 0.2)
			(type default)
		)
		(layer "In10.Cu")
	)
	(gr_arc
		(start 67.7418 -27.81554)
		(mid 67.779517 -27.799917)
		(end 67.79514 -27.7622)
		(stroke
			(width 0.2)
			(type default)
		)
		(layer "In10.Cu")
	)
	(gr_line
		(start 67.7418 -27.30246)
		(end 67.3862 -27.30246)
		(stroke
			(width 0.2)
			(type default)
		)
		(layer "In10.Cu")
	)
	(gr_line
		(start 67.79514 -30.734)
		(end 67.79514 -30.3276)
		(stroke
			(width 0.2)
			(type default)
		)
		(layer "In10.Cu")
	)
	(gr_arc
		(start 67.79514 -30.3276)
		(mid 67.779517 -30.289883)
		(end 67.7418 -30.27426)
		(stroke
			(width 0.2)
			(type default)
		)
		(layer "In10.Cu")
	)
	(gr_line
		(start 67.79514 -29.972)
		(end 67.79514 -29.5656)
		(stroke
			(width 0.2)
			(type default)
		)
		(layer "In10.Cu")
	)
	(gr_arc
		(start 67.79514 -29.5656)
		(mid 67.779517 -29.527883)
		(end 67.7418 -29.51226)
		(stroke
			(width 0.2)
			(type default)
		)
		(layer "In10.Cu")
	)
	(gr_line
		(start 67.79514 -28.5242)
		(end 67.79514 -28.1178)
		(stroke
			(width 0.2)
			(type default)
		)
		(layer "In10.Cu")
	)
	(gr_arc
		(start 67.79514 -28.1178)
		(mid 67.779517 -28.080083)
		(end 67.7418 -28.06446)
		(stroke
			(width 0.2)
			(type default)
		)
		(layer "In10.Cu")
	)
	(gr_line
		(start 67.79514 -27.7622)
		(end 67.79514 -27.3558)
		(stroke
			(width 0.2)
			(type default)
		)
		(layer "In10.Cu")
	)
	(gr_arc
		(start 67.79514 -27.3558)
		(mid 67.779517 -27.318083)
		(end 67.7418 -27.30246)
		(stroke
			(width 0.2)
			(type default)
		)
		(layer "In10.Cu")
	)
	(gr_arc
		(start 67.81546 -14.1478)
		(mid 67.831083 -14.185517)
		(end 67.8688 -14.20114)
		(stroke
			(width 0.2)
			(type default)
		)
		(layer "In10.Cu")
	)
	(gr_line
		(start 67.81546 -13.7922)
		(end 67.81546 -14.1478)
		(stroke
			(width 0.2)
			(type default)
		)
		(layer "In10.Cu")
	)
	(gr_arc
		(start 67.81546 -13.3858)
		(mid 67.831083 -13.423517)
		(end 67.8688 -13.43914)
		(stroke
			(width 0.2)
			(type default)
		)
		(layer "In10.Cu")
	)
	(gr_line
		(start 67.81546 -13.0302)
		(end 67.81546 -13.3858)
		(stroke
			(width 0.2)
			(type default)
		)
		(layer "In10.Cu")
	)
	(gr_line
		(start 67.8688 -14.20114)
		(end 68.2752 -14.20114)
		(stroke
			(width 0.2)
			(type default)
		)
		(layer "In10.Cu")
	)
	(gr_arc
		(start 67.8688 -13.73886)
		(mid 67.831083 -13.754483)
		(end 67.81546 -13.7922)
		(stroke
			(width 0.2)
			(type default)
		)
		(layer "In10.Cu")
	)
	(gr_line
		(start 67.8688 -13.43914)
		(end 68.2752 -13.43914)
		(stroke
			(width 0.2)
			(type default)
		)
		(layer "In10.Cu")
	)
	(gr_arc
		(start 67.8688 -12.97686)
		(mid 67.831083 -12.992483)
		(end 67.81546 -13.0302)
		(stroke
			(width 0.2)
			(type default)
		)
		(layer "In10.Cu")
	)
	(gr_line
		(start 68.072 -14.98854)
		(end 68.834 -14.98854)
		(stroke
			(width 0.2)
			(type default)
		)
		(layer "In10.Cu")
	)
	(gr_arc
		(start 68.072254 -14.22146)
		(mid 67.68846 -14.604873)
		(end 68.072 -14.98854)
		(stroke
			(width 0.2)
			(type default)
		)
		(layer "In10.Cu")
	)
	(gr_arc
		(start 68.2752 -14.20114)
		(mid 68.312917 -14.185517)
		(end 68.32854 -14.1478)
		(stroke
			(width 0.2)
			(type default)
		)
		(layer "In10.Cu")
	)
	(gr_line
		(start 68.2752 -13.73886)
		(end 67.8688 -13.73886)
		(stroke
			(width 0.2)
			(type default)
		)
		(layer "In10.Cu")
	)
	(gr_arc
		(start 68.2752 -13.43914)
		(mid 68.312917 -13.423517)
		(end 68.32854 -13.3858)
		(stroke
			(width 0.2)
			(type default)
		)
		(layer "In10.Cu")
	)
	(gr_line
		(start 68.2752 -12.97686)
		(end 67.8688 -12.97686)
		(stroke
			(width 0.2)
			(type default)
		)
		(layer "In10.Cu")
	)
	(gr_arc
		(start 68.302886 -10.668)
		(mid 68.68668 -10.284587)
		(end 68.30314 -9.90092)
		(stroke
			(width 0.2)
			(type default)
		)
		(layer "In10.Cu")
	)
	(gr_line
		(start 68.30314 -9.90092)
		(end 67.34556 -9.90092)
		(stroke
			(width 0.2)
			(type default)
		)
		(layer "In10.Cu")
	)
	(gr_line
		(start 68.32854 -14.1478)
		(end 68.32854 -13.7922)
		(stroke
			(width 0.2)
			(type default)
		)
		(layer "In10.Cu")
	)
	(gr_arc
		(start 68.32854 -13.7922)
		(mid 68.312917 -13.754483)
		(end 68.2752 -13.73886)
		(stroke
			(width 0.2)
			(type default)
		)
		(layer "In10.Cu")
	)
	(gr_line
		(start 68.32854 -13.3858)
		(end 68.32854 -13.0302)
		(stroke
			(width 0.2)
			(type default)
		)
		(layer "In10.Cu")
	)
	(gr_arc
		(start 68.32854 -13.0302)
		(mid 68.312917 -12.992483)
		(end 68.2752 -12.97686)
		(stroke
			(width 0.2)
			(type default)
		)
		(layer "In10.Cu")
	)
	(gr_arc
		(start 68.57746 -14.1478)
		(mid 68.593083 -14.185517)
		(end 68.6308 -14.20114)
		(stroke
			(width 0.2)
			(type default)
		)
		(layer "In10.Cu")
	)
	(gr_line
		(start 68.57746 -13.7922)
		(end 68.57746 -14.1478)
		(stroke
			(width 0.2)
			(type default)
		)
		(layer "In10.Cu")
	)
	(gr_arc
		(start 68.57746 -13.3858)
		(mid 68.593083 -13.423517)
		(end 68.6308 -13.43914)
		(stroke
			(width 0.2)
			(type default)
		)
		(layer "In10.Cu")
	)
	(gr_line
		(start 68.57746 -13.0302)
		(end 68.57746 -13.3858)
		(stroke
			(width 0.2)
			(type default)
		)
		(layer "In10.Cu")
	)
	(gr_line
		(start 68.6308 -14.20114)
		(end 69.0372 -14.20114)
		(stroke
			(width 0.2)
			(type default)
		)
		(layer "In10.Cu")
	)
	(gr_arc
		(start 68.6308 -13.73886)
		(mid 68.593083 -13.754483)
		(end 68.57746 -13.7922)
		(stroke
			(width 0.2)
			(type default)
		)
		(layer "In10.Cu")
	)
	(gr_line
		(start 68.6308 -13.43914)
		(end 69.0372 -13.43914)
		(stroke
			(width 0.2)
			(type default)
		)
		(layer "In10.Cu")
	)
	(gr_arc
		(start 68.6308 -12.97686)
		(mid 68.593083 -12.992483)
		(end 68.57746 -13.0302)
		(stroke
			(width 0.2)
			(type default)
		)
		(layer "In10.Cu")
	)
	(gr_arc
		(start 68.75145 -28.403296)
		(mid 69.133212 -28.788614)
		(end 69.51853 -28.406852)
		(stroke
			(width 0.2)
			(type default)
		)
		(layer "In10.Cu")
	)
	(gr_line
		(start 68.75526 -27.51963)
		(end 68.75145 -28.403296)
		(stroke
			(width 0.2)
			(type default)
		)
		(layer "In10.Cu")
	)
	(gr_arc
		(start 68.834 -14.98854)
		(mid 69.21754 -14.605)
		(end 68.834 -14.22146)
		(stroke
			(width 0.2)
			(type default)
		)
		(layer "In10.Cu")
	)
	(gr_line
		(start 68.834 -14.22146)
		(end 68.072254 -14.22146)
		(stroke
			(width 0.2)
			(type default)
		)
		(layer "In10.Cu")
	)
	(gr_rect
		(start 68.991734 -4.097528)
		(end 69.708014 -8.293608)
		(stroke
			(width 0)
			(type default)
		)
		(fill no)
		(layer "In10.Cu")
	)
	(gr_arc
		(start 69.0372 -14.20114)
		(mid 69.074917 -14.185517)
		(end 69.09054 -14.1478)
		(stroke
			(width 0.2)
			(type default)
		)
		(layer "In10.Cu")
	)
	(gr_line
		(start 69.0372 -13.73886)
		(end 68.6308 -13.73886)
		(stroke
			(width 0.2)
			(type default)
		)
		(layer "In10.Cu")
	)
	(gr_arc
		(start 69.0372 -13.43914)
		(mid 69.074917 -13.423517)
		(end 69.09054 -13.3858)
		(stroke
			(width 0.2)
			(type default)
		)
		(layer "In10.Cu")
	)
	(gr_line
		(start 69.0372 -12.97686)
		(end 68.6308 -12.97686)
		(stroke
			(width 0.2)
			(type default)
		)
		(layer "In10.Cu")
	)
	(gr_line
		(start 69.09054 -14.1478)
		(end 69.09054 -13.7922)
		(stroke
			(width 0.2)
			(type default)
		)
		(layer "In10.Cu")
	)
	(gr_arc
		(start 69.09054 -13.7922)
		(mid 69.074917 -13.754483)
		(end 69.0372 -13.73886)
		(stroke
			(width 0.2)
			(type default)
		)
		(layer "In10.Cu")
	)
	(gr_line
		(start 69.09054 -13.3858)
		(end 69.09054 -13.0302)
		(stroke
			(width 0.2)
			(type default)
		)
		(layer "In10.Cu")
	)
	(gr_arc
		(start 69.09054 -13.0302)
		(mid 69.074917 -12.992483)
		(end 69.0372 -12.97686)
		(stroke
			(width 0.2)
			(type default)
		)
		(layer "In10.Cu")
	)
	(gr_line
		(start 69.51853 -28.406852)
		(end 69.52234 -27.52344)
		(stroke
			(width 0.2)
			(type default)
		)
		(layer "In10.Cu")
	)
	(gr_arc
		(start 69.52234 -27.52344)
		(mid 69.140705 -27.138123)
		(end 68.75526 -27.51963)
		(stroke
			(width 0.2)
			(type default)
		)
		(layer "In10.Cu")
	)
	(gr_rect
		(start 69.991732 -4.097528)
		(end 70.708012 -8.293608)
		(stroke
			(width 0)
			(type default)
		)
		(fill no)
		(layer "In10.Cu")
	)
	(gr_line
		(start 71.370952 -10.668)
		(end 72.328532 -10.668)
		(stroke
			(width 0.2)
			(type default)
		)
		(layer "In10.Cu")
	)
	(gr_arc
		(start 71.371206 -9.90092)
		(mid 70.987412 -10.284333)
		(end 71.370952 -10.668)
		(stroke
			(width 0.2)
			(type default)
		)
		(layer "In10.Cu")
	)
	(gr_arc
		(start 72.328532 -10.668)
		(mid 72.712072 -10.28446)
		(end 72.328532 -9.90092)
		(stroke
			(width 0.2)
			(type default)
		)
		(layer "In10.Cu")
	)
	(gr_line
		(start 72.328532 -9.90092)
		(end 71.371206 -9.90092)
		(stroke
			(width 0.2)
			(type default)
		)
		(layer "In10.Cu")
	)
	(gr_arc
		(start 72.64146 -14.1478)
		(mid 72.657083 -14.185517)
		(end 72.6948 -14.20114)
		(stroke
			(width 0.2)
			(type default)
		)
		(layer "In10.Cu")
	)
	(gr_line
		(start 72.64146 -13.7922)
		(end 72.64146 -14.1478)
		(stroke
			(width 0.2)
			(type default)
		)
		(layer "In10.Cu")
	)
	(gr_arc
		(start 72.64146 -13.3858)
		(mid 72.657083 -13.423517)
		(end 72.6948 -13.43914)
		(stroke
			(width 0.2)
			(type default)
		)
		(layer "In10.Cu")
	)
	(gr_line
		(start 72.64146 -13.0302)
		(end 72.64146 -13.3858)
		(stroke
			(width 0.2)
			(type default)
		)
		(layer "In10.Cu")
	)
	(gr_line
		(start 72.6948 -14.20114)
		(end 73.1012 -14.20114)
		(stroke
			(width 0.2)
			(type default)
		)
		(layer "In10.Cu")
	)
	(gr_arc
		(start 72.6948 -13.73886)
		(mid 72.657083 -13.754483)
		(end 72.64146 -13.7922)
		(stroke
			(width 0.2)
			(type default)
		)
		(layer "In10.Cu")
	)
	(gr_line
		(start 72.6948 -13.43914)
		(end 73.1012 -13.43914)
		(stroke
			(width 0.2)
			(type default)
		)
		(layer "In10.Cu")
	)
	(gr_arc
		(start 72.6948 -12.97686)
		(mid 72.657083 -12.992483)
		(end 72.64146 -13.0302)
		(stroke
			(width 0.2)
			(type default)
		)
		(layer "In10.Cu")
	)
	(gr_line
		(start 72.8472 -15.09014)
		(end 73.7108 -15.09014)
		(stroke
			(width 0.2)
			(type default)
		)
		(layer "In10.Cu")
	)
	(gr_arc
		(start 72.847454 -14.32306)
		(mid 72.46366 -14.706473)
		(end 72.8472 -15.09014)
		(stroke
			(width 0.2)
			(type default)
		)
		(layer "In10.Cu")
	)
	(gr_rect
		(start 72.991726 -4.097528)
		(end 73.708006 -8.293608)
		(stroke
			(width 0)
			(type default)
		)
		(fill no)
		(layer "In10.Cu")
	)
	(gr_arc
		(start 73.1012 -14.20114)
		(mid 73.138917 -14.185517)
		(end 73.15454 -14.1478)
		(stroke
			(width 0.2)
			(type default)
		)
		(layer "In10.Cu")
	)
	(gr_line
		(start 73.1012 -13.73886)
		(end 72.6948 -13.73886)
		(stroke
			(width 0.2)
			(type default)
		)
		(layer "In10.Cu")
	)
	(gr_arc
		(start 73.1012 -13.43914)
		(mid 73.138917 -13.423517)
		(end 73.15454 -13.3858)
		(stroke
			(width 0.2)
			(type default)
		)
		(layer "In10.Cu")
	)
	(gr_line
		(start 73.1012 -12.97686)
		(end 72.6948 -12.97686)
		(stroke
			(width 0.2)
			(type default)
		)
		(layer "In10.Cu")
	)
	(gr_line
		(start 73.15454 -14.1478)
		(end 73.15454 -13.7922)
		(stroke
			(width 0.2)
			(type default)
		)
		(layer "In10.Cu")
	)
	(gr_arc
		(start 73.15454 -13.7922)
		(mid 73.138917 -13.754483)
		(end 73.1012 -13.73886)
		(stroke
			(width 0.2)
			(type default)
		)
		(layer "In10.Cu")
	)
	(gr_line
		(start 73.15454 -13.3858)
		(end 73.15454 -13.0302)
		(stroke
			(width 0.2)
			(type default)
		)
		(layer "In10.Cu")
	)
	(gr_arc
		(start 73.15454 -13.0302)
		(mid 73.138917 -12.992483)
		(end 73.1012 -12.97686)
		(stroke
			(width 0.2)
			(type default)
		)
		(layer "In10.Cu")
	)
	(gr_arc
		(start 73.40346 -14.1478)
		(mid 73.419083 -14.185517)
		(end 73.4568 -14.20114)
		(stroke
			(width 0.2)
			(type default)
		)
		(layer "In10.Cu")
	)
	(gr_line
		(start 73.40346 -13.7922)
		(end 73.40346 -14.1478)
		(stroke
			(width 0.2)
			(type default)
		)
		(layer "In10.Cu")
	)
	(gr_arc
		(start 73.40346 -13.3858)
		(mid 73.419083 -13.423517)
		(end 73.4568 -13.43914)
		(stroke
			(width 0.2)
			(type default)
		)
		(layer "In10.Cu")
	)
	(gr_line
		(start 73.40346 -13.0302)
		(end 73.40346 -13.3858)
		(stroke
			(width 0.2)
			(type default)
		)
		(layer "In10.Cu")
	)
	(gr_line
		(start 73.4568 -14.20114)
		(end 73.8632 -14.20114)
		(stroke
			(width 0.2)
			(type default)
		)
		(layer "In10.Cu")
	)
	(gr_arc
		(start 73.4568 -13.73886)
		(mid 73.419083 -13.754483)
		(end 73.40346 -13.7922)
		(stroke
			(width 0.2)
			(type default)
		)
		(layer "In10.Cu")
	)
	(gr_line
		(start 73.4568 -13.43914)
		(end 73.8632 -13.43914)
		(stroke
			(width 0.2)
			(type default)
		)
		(layer "In10.Cu")
	)
	(gr_arc
		(start 73.4568 -12.97686)
		(mid 73.419083 -12.992483)
		(end 73.40346 -13.0302)
		(stroke
			(width 0.2)
			(type default)
		)
		(layer "In10.Cu")
	)
	(gr_arc
		(start 73.7108 -15.09014)
		(mid 74.09434 -14.7066)
		(end 73.7108 -14.32306)
		(stroke
			(width 0.2)
			(type default)
		)
		(layer "In10.Cu")
	)
	(gr_line
		(start 73.7108 -14.32306)
		(end 72.847454 -14.32306)
		(stroke
			(width 0.2)
			(type default)
		)
		(layer "In10.Cu")
	)
	(gr_line
		(start 73.787 -70.993)
		(end 75.057 -69.723)
		(stroke
			(width 0.381)
			(type default)
		)
		(layer "In10.Cu")
	)
	(gr_line
		(start 73.787 -70.231)
		(end 73.787 -73.152)
		(stroke
			(width 0.381)
			(type default)
		)
		(layer "In10.Cu")
	)
	(gr_arc
		(start 73.8632 -14.20114)
		(mid 73.900917 -14.185517)
		(end 73.91654 -14.1478)
		(stroke
			(width 0.2)
			(type default)
		)
		(layer "In10.Cu")
	)
	(gr_line
		(start 73.8632 -13.73886)
		(end 73.4568 -13.73886)
		(stroke
			(width 0.2)
			(type default)
		)
		(layer "In10.Cu")
	)
	(gr_arc
		(start 73.8632 -13.43914)
		(mid 73.900917 -13.423517)
		(end 73.91654 -13.3858)
		(stroke
			(width 0.2)
			(type default)
		)
		(layer "In10.Cu")
	)
	(gr_line
		(start 73.8632 -12.97686)
		(end 73.4568 -12.97686)
		(stroke
			(width 0.2)
			(type default)
		)
		(layer "In10.Cu")
	)
	(gr_line
		(start 73.91654 -14.1478)
		(end 73.91654 -13.7922)
		(stroke
			(width 0.2)
			(type default)
		)
		(layer "In10.Cu")
	)
	(gr_arc
		(start 73.91654 -13.7922)
		(mid 73.900917 -13.754483)
		(end 73.8632 -13.73886)
		(stroke
			(width 0.2)
			(type default)
		)
		(layer "In10.Cu")
	)
	(gr_line
		(start 73.91654 -13.3858)
		(end 73.91654 -13.0302)
		(stroke
			(width 0.2)
			(type default)
		)
		(layer "In10.Cu")
	)
	(gr_arc
		(start 73.91654 -13.0302)
		(mid 73.900917 -12.992483)
		(end 73.8632 -12.97686)
		(stroke
			(width 0.2)
			(type default)
		)
		(layer "In10.Cu")
	)
	(gr_rect
		(start 73.991724 -4.097528)
		(end 74.708004 -8.293608)
		(stroke
			(width 0)
			(type default)
		)
		(fill no)
		(layer "In10.Cu")
	)
	(gr_line
		(start 74.549 -70.231)
		(end 73.787 -70.993)
		(stroke
			(width 0.381)
			(type default)
		)
		(layer "In10.Cu")
	)
	(gr_line
		(start 75.057 -69.723)
		(end 85.598 -69.723)
		(stroke
			(width 0.381)
			(type default)
		)
		(layer "In10.Cu")
	)
	(gr_line
		(start 75.370944 -10.668)
		(end 76.328524 -10.668)
		(stroke
			(width 0.2)
			(type default)
		)
		(layer "In10.Cu")
	)
	(gr_arc
		(start 75.371198 -9.90092)
		(mid 74.987404 -10.284333)
		(end 75.370944 -10.668)
		(stroke
			(width 0.2)
			(type default)
		)
		(layer "In10.Cu")
	)
	(gr_arc
		(start 76.328524 -10.668)
		(mid 76.712064 -10.28446)
		(end 76.328524 -9.90092)
		(stroke
			(width 0.2)
			(type default)
		)
		(layer "In10.Cu")
	)
	(gr_line
		(start 76.328524 -9.90092)
		(end 75.371198 -9.90092)
		(stroke
			(width 0.2)
			(type default)
		)
		(layer "In10.Cu")
	)
	(gr_rect
		(start 76.991718 -4.097528)
		(end 77.707998 -8.293608)
		(stroke
			(width 0)
			(type default)
		)
		(fill no)
		(layer "In10.Cu")
	)
	(gr_arc
		(start 77.21346 -14.0208)
		(mid 77.229083 -14.058517)
		(end 77.2668 -14.07414)
		(stroke
			(width 0.2)
			(type default)
		)
		(layer "In10.Cu")
	)
	(gr_line
		(start 77.21346 -13.6652)
		(end 77.21346 -14.0208)
		(stroke
			(width 0.2)
			(type default)
		)
		(layer "In10.Cu")
	)
	(gr_arc
		(start 77.21346 -13.2588)
		(mid 77.229083 -13.296517)
		(end 77.2668 -13.31214)
		(stroke
			(width 0.2)
			(type default)
		)
		(layer "In10.Cu")
	)
	(gr_line
		(start 77.21346 -12.9032)
		(end 77.21346 -13.2588)
		(stroke
			(width 0.2)
			(type default)
		)
		(layer "In10.Cu")
	)
	(gr_line
		(start 77.2668 -14.07414)
		(end 77.6732 -14.07414)
		(stroke
			(width 0.2)
			(type default)
		)
		(layer "In10.Cu")
	)
	(gr_arc
		(start 77.2668 -13.61186)
		(mid 77.229083 -13.627483)
		(end 77.21346 -13.6652)
		(stroke
			(width 0.2)
			(type default)
		)
		(layer "In10.Cu")
	)
	(gr_line
		(start 77.2668 -13.31214)
		(end 77.6732 -13.31214)
		(stroke
			(width 0.2)
			(type default)
		)
		(layer "In10.Cu")
	)
	(gr_arc
		(start 77.2668 -12.84986)
		(mid 77.229083 -12.865483)
		(end 77.21346 -12.9032)
		(stroke
			(width 0.2)
			(type default)
		)
		(layer "In10.Cu")
	)
	(gr_line
		(start 77.4192 -14.96314)
		(end 78.2828 -14.96314)
		(stroke
			(width 0.2)
			(type default)
		)
		(layer "In10.Cu")
	)
	(gr_arc
		(start 77.419454 -14.19606)
		(mid 77.03566 -14.579473)
		(end 77.4192 -14.96314)
		(stroke
			(width 0.2)
			(type default)
		)
		(layer "In10.Cu")
	)
	(gr_arc
		(start 77.6732 -14.07414)
		(mid 77.710917 -14.058517)
		(end 77.72654 -14.0208)
		(stroke
			(width 0.2)
			(type default)
		)
		(layer "In10.Cu")
	)
	(gr_line
		(start 77.6732 -13.61186)
		(end 77.2668 -13.61186)
		(stroke
			(width 0.2)
			(type default)
		)
		(layer "In10.Cu")
	)
	(gr_arc
		(start 77.6732 -13.31214)
		(mid 77.710917 -13.296517)
		(end 77.72654 -13.2588)
		(stroke
			(width 0.2)
			(type default)
		)
		(layer "In10.Cu")
	)
	(gr_line
		(start 77.6732 -12.84986)
		(end 77.2668 -12.84986)
		(stroke
			(width 0.2)
			(type default)
		)
		(layer "In10.Cu")
	)
	(gr_line
		(start 77.72654 -14.0208)
		(end 77.72654 -13.6652)
		(stroke
			(width 0.2)
			(type default)
		)
		(layer "In10.Cu")
	)
	(gr_arc
		(start 77.72654 -13.6652)
		(mid 77.710917 -13.627483)
		(end 77.6732 -13.61186)
		(stroke
			(width 0.2)
			(type default)
		)
		(layer "In10.Cu")
	)
	(gr_line
		(start 77.72654 -13.2588)
		(end 77.72654 -12.9032)
		(stroke
			(width 0.2)
			(type default)
		)
		(layer "In10.Cu")
	)
	(gr_arc
		(start 77.72654 -12.9032)
		(mid 77.710917 -12.865483)
		(end 77.6732 -12.84986)
		(stroke
			(width 0.2)
			(type default)
		)
		(layer "In10.Cu")
	)
	(gr_arc
		(start 77.972666 -29.55925)
		(mid 77.633576 -29.90596)
		(end 77.980286 -30.24505)
		(stroke
			(width 0.2)
			(type default)
		)
		(layer "In10.Cu")
	)
	(gr_arc
		(start 77.97546 -14.0208)
		(mid 77.991083 -14.058517)
		(end 78.0288 -14.07414)
		(stroke
			(width 0.2)
			(type default)
		)
		(layer "In10.Cu")
	)
	(gr_line
		(start 77.97546 -13.6652)
		(end 77.97546 -14.0208)
		(stroke
			(width 0.2)
			(type default)
		)
		(layer "In10.Cu")
	)
	(gr_arc
		(start 77.97546 -13.2588)
		(mid 77.991083 -13.296517)
		(end 78.0288 -13.31214)
		(stroke
			(width 0.2)
			(type default)
		)
		(layer "In10.Cu")
	)
	(gr_line
		(start 77.97546 -12.9032)
		(end 77.97546 -13.2588)
		(stroke
			(width 0.2)
			(type default)
		)
		(layer "In10.Cu")
	)
	(gr_line
		(start 77.980286 -30.24505)
		(end 78.538832 -30.2387)
		(stroke
			(width 0.2)
			(type default)
		)
		(layer "In10.Cu")
	)
	(gr_rect
		(start 77.991716 -4.097528)
		(end 78.707996 -8.293608)
		(stroke
			(width 0)
			(type default)
		)
		(fill no)
		(layer "In10.Cu")
	)
	(gr_line
		(start 78.0288 -14.07414)
		(end 78.4352 -14.07414)
		(stroke
			(width 0.2)
			(type default)
		)
		(layer "In10.Cu")
	)
	(gr_arc
		(start 78.0288 -13.61186)
		(mid 77.991083 -13.627483)
		(end 77.97546 -13.6652)
		(stroke
			(width 0.2)
			(type default)
		)
		(layer "In10.Cu")
	)
	(gr_line
		(start 78.0288 -13.31214)
		(end 78.4352 -13.31214)
		(stroke
			(width 0.2)
			(type default)
		)
		(layer "In10.Cu")
	)
	(gr_arc
		(start 78.0288 -12.84986)
		(mid 77.991083 -12.865483)
		(end 77.97546 -12.9032)
		(stroke
			(width 0.2)
			(type default)
		)
		(layer "In10.Cu")
	)
	(gr_line
		(start 78.090014 -31.508446)
		(end 78.648814 -31.53283)
		(stroke
			(width 0.2)
			(type default)
		)
		(layer "In10.Cu")
	)
	(gr_arc
		(start 78.12024 -30.823154)
		(mid 77.762614 -31.150687)
		(end 78.090014 -31.508446)
		(stroke
			(width 0.2)
			(type default)
		)
		(layer "In10.Cu")
	)
	(gr_arc
		(start 78.2828 -14.96314)
		(mid 78.66634 -14.5796)
		(end 78.2828 -14.19606)
		(stroke
			(width 0.2)
			(type default)
		)
		(layer "In10.Cu")
	)
	(gr_line
		(start 78.2828 -14.19606)
		(end 77.419454 -14.19606)
		(stroke
			(width 0.2)
			(type default)
		)
		(layer "In10.Cu")
	)
	(gr_arc
		(start 78.4352 -14.07414)
		(mid 78.472917 -14.058517)
		(end 78.48854 -14.0208)
		(stroke
			(width 0.2)
			(type default)
		)
		(layer "In10.Cu")
	)
	(gr_line
		(start 78.4352 -13.61186)
		(end 78.0288 -13.61186)
		(stroke
			(width 0.2)
			(type default)
		)
		(layer "In10.Cu")
	)
	(gr_arc
		(start 78.4352 -13.31214)
		(mid 78.472917 -13.296517)
		(end 78.48854 -13.2588)
		(stroke
			(width 0.2)
			(type default)
		)
		(layer "In10.Cu")
	)
	(gr_line
		(start 78.4352 -12.84986)
		(end 78.0288 -12.84986)
		(stroke
			(width 0.2)
			(type default)
		)
		(layer "In10.Cu")
	)
	(gr_line
		(start 78.48854 -14.0208)
		(end 78.48854 -13.6652)
		(stroke
			(width 0.2)
			(type default)
		)
		(layer "In10.Cu")
	)
	(gr_arc
		(start 78.48854 -13.6652)
		(mid 78.472917 -13.627483)
		(end 78.4352 -13.61186)
		(stroke
			(width 0.2)
			(type default)
		)
		(layer "In10.Cu")
	)
	(gr_line
		(start 78.48854 -13.2588)
		(end 78.48854 -12.9032)
		(stroke
			(width 0.2)
			(type default)
		)
		(layer "In10.Cu")
	)
	(gr_arc
		(start 78.48854 -12.9032)
		(mid 78.472917 -12.865483)
		(end 78.4352 -12.84986)
		(stroke
			(width 0.2)
			(type default)
		)
		(layer "In10.Cu")
	)
	(gr_line
		(start 78.531466 -29.5529)
		(end 77.972666 -29.55925)
		(stroke
			(width 0.2)
			(type default)
		)
		(layer "In10.Cu")
	)
	(gr_arc
		(start 78.538832 -30.2387)
		(mid 78.878175 -29.892117)
		(end 78.531466 -29.5529)
		(stroke
			(width 0.2)
			(type default)
		)
		(layer "In10.Cu")
	)
	(gr_arc
		(start 78.648814 -31.53283)
		(mid 79.006446 -31.20517)
		(end 78.678786 -30.847538)
		(stroke
			(width 0.2)
			(type default)
		)
		(layer "In10.Cu")
	)
	(gr_line
		(start 78.678786 -30.847538)
		(end 78.12024 -30.823154)
		(stroke
			(width 0.2)
			(type default)
		)
		(layer "In10.Cu")
	)
	(gr_line
		(start 79.121 -65.151)
		(end 79.883 -65.913)
		(stroke
			(width 0.381)
			(type default)
		)
		(layer "In10.Cu")
	)
	(gr_line
		(start 79.370936 -10.7188)
		(end 80.328516 -10.7188)
		(stroke
			(width 0.2)
			(type default)
		)
		(layer "In10.Cu")
	)
	(gr_arc
		(start 79.37119 -9.95172)
		(mid 78.987396 -10.335133)
		(end 79.370936 -10.7188)
		(stroke
			(width 0.2)
			(type default)
		)
		(layer "In10.Cu")
	)
	(gr_line
		(start 79.883 -65.913)
		(end 82.169 -65.913)
		(stroke
			(width 0.381)
			(type default)
		)
		(layer "In10.Cu")
	)
	(gr_arc
		(start 80.00746 -14.0208)
		(mid 80.023083 -14.058517)
		(end 80.0608 -14.07414)
		(stroke
			(width 0.2)
			(type default)
		)
		(layer "In10.Cu")
	)
	(gr_line
		(start 80.00746 -13.6652)
		(end 80.00746 -14.0208)
		(stroke
			(width 0.2)
			(type default)
		)
		(layer "In10.Cu")
	)
	(gr_arc
		(start 80.00746 -13.2588)
		(mid 80.023083 -13.296517)
		(end 80.0608 -13.31214)
		(stroke
			(width 0.2)
			(type default)
		)
		(layer "In10.Cu")
	)
	(gr_line
		(start 80.00746 -12.9032)
		(end 80.00746 -13.2588)
		(stroke
			(width 0.2)
			(type default)
		)
		(layer "In10.Cu")
	)
	(gr_line
		(start 80.0608 -14.07414)
		(end 80.4672 -14.07414)
		(stroke
			(width 0.2)
			(type default)
		)
		(layer "In10.Cu")
	)
	(gr_arc
		(start 80.0608 -13.61186)
		(mid 80.023083 -13.627483)
		(end 80.00746 -13.6652)
		(stroke
			(width 0.2)
			(type default)
		)
		(layer "In10.Cu")
	)
	(gr_line
		(start 80.0608 -13.31214)
		(end 80.4672 -13.31214)
		(stroke
			(width 0.2)
			(type default)
		)
		(layer "In10.Cu")
	)
	(gr_arc
		(start 80.0608 -12.84986)
		(mid 80.023083 -12.865483)
		(end 80.00746 -12.9032)
		(stroke
			(width 0.2)
			(type default)
		)
		(layer "In10.Cu")
	)
	(gr_line
		(start 80.2132 -14.96314)
		(end 81.076546 -14.96314)
		(stroke
			(width 0.2)
			(type default)
		)
		(layer "In10.Cu")
	)
	(gr_arc
		(start 80.2132 -14.19606)
		(mid 79.82966 -14.5796)
		(end 80.2132 -14.96314)
		(stroke
			(width 0.2)
			(type default)
		)
		(layer "In10.Cu")
	)
	(gr_arc
		(start 80.2259 -54.685946)
		(mid 80.568673 -55.0291)
		(end 80.9117 -54.6862)
		(stroke
			(width 0.2)
			(type default)
		)
		(layer "In10.Cu")
	)
	(gr_line
		(start 80.2259 -54.1274)
		(end 80.2259 -54.685946)
		(stroke
			(width 0.2)
			(type default)
		)
		(layer "In10.Cu")
	)
	(gr_line
		(start 80.264 -60.7187)
		(end 81.0514 -60.7187)
		(stroke
			(width 0.2)
			(type default)
		)
		(layer "In10.Cu")
	)
	(gr_arc
		(start 80.264254 -60.0329)
		(mid 79.9211 -60.375673)
		(end 80.264 -60.7187)
		(stroke
			(width 0.2)
			(type default)
		)
		(layer "In10.Cu")
	)
	(gr_arc
		(start 80.328516 -10.7188)
		(mid 80.712056 -10.33526)
		(end 80.328516 -9.95172)
		(stroke
			(width 0.2)
			(type default)
		)
		(layer "In10.Cu")
	)
	(gr_line
		(start 80.328516 -9.95172)
		(end 79.37119 -9.95172)
		(stroke
			(width 0.2)
			(type default)
		)
		(layer "In10.Cu")
	)
	(gr_arc
		(start 80.4672 -14.07414)
		(mid 80.504917 -14.058517)
		(end 80.52054 -14.0208)
		(stroke
			(width 0.2)
			(type default)
		)
		(layer "In10.Cu")
	)
	(gr_line
		(start 80.4672 -13.61186)
		(end 80.0608 -13.61186)
		(stroke
			(width 0.2)
			(type default)
		)
		(layer "In10.Cu")
	)
	(gr_arc
		(start 80.4672 -13.31214)
		(mid 80.504917 -13.296517)
		(end 80.52054 -13.2588)
		(stroke
			(width 0.2)
			(type default)
		)
		(layer "In10.Cu")
	)
	(gr_line
		(start 80.4672 -12.84986)
		(end 80.0608 -12.84986)
		(stroke
			(width 0.2)
			(type default)
		)
		(layer "In10.Cu")
	)
	(gr_line
		(start 80.52054 -14.0208)
		(end 80.52054 -13.6652)
		(stroke
			(width 0.2)
			(type default)
		)
		(layer "In10.Cu")
	)
	(gr_arc
		(start 80.52054 -13.6652)
		(mid 80.504917 -13.627483)
		(end 80.4672 -13.61186)
		(stroke
			(width 0.2)
			(type default)
		)
		(layer "In10.Cu")
	)
	(gr_line
		(start 80.52054 -13.2588)
		(end 80.52054 -12.9032)
		(stroke
			(width 0.2)
			(type default)
		)
		(layer "In10.Cu")
	)
	(gr_arc
		(start 80.52054 -12.9032)
		(mid 80.504917 -12.865483)
		(end 80.4672 -12.84986)
		(stroke
			(width 0.2)
			(type default)
		)
		(layer "In10.Cu")
	)
	(gr_arc
		(start 80.76946 -14.0208)
		(mid 80.785083 -14.058517)
		(end 80.8228 -14.07414)
		(stroke
			(width 0.2)
			(type default)
		)
		(layer "In10.Cu")
	)
	(gr_line
		(start 80.76946 -13.6652)
		(end 80.76946 -14.0208)
		(stroke
			(width 0.2)
			(type default)
		)
		(layer "In10.Cu")
	)
	(gr_arc
		(start 80.76946 -13.2588)
		(mid 80.785083 -13.296517)
		(end 80.8228 -13.31214)
		(stroke
			(width 0.2)
			(type default)
		)
		(layer "In10.Cu")
	)
	(gr_line
		(start 80.76946 -12.9032)
		(end 80.76946 -13.2588)
		(stroke
			(width 0.2)
			(type default)
		)
		(layer "In10.Cu")
	)
	(gr_line
		(start 80.8228 -14.07414)
		(end 81.2292 -14.07414)
		(stroke
			(width 0.2)
			(type default)
		)
		(layer "In10.Cu")
	)
	(gr_arc
		(start 80.8228 -13.61186)
		(mid 80.785083 -13.627483)
		(end 80.76946 -13.6652)
		(stroke
			(width 0.2)
			(type default)
		)
		(layer "In10.Cu")
	)
	(gr_line
		(start 80.8228 -13.31214)
		(end 81.2292 -13.31214)
		(stroke
			(width 0.2)
			(type default)
		)
		(layer "In10.Cu")
	)
	(gr_arc
		(start 80.8228 -12.84986)
		(mid 80.785083 -12.865483)
		(end 80.76946 -12.9032)
		(stroke
			(width 0.2)
			(type default)
		)
		(layer "In10.Cu")
	)
	(gr_line
		(start 80.9117 -54.6862)
		(end 80.9117 -54.1274)
		(stroke
			(width 0.2)
			(type default)
		)
		(layer "In10.Cu")
	)
	(gr_arc
		(start 80.9117 -54.1274)
		(mid 80.5688 -53.7845)
		(end 80.2259 -54.1274)
		(stroke
			(width 0.2)
			(type default)
		)
		(layer "In10.Cu")
	)
	(gr_rect
		(start 80.99171 -4.097528)
		(end 81.70799 -8.293608)
		(stroke
			(width 0)
			(type default)
		)
		(fill no)
		(layer "In10.Cu")
	)
	(gr_arc
		(start 81.0514 -60.7187)
		(mid 81.3943 -60.3758)
		(end 81.0514 -60.0329)
		(stroke
			(width 0.2)
			(type default)
		)
		(layer "In10.Cu")
	)
	(gr_line
		(start 81.0514 -60.0329)
		(end 80.264254 -60.0329)
		(stroke
			(width 0.2)
			(type default)
		)
		(layer "In10.Cu")
	)
	(gr_arc
		(start 81.076546 -14.96314)
		(mid 81.46034 -14.579727)
		(end 81.0768 -14.19606)
		(stroke
			(width 0.2)
			(type default)
		)
		(layer "In10.Cu")
	)
	(gr_line
		(start 81.0768 -14.19606)
		(end 80.2132 -14.19606)
		(stroke
			(width 0.2)
			(type default)
		)
		(layer "In10.Cu")
	)
	(gr_arc
		(start 81.2292 -14.07414)
		(mid 81.266917 -14.058517)
		(end 81.28254 -14.0208)
		(stroke
			(width 0.2)
			(type default)
		)
		(layer "In10.Cu")
	)
	(gr_line
		(start 81.2292 -13.61186)
		(end 80.8228 -13.61186)
		(stroke
			(width 0.2)
			(type default)
		)
		(layer "In10.Cu")
	)
	(gr_arc
		(start 81.2292 -13.31214)
		(mid 81.266917 -13.296517)
		(end 81.28254 -13.2588)
		(stroke
			(width 0.2)
			(type default)
		)
		(layer "In10.Cu")
	)
	(gr_line
		(start 81.2292 -12.84986)
		(end 80.8228 -12.84986)
		(stroke
			(width 0.2)
			(type default)
		)
		(layer "In10.Cu")
	)
	(gr_line
		(start 81.28254 -14.0208)
		(end 81.28254 -13.6652)
		(stroke
			(width 0.2)
			(type default)
		)
		(layer "In10.Cu")
	)
	(gr_arc
		(start 81.28254 -13.6652)
		(mid 81.266917 -13.627483)
		(end 81.2292 -13.61186)
		(stroke
			(width 0.2)
			(type default)
		)
		(layer "In10.Cu")
	)
	(gr_line
		(start 81.28254 -13.2588)
		(end 81.28254 -12.9032)
		(stroke
			(width 0.2)
			(type default)
		)
		(layer "In10.Cu")
	)
	(gr_arc
		(start 81.28254 -12.9032)
		(mid 81.266917 -12.865483)
		(end 81.2292 -12.84986)
		(stroke
			(width 0.2)
			(type default)
		)
		(layer "In10.Cu")
	)
	(gr_arc
		(start 81.3435 -53.593746)
		(mid 81.686273 -53.9369)
		(end 82.0293 -53.594)
		(stroke
			(width 0.2)
			(type default)
		)
		(layer "In10.Cu")
	)
	(gr_line
		(start 81.3435 -53.0098)
		(end 81.3435 -53.593746)
		(stroke
			(width 0.2)
			(type default)
		)
		(layer "In10.Cu")
	)
	(gr_rect
		(start 81.991708 -4.097528)
		(end 82.707988 -8.293608)
		(stroke
			(width 0)
			(type default)
		)
		(fill no)
		(layer "In10.Cu")
	)
	(gr_line
		(start 82.0293 -53.594)
		(end 82.0293 -53.0098)
		(stroke
			(width 0.2)
			(type default)
		)
		(layer "In10.Cu")
	)
	(gr_arc
		(start 82.0293 -53.0098)
		(mid 81.6864 -52.6669)
		(end 81.3435 -53.0098)
		(stroke
			(width 0.2)
			(type default)
		)
		(layer "In10.Cu")
	)
	(gr_line
		(start 82.169 -65.913)
		(end 82.931 -65.151)
		(stroke
			(width 0.381)
			(type default)
		)
		(layer "In10.Cu")
	)
	(gr_line
		(start 82.296 -14.32814)
		(end 83.1596 -14.32814)
		(stroke
			(width 0.2)
			(type default)
		)
		(layer "In10.Cu")
	)
	(gr_arc
		(start 82.296254 -13.56106)
		(mid 81.91246 -13.944473)
		(end 82.296 -14.32814)
		(stroke
			(width 0.2)
			(type default)
		)
		(layer "In10.Cu")
	)
	(gr_arc
		(start 82.803746 -55.65902)
		(mid 82.83702 -56.146446)
		(end 83.324446 -56.113172)
		(stroke
			(width 0.2)
			(type default)
		)
		(layer "In10.Cu")
	)
	(gr_line
		(start 82.931 -65.151)
		(end 91.059 -65.151)
		(stroke
			(width 0.381)
			(type default)
		)
		(layer "In10.Cu")
	)
	(gr_arc
		(start 83.1596 -14.32814)
		(mid 83.54314 -13.9446)
		(end 83.1596 -13.56106)
		(stroke
			(width 0.2)
			(type default)
		)
		(layer "In10.Cu")
	)
	(gr_line
		(start 83.1596 -13.56106)
		(end 82.296254 -13.56106)
		(stroke
			(width 0.2)
			(type default)
		)
		(layer "In10.Cu")
	)
	(gr_line
		(start 83.18119 -55.226204)
		(end 82.803746 -55.65902)
		(stroke
			(width 0.2)
			(type default)
		)
		(layer "In10.Cu")
	)
	(gr_arc
		(start 83.309968 -59.661806)
		(mid 83.308952 -60.146946)
		(end 83.794092 -60.147962)
		(stroke
			(width 0.2)
			(type default)
		)
		(layer "In10.Cu")
	)
	(gr_line
		(start 83.324446 -56.113172)
		(end 83.701636 -55.68061)
		(stroke
			(width 0.2)
			(type default)
		)
		(layer "In10.Cu")
	)
	(gr_line
		(start 83.388962 -10.79627)
		(end 84.310474 -10.79627)
		(stroke
			(width 0.2)
			(type default)
		)
		(layer "In10.Cu")
	)
	(gr_arc
		(start 83.389216 -10.02919)
		(mid 83.005422 -10.412603)
		(end 83.388962 -10.79627)
		(stroke
			(width 0.2)
			(type default)
		)
		(layer "In10.Cu")
	)
	(gr_arc
		(start 83.701636 -55.68061)
		(mid 83.668625 -55.193446)
		(end 83.18119 -55.226204)
		(stroke
			(width 0.2)
			(type default)
		)
		(layer "In10.Cu")
	)
	(gr_line
		(start 83.794092 -60.147962)
		(end 84.348828 -59.595258)
		(stroke
			(width 0.2)
			(type default)
		)
		(layer "In10.Cu")
	)
	(gr_line
		(start 83.868006 -59.106054)
		(end 83.309968 -59.661806)
		(stroke
			(width 0.2)
			(type default)
		)
		(layer "In10.Cu")
	)
	(gr_arc
		(start 83.885024 -54.567836)
		(mid 84.22386 -54.91988)
		(end 84.575904 -54.581044)
		(stroke
			(width 0.2)
			(type default)
		)
		(layer "In10.Cu")
	)
	(gr_line
		(start 83.895692 -54.009036)
		(end 83.885024 -54.567836)
		(stroke
			(width 0.2)
			(type default)
		)
		(layer "In10.Cu")
	)
	(gr_arc
		(start 84.310474 -10.79627)
		(mid 84.694014 -10.41273)
		(end 84.310474 -10.02919)
		(stroke
			(width 0.2)
			(type default)
		)
		(layer "In10.Cu")
	)
	(gr_line
		(start 84.310474 -10.02919)
		(end 83.389216 -10.02919)
		(stroke
			(width 0.2)
			(type default)
		)
		(layer "In10.Cu")
	)
	(gr_arc
		(start 84.348828 -59.595258)
		(mid 84.354625 -59.108766)
		(end 83.868006 -59.106054)
		(stroke
			(width 0.2)
			(type default)
		)
		(layer "In10.Cu")
	)
	(gr_line
		(start 84.575904 -54.581044)
		(end 84.586572 -54.022498)
		(stroke
			(width 0.2)
			(type default)
		)
		(layer "In10.Cu")
	)
	(gr_arc
		(start 84.586572 -54.022498)
		(mid 84.247863 -53.670456)
		(end 83.895692 -54.009036)
		(stroke
			(width 0.2)
			(type default)
		)
		(layer "In10.Cu")
	)
	(gr_arc
		(start 85.330538 -55.356506)
		(mid 85.670517 -55.707536)
		(end 86.021418 -55.367428)
		(stroke
			(width 0.2)
			(type default)
		)
		(layer "In10.Cu")
	)
	(gr_line
		(start 85.339174 -54.79034)
		(end 85.330538 -55.356506)
		(stroke
			(width 0.2)
			(type default)
		)
		(layer "In10.Cu")
	)
	(gr_line
		(start 85.598 -69.723)
		(end 86.995 -68.326)
		(stroke
			(width 0.381)
			(type default)
		)
		(layer "In10.Cu")
	)
	(gr_arc
		(start 85.741764 -53.758592)
		(mid 86.080727 -54.110638)
		(end 86.432644 -53.771546)
		(stroke
			(width 0.2)
			(type default)
		)
		(layer "In10.Cu")
	)
	(gr_line
		(start 85.752178 -53.19522)
		(end 85.741764 -53.758592)
		(stroke
			(width 0.2)
			(type default)
		)
		(layer "In10.Cu")
	)
	(gr_line
		(start 86.021418 -55.367428)
		(end 86.030054 -54.801008)
		(stroke
			(width 0.2)
			(type default)
		)
		(layer "In10.Cu")
	)
	(gr_arc
		(start 86.030054 -54.801008)
		(mid 85.689948 -54.450234)
		(end 85.339174 -54.79034)
		(stroke
			(width 0.2)
			(type default)
		)
		(layer "In10.Cu")
	)
	(gr_line
		(start 86.432644 -53.771546)
		(end 86.443058 -53.20792)
		(stroke
			(width 0.2)
			(type default)
		)
		(layer "In10.Cu")
	)
	(gr_arc
		(start 86.443058 -53.20792)
		(mid 86.103968 -52.85613)
		(end 85.752178 -53.19522)
		(stroke
			(width 0.2)
			(type default)
		)
		(layer "In10.Cu")
	)
	(gr_arc
		(start 86.826852 -54.834028)
		(mid 87.165307 -55.186583)
		(end 87.517732 -54.847998)
		(stroke
			(width 0.2)
			(type default)
		)
		(layer "In10.Cu")
	)
	(gr_line
		(start 86.838028 -54.270402)
		(end 86.826852 -54.834028)
		(stroke
			(width 0.2)
			(type default)
		)
		(layer "In10.Cu")
	)
	(gr_line
		(start 86.995 -68.326)
		(end 89.789 -68.326)
		(stroke
			(width 0.381)
			(type default)
		)
		(layer "In10.Cu")
	)
	(gr_line
		(start 87.517732 -54.847998)
		(end 87.528908 -54.284118)
		(stroke
			(width 0.2)
			(type default)
		)
		(layer "In10.Cu")
	)
	(gr_arc
		(start 87.528908 -54.284118)
		(mid 87.190326 -53.93182)
		(end 86.838028 -54.270402)
		(stroke
			(width 0.2)
			(type default)
		)
		(layer "In10.Cu")
	)
	(gr_line
		(start 87.940896 -53.421534)
		(end 87.95893 -53.98008)
		(stroke
			(width 0.2)
			(type default)
		)
		(layer "In10.Cu")
	)
	(gr_line
		(start 87.943436 -53.421534)
		(end 87.940896 -53.421534)
		(stroke
			(width 0.2)
			(type default)
		)
		(layer "In10.Cu")
	)
	(gr_line
		(start 87.95893 -53.98008)
		(end 87.96147 -53.98008)
		(stroke
			(width 0.2)
			(type default)
		)
		(layer "In10.Cu")
	)
	(gr_arc
		(start 87.96147 -53.98008)
		(mid 88.317832 -54.31409)
		(end 88.651842 -53.957728)
		(stroke
			(width 0.2)
			(type default)
		)
		(layer "In10.Cu")
	)
	(gr_arc
		(start 88.633808 -53.399182)
		(mid 88.277446 -53.065172)
		(end 87.943436 -53.421534)
		(stroke
			(width 0.2)
			(type default)
		)
		(layer "In10.Cu")
	)
	(gr_line
		(start 88.636094 -53.399182)
		(end 88.633808 -53.399182)
		(stroke
			(width 0.2)
			(type default)
		)
		(layer "In10.Cu")
	)
	(gr_line
		(start 88.636348 -53.399436)
		(end 88.636094 -53.399182)
		(stroke
			(width 0.2)
			(type default)
		)
		(layer "In10.Cu")
	)
	(gr_line
		(start 88.651842 -53.957728)
		(end 88.654382 -53.957728)
		(stroke
			(width 0.2)
			(type default)
		)
		(layer "In10.Cu")
	)
	(gr_line
		(start 88.654382 -53.957728)
		(end 88.636348 -53.399436)
		(stroke
			(width 0.2)
			(type default)
		)
		(layer "In10.Cu")
	)
	(gr_rect
		(start 88.991948 -4.097528)
		(end 89.708228 -8.293608)
		(stroke
			(width 0)
			(type default)
		)
		(fill no)
		(layer "In10.Cu")
	)
	(gr_arc
		(start 89.415874 -54.043326)
		(mid 89.727024 -54.420008)
		(end 90.103706 -54.108858)
		(stroke
			(width 0.2)
			(type default)
		)
		(layer "In10.Cu")
	)
	(gr_line
		(start 89.46896 -53.486812)
		(end 89.415874 -54.043326)
		(stroke
			(width 0.2)
			(type default)
		)
		(layer "In10.Cu")
	)
	(gr_rect
		(start 89.991946 -4.097528)
		(end 90.708226 -8.293608)
		(stroke
			(width 0)
			(type default)
		)
		(fill no)
		(layer "In10.Cu")
	)
	(gr_line
		(start 90.103706 -54.108858)
		(end 90.156792 -53.552598)
		(stroke
			(width 0.2)
			(type default)
		)
		(layer "In10.Cu")
	)
	(gr_arc
		(start 90.156792 -53.552598)
		(mid 89.845768 -53.175928)
		(end 89.46896 -53.486812)
		(stroke
			(width 0.2)
			(type default)
		)
		(layer "In10.Cu")
	)
	(gr_line
		(start 90.681556 -53.93817)
		(end 90.684096 -53.938424)
		(stroke
			(width 0.2)
			(type default)
		)
		(layer "In10.Cu")
	)
	(gr_arc
		(start 90.684096 -53.938424)
		(mid 91.010994 -54.30139)
		(end 91.37396 -53.974492)
		(stroke
			(width 0.2)
			(type default)
		)
		(layer "In10.Cu")
	)
	(gr_line
		(start 90.71102 -53.377592)
		(end 90.681556 -53.93817)
		(stroke
			(width 0.2)
			(type default)
		)
		(layer "In10.Cu")
	)
	(gr_line
		(start 90.71356 -53.377846)
		(end 90.71102 -53.377592)
		(stroke
			(width 0.2)
			(type default)
		)
		(layer "In10.Cu")
	)
	(gr_line
		(start 90.73769 -54.954932)
		(end 90.73896 -54.956964)
		(stroke
			(width 0.2)
			(type default)
		)
		(layer "In10.Cu")
	)
	(gr_line
		(start 90.73769 -54.954678)
		(end 90.73769 -54.954932)
		(stroke
			(width 0.2)
			(type default)
		)
		(layer "In10.Cu")
	)
	(gr_arc
		(start 90.73896 -54.956964)
		(mid 90.631264 -55.433468)
		(end 91.107768 -55.541164)
		(stroke
			(width 0.2)
			(type default)
		)
		(layer "In10.Cu")
	)
	(gr_line
		(start 91.059 -65.151)
		(end 92.964 -63.246)
		(stroke
			(width 0.381)
			(type default)
		)
		(layer "In10.Cu")
	)
	(gr_line
		(start 91.107768 -55.541164)
		(end 91.109038 -55.543196)
		(stroke
			(width 0.2)
			(type default)
		)
		(layer "In10.Cu")
	)
	(gr_line
		(start 91.109038 -55.543196)
		(end 91.581732 -55.244746)
		(stroke
			(width 0.2)
			(type default)
		)
		(layer "In10.Cu")
	)
	(gr_line
		(start 91.210384 -54.656482)
		(end 90.73769 -54.954678)
		(stroke
			(width 0.2)
			(type default)
		)
		(layer "In10.Cu")
	)
	(gr_line
		(start 91.211654 -54.658514)
		(end 91.210384 -54.656482)
		(stroke
			(width 0.2)
			(type default)
		)
		(layer "In10.Cu")
	)
	(gr_line
		(start 91.37396 -53.974492)
		(end 91.3765 -53.974746)
		(stroke
			(width 0.2)
			(type default)
		)
		(layer "In10.Cu")
	)
	(gr_line
		(start 91.3765 -53.974746)
		(end 91.405964 -53.414422)
		(stroke
			(width 0.2)
			(type default)
		)
		(layer "In10.Cu")
	)
	(gr_arc
		(start 91.403424 -53.414168)
		(mid 91.076653 -53.050941)
		(end 90.71356 -53.377846)
		(stroke
			(width 0.2)
			(type default)
		)
		(layer "In10.Cu")
	)
	(gr_line
		(start 91.40571 -53.414168)
		(end 91.403424 -53.414168)
		(stroke
			(width 0.2)
			(type default)
		)
		(layer "In10.Cu")
	)
	(gr_line
		(start 91.405964 -53.414422)
		(end 91.40571 -53.414168)
		(stroke
			(width 0.2)
			(type default)
		)
		(layer "In10.Cu")
	)
	(gr_arc
		(start 91.580462 -55.242714)
		(mid 91.688158 -54.76621)
		(end 91.211654 -54.658514)
		(stroke
			(width 0.2)
			(type default)
		)
		(layer "In10.Cu")
	)
	(gr_line
		(start 91.581732 -55.244746)
		(end 91.580462 -55.242714)
		(stroke
			(width 0.2)
			(type default)
		)
		(layer "In10.Cu")
	)
	(gr_line
		(start 92.075 -55.118)
		(end 92.075 -39.497)
		(stroke
			(width 0.381)
			(type default)
		)
		(layer "In10.Cu")
	)
	(gr_line
		(start 92.075 -39.497)
		(end 92.456 -39.116)
		(stroke
			(width 0.381)
			(type default)
		)
		(layer "In10.Cu")
	)
	(gr_line
		(start 92.456 -56.388)
		(end 92.456 -55.499)
		(stroke
			(width 0.381)
			(type default)
		)
		(layer "In10.Cu")
	)
	(gr_line
		(start 92.456 -55.499)
		(end 92.075 -55.118)
		(stroke
			(width 0.381)
			(type default)
		)
		(layer "In10.Cu")
	)
	(gr_line
		(start 92.456 -39.116)
		(end 94.615 -39.116)
		(stroke
			(width 0.381)
			(type default)
		)
		(layer "In10.Cu")
	)
	(gr_line
		(start 92.964 -63.246)
		(end 103.124 -63.246)
		(stroke
			(width 0.381)
			(type default)
		)
		(layer "In10.Cu")
	)
	(gr_line
		(start 93.218 -68.326)
		(end 89.789 -68.326)
		(stroke
			(width 0.381)
			(type default)
		)
		(layer "In10.Cu")
	)
	(gr_line
		(start 93.98 -67.564)
		(end 93.218 -68.326)
		(stroke
			(width 0.381)
			(type default)
		)
		(layer "In10.Cu")
	)
	(gr_line
		(start 93.98 -57.912)
		(end 92.456 -56.388)
		(stroke
			(width 0.381)
			(type default)
		)
		(layer "In10.Cu")
	)
	(gr_line
		(start 94.615 -39.116)
		(end 95.504 -40.005)
		(stroke
			(width 0.381)
			(type default)
		)
		(layer "In10.Cu")
	)
	(gr_line
		(start 95.504 -40.005)
		(end 96.139 -40.005)
		(stroke
			(width 0.381)
			(type default)
		)
		(layer "In10.Cu")
	)
	(gr_line
		(start 96.139 -40.005)
		(end 97.028 -40.894)
		(stroke
			(width 0.381)
			(type default)
		)
		(layer "In10.Cu")
	)
	(gr_line
		(start 97.028 -40.894)
		(end 97.536 -40.894)
		(stroke
			(width 0.381)
			(type default)
		)
		(layer "In10.Cu")
	)
	(gr_line
		(start 97.409 -32.004)
		(end 97.663 -32.258)
		(stroke
			(width 0.3048)
			(type default)
		)
		(layer "In10.Cu")
	)
	(gr_line
		(start 97.409 -25.908)
		(end 97.409 -32.004)
		(stroke
			(width 0.3048)
			(type default)
		)
		(layer "In10.Cu")
	)
	(gr_line
		(start 97.536 -40.894)
		(end 98.171 -41.529)
		(stroke
			(width 0.381)
			(type default)
		)
		(layer "In10.Cu")
	)
	(gr_line
		(start 97.663 -32.258)
		(end 98.171 -32.258)
		(stroke
			(width 0.3048)
			(type default)
		)
		(layer "In10.Cu")
	)
	(gr_line
		(start 97.917 -25.4)
		(end 97.409 -25.908)
		(stroke
			(width 0.3048)
			(type default)
		)
		(layer "In10.Cu")
	)
	(gr_line
		(start 97.917 -22.733)
		(end 97.917 -25.4)
		(stroke
			(width 0.3048)
			(type default)
		)
		(layer "In10.Cu")
	)
	(gr_line
		(start 98.171 -41.529)
		(end 100.203 -41.529)
		(stroke
			(width 0.381)
			(type default)
		)
		(layer "In10.Cu")
	)
	(gr_line
		(start 98.171 -32.258)
		(end 98.679 -32.766)
		(stroke
			(width 0.3048)
			(type default)
		)
		(layer "In10.Cu")
	)
	(gr_line
		(start 98.171 -22.479)
		(end 97.917 -22.733)
		(stroke
			(width 0.3048)
			(type default)
		)
		(layer "In10.Cu")
	)
	(gr_line
		(start 98.552 -50.8)
		(end 98.552 -45.339)
		(stroke
			(width 0.3048)
			(type default)
		)
		(layer "In10.Cu")
	)
	(gr_line
		(start 98.552 -45.339)
		(end 99.06 -44.831)
		(stroke
			(width 0.3048)
			(type default)
		)
		(layer "In10.Cu")
	)
	(gr_line
		(start 98.552 -22.479)
		(end 98.171 -22.479)
		(stroke
			(width 0.3048)
			(type default)
		)
		(layer "In10.Cu")
	)
	(gr_line
		(start 98.679 -57.912)
		(end 93.98 -57.912)
		(stroke
			(width 0.381)
			(type default)
		)
		(layer "In10.Cu")
	)
	(gr_line
		(start 98.679 -32.766)
		(end 99.187 -32.766)
		(stroke
			(width 0.3048)
			(type default)
		)
		(layer "In10.Cu")
	)
	(gr_line
		(start 98.806 -22.225)
		(end 98.552 -22.479)
		(stroke
			(width 0.3048)
			(type default)
		)
		(layer "In10.Cu")
	)
	(gr_line
		(start 99.06 -44.831)
		(end 107.188 -44.831)
		(stroke
			(width 0.3048)
			(type default)
		)
		(layer "In10.Cu")
	)
	(gr_line
		(start 99.187 -32.766)
		(end 100.076 -33.655)
		(stroke
			(width 0.3048)
			(type default)
		)
		(layer "In10.Cu")
	)
	(gr_line
		(start 99.24542 -60.922154)
		(end 99.86518 -61.523372)
		(stroke
			(width 0.2)
			(type default)
		)
		(layer "In10.Cu")
	)
	(gr_line
		(start 99.247198 -60.920376)
		(end 99.24542 -60.922154)
		(stroke
			(width 0.2)
			(type default)
		)
		(layer "In10.Cu")
	)
	(gr_line
		(start 99.695 -67.564)
		(end 93.98 -67.564)
		(stroke
			(width 0.381)
			(type default)
		)
		(layer "In10.Cu")
	)
	(gr_arc
		(start 99.781106 -60.369704)
		(mid 99.238816 -60.378086)
		(end 99.247198 -60.920376)
		(stroke
			(width 0.2)
			(type default)
		)
		(layer "In10.Cu")
	)
	(gr_line
		(start 99.782884 -60.367926)
		(end 99.781106 -60.369704)
		(stroke
			(width 0.2)
			(type default)
		)
		(layer "In10.Cu")
	)
	(gr_line
		(start 99.86518 -61.523372)
		(end 99.865434 -61.523372)
		(stroke
			(width 0.2)
			(type default)
		)
		(layer "In10.Cu")
	)
	(gr_line
		(start 99.865434 -61.523372)
		(end 99.866958 -61.521848)
		(stroke
			(width 0.2)
			(type default)
		)
		(layer "In10.Cu")
	)
	(gr_arc
		(start 99.866958 -61.521848)
		(mid 100.409565 -61.513655)
		(end 100.40112 -60.971176)
		(stroke
			(width 0.2)
			(type default)
		)
		(layer "In10.Cu")
	)
	(gr_line
		(start 100.076 -33.655)
		(end 104.013 -33.655)
		(stroke
			(width 0.3048)
			(type default)
		)
		(layer "In10.Cu")
	)
	(gr_line
		(start 100.203 -41.529)
		(end 100.965 -42.291)
		(stroke
			(width 0.381)
			(type default)
		)
		(layer "In10.Cu")
	)
	(gr_line
		(start 100.40112 -60.971176)
		(end 100.402898 -60.969398)
		(stroke
			(width 0.2)
			(type default)
		)
		(layer "In10.Cu")
	)
	(gr_line
		(start 100.402898 -60.969398)
		(end 99.782884 -60.367926)
		(stroke
			(width 0.2)
			(type default)
		)
		(layer "In10.Cu")
	)
	(gr_line
		(start 100.965 -66.294)
		(end 99.695 -67.564)
		(stroke
			(width 0.381)
			(type default)
		)
		(layer "In10.Cu")
	)
	(gr_line
		(start 100.965 -42.291)
		(end 100.965 -44.831)
		(stroke
			(width 0.381)
			(type default)
		)
		(layer "In10.Cu")
	)
	(gr_line
		(start 101.185472 -62.20587)
		(end 101.795072 -62.817756)
		(stroke
			(width 0.2)
			(type default)
		)
		(layer "In10.Cu")
	)
	(gr_line
		(start 101.346 -57.531)
		(end 101.346 -56.896)
		(stroke
			(width 0.3048)
			(type default)
		)
		(layer "In10.Cu")
	)
	(gr_line
		(start 101.346 -56.896)
		(end 101.854 -56.388)
		(stroke
			(width 0.3048)
			(type default)
		)
		(layer "In10.Cu")
	)
	(gr_line
		(start 101.346 -19.685)
		(end 98.806 -22.225)
		(stroke
			(width 0.381)
			(type default)
		)
		(layer "In10.Cu")
	)
	(gr_arc
		(start 101.734366 -61.66993)
		(mid 101.189299 -61.660676)
		(end 101.185472 -62.20587)
		(stroke
			(width 0.2)
			(type default)
		)
		(layer "In10.Cu")
	)
	(gr_arc
		(start 101.795072 -62.817756)
		(mid 102.337616 -62.818772)
		(end 102.338632 -62.276228)
		(stroke
			(width 0.2)
			(type default)
		)
		(layer "In10.Cu")
	)
	(gr_line
		(start 101.854 -56.388)
		(end 101.854 -54.102)
		(stroke
			(width 0.3048)
			(type default)
		)
		(layer "In10.Cu")
	)
	(gr_line
		(start 101.854 -54.102)
		(end 98.552 -50.8)
		(stroke
			(width 0.3048)
			(type default)
		)
		(layer "In10.Cu")
	)
	(gr_line
		(start 102.338632 -62.276228)
		(end 101.734366 -61.66993)
		(stroke
			(width 0.2)
			(type default)
		)
		(layer "In10.Cu")
	)
	(gr_line
		(start 102.87 -62.103)
		(end 98.679 -57.912)
		(stroke
			(width 0.381)
			(type default)
		)
		(layer "In10.Cu")
	)
	(gr_line
		(start 103.124 -63.246)
		(end 103.505 -62.865)
		(stroke
			(width 0.381)
			(type default)
		)
		(layer "In10.Cu")
	)
	(gr_line
		(start 103.251 -62.103)
		(end 102.87 -62.103)
		(stroke
			(width 0.381)
			(type default)
		)
		(layer "In10.Cu")
	)
	(gr_line
		(start 103.505 -62.865)
		(end 103.505 -62.357)
		(stroke
			(width 0.381)
			(type default)
		)
		(layer "In10.Cu")
	)
	(gr_line
		(start 103.505 -62.357)
		(end 103.251 -62.103)
		(stroke
			(width 0.381)
			(type default)
		)
		(layer "In10.Cu")
	)
	(gr_line
		(start 104.013 -66.294)
		(end 100.965 -66.294)
		(stroke
			(width 0.381)
			(type default)
		)
		(layer "In10.Cu")
	)
	(gr_line
		(start 104.013 -33.655)
		(end 104.648 -33.02)
		(stroke
			(width 0.3048)
			(type default)
		)
		(layer "In10.Cu")
	)
	(gr_line
		(start 104.648 -33.02)
		(end 109.728 -33.02)
		(stroke
			(width 0.3048)
			(type default)
		)
		(layer "In10.Cu")
	)
	(gr_line
		(start 104.775 -60.96)
		(end 101.346 -57.531)
		(stroke
			(width 0.381)
			(type default)
		)
		(layer "In10.Cu")
	)
	(gr_line
		(start 105.664 -60.96)
		(end 104.775 -60.96)
		(stroke
			(width 0.381)
			(type default)
		)
		(layer "In10.Cu")
	)
	(gr_line
		(start 105.791 -64.516)
		(end 104.013 -66.294)
		(stroke
			(width 0.381)
			(type default)
		)
		(layer "In10.Cu")
	)
	(gr_line
		(start 105.791 -62.357)
		(end 105.791 -64.516)
		(stroke
			(width 0.381)
			(type default)
		)
		(layer "In10.Cu")
	)
	(gr_line
		(start 106.045 -62.103)
		(end 105.791 -62.357)
		(stroke
			(width 0.381)
			(type default)
		)
		(layer "In10.Cu")
	)
	(gr_line
		(start 106.045 -61.341)
		(end 105.664 -60.96)
		(stroke
			(width 0.381)
			(type default)
		)
		(layer "In10.Cu")
	)
	(gr_line
		(start 106.045 -61.341)
		(end 106.045 -62.103)
		(stroke
			(width 0.381)
			(type default)
		)
		(layer "In10.Cu")
	)
	(gr_line
		(start 107.188 -44.831)
		(end 107.442 -44.958)
		(stroke
			(width 0.3048)
			(type default)
		)
		(layer "In10.Cu")
	)
	(gr_line
		(start 107.442 -44.958)
		(end 108.585 -44.958)
		(stroke
			(width 0.3048)
			(type default)
		)
		(layer "In10.Cu")
	)
	(gr_line
		(start 108.331 -19.685)
		(end 101.346 -19.685)
		(stroke
			(width 0.381)
			(type default)
		)
		(layer "In10.Cu")
	)
	(gr_line
		(start 108.585 -44.958)
		(end 109.093 -45.466)
		(stroke
			(width 0.3048)
			(type default)
		)
		(layer "In10.Cu")
	)
	(gr_line
		(start 109.093 -45.466)
		(end 114.173 -45.466)
		(stroke
			(width 0.3048)
			(type default)
		)
		(layer "In10.Cu")
	)
	(gr_line
		(start 109.728 -33.02)
		(end 109.9566 -32.8422)
		(stroke
			(width 0.3048)
			(type default)
		)
		(layer "In10.Cu")
	)
	(gr_line
		(start 109.9566 -32.8422)
		(end 110.7948 -32.8422)
		(stroke
			(width 0.3048)
			(type default)
		)
		(layer "In10.Cu")
	)
	(gr_line
		(start 110.7948 -32.8422)
		(end 111.0742 -33.1216)
		(stroke
			(width 0.3048)
			(type default)
		)
		(layer "In10.Cu")
	)
	(gr_line
		(start 111.0996 -33.147)
		(end 112.395 -33.147)
		(stroke
			(width 0.3048)
			(type default)
		)
		(layer "In10.Cu")
	)
	(gr_line
		(start 112.395 -33.147)
		(end 114.554 -30.988)
		(stroke
			(width 0.3048)
			(type default)
		)
		(layer "In10.Cu")
	)
	(gr_line
		(start 114.173 -45.466)
		(end 114.427 -45.212)
		(stroke
			(width 0.3048)
			(type default)
		)
		(layer "In10.Cu")
	)
	(gr_line
		(start 114.173 -13.843)
		(end 108.331 -19.685)
		(stroke
			(width 0.381)
			(type default)
		)
		(layer "In10.Cu")
	)
	(gr_line
		(start 114.427 -45.212)
		(end 116.967 -45.212)
		(stroke
			(width 0.3048)
			(type default)
		)
		(layer "In10.Cu")
	)
	(gr_line
		(start 114.554 -30.988)
		(end 117.856 -30.988)
		(stroke
			(width 0.3048)
			(type default)
		)
		(layer "In10.Cu")
	)
	(gr_line
		(start 116.967 -45.212)
		(end 117.094 -45.339)
		(stroke
			(width 0.3048)
			(type default)
		)
		(layer "In10.Cu")
	)
	(gr_line
		(start 117.094 -45.339)
		(end 151.511 -45.339)
		(stroke
			(width 0.381)
			(type default)
		)
		(layer "In10.Cu")
	)
	(gr_line
		(start 117.856 -30.988)
		(end 118.999 -29.845)
		(stroke
			(width 0.381)
			(type default)
		)
		(layer "In10.Cu")
	)
	(gr_line
		(start 118.999 -29.845)
		(end 158.369 -29.845)
		(stroke
			(width 0.381)
			(type default)
		)
		(layer "In10.Cu")
	)
	(gr_line
		(start 119.126 -61.341)
		(end 106.045 -61.341)
		(stroke
			(width 0.381)
			(type default)
		)
		(layer "In10.Cu")
	)
	(gr_line
		(start 119.38 -61.595)
		(end 119.126 -61.341)
		(stroke
			(width 0.381)
			(type default)
		)
		(layer "In10.Cu")
	)
	(gr_line
		(start 131.318 -13.843)
		(end 114.173 -13.843)
		(stroke
			(width 0.381)
			(type default)
		)
		(layer "In10.Cu")
	)
	(gr_line
		(start 133.858 -11.303)
		(end 131.318 -13.843)
		(stroke
			(width 0.381)
			(type default)
		)
		(layer "In10.Cu")
	)
	(gr_line
		(start 147.701 -61.595)
		(end 119.38 -61.595)
		(stroke
			(width 0.381)
			(type default)
		)
		(layer "In10.Cu")
	)
	(gr_line
		(start 148.082 -68.453)
		(end 148.082 -65.405)
		(stroke
			(width 0.381)
			(type default)
		)
		(layer "In10.Cu")
	)
	(gr_line
		(start 148.082 -65.405)
		(end 148.463 -65.024)
		(stroke
			(width 0.381)
			(type default)
		)
		(layer "In10.Cu")
	)
	(gr_line
		(start 148.463 -71.628)
		(end 148.463 -68.834)
		(stroke
			(width 0.381)
			(type default)
		)
		(layer "In10.Cu")
	)
	(gr_line
		(start 148.463 -68.834)
		(end 148.082 -68.453)
		(stroke
			(width 0.381)
			(type default)
		)
		(layer "In10.Cu")
	)
	(gr_line
		(start 148.463 -65.024)
		(end 148.463 -62.357)
		(stroke
			(width 0.381)
			(type default)
		)
		(layer "In10.Cu")
	)
	(gr_line
		(start 148.463 -62.357)
		(end 147.701 -61.595)
		(stroke
			(width 0.381)
			(type default)
		)
		(layer "In10.Cu")
	)
	(gr_line
		(start 148.844 -72.009)
		(end 148.463 -71.628)
		(stroke
			(width 0.381)
			(type default)
		)
		(layer "In10.Cu")
	)
	(gr_line
		(start 151.511 -45.339)
		(end 164.084 -57.912)
		(stroke
			(width 0.381)
			(type default)
		)
		(layer "In10.Cu")
	)
	(gr_line
		(start 155.067 -11.303)
		(end 133.858 -11.303)
		(stroke
			(width 0.381)
			(type default)
		)
		(layer "In10.Cu")
	)
	(gr_line
		(start 155.702 -10.668)
		(end 155.067 -11.303)
		(stroke
			(width 0.381)
			(type default)
		)
		(layer "In10.Cu")
	)
	(gr_line
		(start 155.702 -0.635)
		(end 155.702 -10.668)
		(stroke
			(width 0.381)
			(type default)
		)
		(layer "In10.Cu")
	)
	(gr_line
		(start 158.369 -29.845)
		(end 172.974 -15.24)
		(stroke
			(width 0.381)
			(type default)
		)
		(layer "In10.Cu")
	)
	(gr_line
		(start 162.433 -72.009)
		(end 148.844 -72.009)
		(stroke
			(width 0.381)
			(type default)
		)
		(layer "In10.Cu")
	)
	(gr_line
		(start 162.814 -71.628)
		(end 162.433 -72.009)
		(stroke
			(width 0.381)
			(type default)
		)
		(layer "In10.Cu")
	)
	(gr_line
		(start 162.814 -62.484)
		(end 162.814 -71.628)
		(stroke
			(width 0.381)
			(type default)
		)
		(layer "In10.Cu")
	)
	(gr_line
		(start 164.084 -61.214)
		(end 162.814 -62.484)
		(stroke
			(width 0.381)
			(type default)
		)
		(layer "In10.Cu")
	)
	(gr_line
		(start 164.084 -57.912)
		(end 164.084 -61.214)
		(stroke
			(width 0.381)
			(type default)
		)
		(layer "In10.Cu")
	)
	(gr_line
		(start 170.053 -10.287)
		(end 170.053 -6.096)
		(stroke
			(width 0.381)
			(type default)
		)
		(layer "In10.Cu")
	)
	(gr_line
		(start 170.053 -6.096)
		(end 170.688 -5.461)
		(stroke
			(width 0.381)
			(type default)
		)
		(layer "In10.Cu")
	)
	(gr_line
		(start 170.053 -3.81)
		(end 170.053 -0.635)
		(stroke
			(width 0.381)
			(type default)
		)
		(layer "In10.Cu")
	)
	(gr_line
		(start 170.561 -10.795)
		(end 170.053 -10.287)
		(stroke
			(width 0.381)
			(type default)
		)
		(layer "In10.Cu")
	)
	(gr_line
		(start 170.688 -5.461)
		(end 170.688 -4.445)
		(stroke
			(width 0.381)
			(type default)
		)
		(layer "In10.Cu")
	)
	(gr_line
		(start 170.688 -4.445)
		(end 170.053 -3.81)
		(stroke
			(width 0.381)
			(type default)
		)
		(layer "In10.Cu")
	)
	(gr_line
		(start 172.339 -10.795)
		(end 170.561 -10.795)
		(stroke
			(width 0.381)
			(type default)
		)
		(layer "In10.Cu")
	)
	(gr_line
		(start 172.974 -15.24)
		(end 172.974 -11.43)
		(stroke
			(width 0.381)
			(type default)
		)
		(layer "In10.Cu")
	)
	(gr_line
		(start 172.974 -11.43)
		(end 172.339 -10.795)
		(stroke
			(width 0.381)
			(type default)
		)
		(layer "In10.Cu")
	)
	(gr_line
		(start 0 -72.799956)
		(end 0 -15.699994)
		(stroke
			(width 0.05)
			(type default)
		)
		(layer "Edge.Cuts")
	)
	(gr_arc
		(start 0 -72.799956)
		(mid 0.292895 -73.507058)
		(end 0.999998 -73.799954)
		(stroke
			(width 0.05)
			(type default)
		)
		(layer "Edge.Cuts")
	)
	(gr_line
		(start 0.000254 -72.799956)
		(end 0.000254 -15.699994)
		(stroke
			(width 0.05)
			(type default)
		)
		(layer "Edge.Cuts")
	)
	(gr_arc
		(start 0.000254 -72.799956)
		(mid 0.293147 -73.507061)
		(end 1.000252 -73.799954)
		(stroke
			(width 0.05)
			(type default)
		)
		(layer "Edge.Cuts")
	)
	(gr_arc
		(start 0.999998 -14.699996)
		(mid 0.292893 -14.992889)
		(end 0 -15.699994)
		(stroke
			(width 0.05)
			(type default)
		)
		(layer "Edge.Cuts")
	)
	(gr_line
		(start 0.999998 -14.699996)
		(end 13.699998 -14.699996)
		(stroke
			(width 0.05)
			(type default)
		)
		(layer "Edge.Cuts")
	)
	(gr_arc
		(start 1.000252 -14.699996)
		(mid 0.293147 -14.992889)
		(end 0.000254 -15.699994)
		(stroke
			(width 0.05)
			(type default)
		)
		(layer "Edge.Cuts")
	)
	(gr_line
		(start 1.000252 -14.699996)
		(end 13.700252 -14.699996)
		(stroke
			(width 0.05)
			(type default)
		)
		(layer "Edge.Cuts")
	)
	(gr_arc
		(start 13.699998 -14.699996)
		(mid 14.407103 -14.407103)
		(end 14.699996 -13.699998)
		(stroke
			(width 0.05)
			(type default)
		)
		(layer "Edge.Cuts")
	)
	(gr_arc
		(start 13.700252 -14.699996)
		(mid 14.407357 -14.407103)
		(end 14.70025 -13.699998)
		(stroke
			(width 0.05)
			(type default)
		)
		(layer "Edge.Cuts")
	)
	(gr_line
		(start 14.699996 -13.699998)
		(end 14.699996 -4.100068)
		(stroke
			(width 0.05)
			(type default)
		)
		(layer "Edge.Cuts")
	)
	(gr_line
		(start 14.699996 -4.100068)
		(end 85.900006 -4.100068)
		(stroke
			(width 0.05)
			(type default)
		)
		(layer "Edge.Cuts")
	)
	(gr_line
		(start 14.70025 -13.699998)
		(end 14.70025 -3.199892)
		(stroke
			(width 0.05)
			(type default)
		)
		(layer "Edge.Cuts")
	)
	(gr_line
		(start 14.70025 -3.199892)
		(end 15.200376 -2.699766)
		(stroke
			(width 0.05)
			(type default)
		)
		(layer "Edge.Cuts")
	)
	(gr_line
		(start 15.200376 -2.699766)
		(end 85.400388 -2.699766)
		(stroke
			(width 0.05)
			(type default)
		)
		(layer "Edge.Cuts")
	)
	(gr_line
		(start 85.400388 -2.699766)
		(end 85.90026 -3.199892)
		(stroke
			(width 0.05)
			(type default)
		)
		(layer "Edge.Cuts")
	)
	(gr_arc
		(start 85.900006 -10.150094)
		(mid 86.849966 -11.100054)
		(end 87.799926 -10.150094)
		(stroke
			(width 0.05)
			(type default)
		)
		(layer "Edge.Cuts")
	)
	(gr_line
		(start 85.900006 -4.100068)
		(end 85.900006 -10.150094)
		(stroke
			(width 0.05)
			(type default)
		)
		(layer "Edge.Cuts")
	)
	(gr_arc
		(start 85.90026 -10.14984)
		(mid 86.850474 -11.100054)
		(end 87.800434 -10.14984)
		(stroke
			(width 0.05)
			(type default)
		)
		(layer "Edge.Cuts")
	)
	(gr_line
		(start 85.90026 -3.199892)
		(end 85.90026 -10.14984)
		(stroke
			(width 0.05)
			(type default)
		)
		(layer "Edge.Cuts")
	)
	(gr_line
		(start 87.799926 -10.150094)
		(end 87.799926 -4.100068)
		(stroke
			(width 0.05)
			(type default)
		)
		(layer "Edge.Cuts")
	)
	(gr_line
		(start 87.799926 -4.100068)
		(end 99.000056 -4.100068)
		(stroke
			(width 0.05)
			(type default)
		)
		(layer "Edge.Cuts")
	)
	(gr_line
		(start 87.800434 -10.14984)
		(end 87.800434 -3.199892)
		(stroke
			(width 0.05)
			(type default)
		)
		(layer "Edge.Cuts")
	)
	(gr_line
		(start 87.800434 -3.199892)
		(end 88.300306 -2.699766)
		(stroke
			(width 0.05)
			(type default)
		)
		(layer "Edge.Cuts")
	)
	(gr_line
		(start 88.150954 -60.301124)
		(end 89.7509 -60.301124)
		(stroke
			(width 0.05)
			(type default)
		)
		(layer "Edge.Cuts")
	)
	(gr_arc
		(start 88.150954 -57.100978)
		(mid 86.550754 -58.701178)
		(end 88.150954 -60.301124)
		(stroke
			(width 0.05)
			(type default)
		)
		(layer "Edge.Cuts")
	)
	(gr_line
		(start 88.300306 -2.699766)
		(end 98.500438 -2.699766)
		(stroke
			(width 0.05)
			(type default)
		)
		(layer "Edge.Cuts")
	)
	(gr_arc
		(start 89.7509 -60.301124)
		(mid 91.350846 -58.701178)
		(end 89.7509 -57.100978)
		(stroke
			(width 0.05)
			(type default)
		)
		(layer "Edge.Cuts")
	)
	(gr_line
		(start 89.7509 -57.100978)
		(end 88.150954 -57.100978)
		(stroke
			(width 0.05)
			(type default)
		)
		(layer "Edge.Cuts")
	)
	(gr_line
		(start 98.500438 -2.699766)
		(end 99.00031 -3.199892)
		(stroke
			(width 0.05)
			(type default)
		)
		(layer "Edge.Cuts")
	)
	(gr_arc
		(start 99.000056 -10.700004)
		(mid 99.292949 -11.407109)
		(end 100.000054 -11.700002)
		(stroke
			(width 0.05)
			(type default)
		)
		(layer "Edge.Cuts")
	)
	(gr_line
		(start 99.000056 -4.100068)
		(end 99.000056 -10.700004)
		(stroke
			(width 0.05)
			(type default)
		)
		(layer "Edge.Cuts")
	)
	(gr_arc
		(start 99.00031 -10.700004)
		(mid 99.293203 -11.407109)
		(end 100.000308 -11.700002)
		(stroke
			(width 0.05)
			(type default)
		)
		(layer "Edge.Cuts")
	)
	(gr_line
		(start 99.00031 -3.199892)
		(end 99.00031 -10.700004)
		(stroke
			(width 0.05)
			(type default)
		)
		(layer "Edge.Cuts")
	)
	(gr_line
		(start 100.000054 -11.700002)
		(end 104.000046 -11.700002)
		(stroke
			(width 0.05)
			(type default)
		)
		(layer "Edge.Cuts")
	)
	(gr_line
		(start 100.000308 -11.700002)
		(end 104.0003 -11.700002)
		(stroke
			(width 0.05)
			(type default)
		)
		(layer "Edge.Cuts")
	)
	(gr_arc
		(start 104.000046 -11.700002)
		(mid 104.707151 -11.407109)
		(end 105.000044 -10.700004)
		(stroke
			(width 0.05)
			(type default)
		)
		(layer "Edge.Cuts")
	)
	(gr_arc
		(start 104.0003 -11.700002)
		(mid 104.707405 -11.407109)
		(end 105.000298 -10.700004)
		(stroke
			(width 0.05)
			(type default)
		)
		(layer "Edge.Cuts")
	)
	(gr_line
		(start 105.000044 -10.700004)
		(end 105.000044 -0.999998)
		(stroke
			(width 0.05)
			(type default)
		)
		(layer "Edge.Cuts")
	)
	(gr_line
		(start 105.000298 -10.700004)
		(end 105.000298 -0.999998)
		(stroke
			(width 0.05)
			(type default)
		)
		(layer "Edge.Cuts")
	)
	(gr_arc
		(start 106.000042 0)
		(mid 105.292909 -0.292878)
		(end 105.000044 -0.999998)
		(stroke
			(width 0.05)
			(type default)
		)
		(layer "Edge.Cuts")
	)
	(gr_line
		(start 106.000042 0)
		(end 209.00009 0)
		(stroke
			(width 0.05)
			(type default)
		)
		(layer "Edge.Cuts")
	)
	(gr_arc
		(start 106.000296 0)
		(mid 105.293193 -0.292894)
		(end 105.000298 -0.999998)
		(stroke
			(width 0.05)
			(type default)
		)
		(layer "Edge.Cuts")
	)
	(gr_line
		(start 106.000296 0)
		(end 209.000344 0)
		(stroke
			(width 0.05)
			(type default)
		)
		(layer "Edge.Cuts")
	)
	(gr_line
		(start 209.00009 -73.799954)
		(end 0.999998 -73.799954)
		(stroke
			(width 0.05)
			(type default)
		)
		(layer "Edge.Cuts")
	)
	(gr_arc
		(start 209.00009 -73.799954)
		(mid 209.707186 -73.507062)
		(end 210.000088 -72.799956)
		(stroke
			(width 0.05)
			(type default)
		)
		(layer "Edge.Cuts")
	)
	(gr_line
		(start 209.000344 -73.799954)
		(end 1.000252 -73.799954)
		(stroke
			(width 0.05)
			(type default)
		)
		(layer "Edge.Cuts")
	)
	(gr_arc
		(start 209.000344 -73.799954)
		(mid 209.707405 -73.507043)
		(end 210.000342 -72.799956)
		(stroke
			(width 0.05)
			(type default)
		)
		(layer "Edge.Cuts")
	)
	(gr_arc
		(start 210.000088 -0.999998)
		(mid 209.707194 -0.292897)
		(end 209.00009 0)
		(stroke
			(width 0.05)
			(type default)
		)
		(layer "Edge.Cuts")
	)
	(gr_line
		(start 210.000088 -0.999998)
		(end 210.000088 -72.799956)
		(stroke
			(width 0.05)
			(type default)
		)
		(layer "Edge.Cuts")
	)
	(gr_arc
		(start 210.000342 -0.999998)
		(mid 209.707451 -0.292878)
		(end 209.000344 0)
		(stroke
			(width 0.05)
			(type default)
		)
		(layer "Edge.Cuts")
	)
	(gr_line
		(start 210.000342 -0.999998)
		(end 210.000342 -72.799956)
		(stroke
			(width 0.05)
			(type default)
		)
		(layer "Edge.Cuts")
	)
	(segment
		(start 151.257 -50.4952)
		(end 151.6888 -50.4952)
		(width 0.1143)
		(layer "F.Cu")
		(net "BUS_SW_OE#")
	)
	(segment
		(start 150.8125 -50.4952)
		(end 151.257 -50.4952)
		(width 0.1143)
		(layer "F.Cu")
		(net "BUS_SW_OE#")
	)
	(segment
		(start 151.6888 -50.4952)
		(end 152.1206 -50.927)
		(width 0.1143)
		(layer "F.Cu")
		(net "BUS_SW_OE#")
	)
	(segment
		(start 149.9616 -50.71618)
		(end 150.59152 -50.71618)
		(width 0.1143)
		(layer "F.Cu")
		(net "BUS_SW_OE#")
	)
	(segment
		(start 150.59152 -50.71618)
		(end 150.8125 -50.4952)
		(width 0.1143)
		(layer "F.Cu")
		(net "BUS_SW_OE#")
	)
	(via
		(at 152.1206 -50.927)
		(size 0.7112)
		(drill 0.3556)
		(layers "F.Cu" "B.Cu")
		(net "BUS_SW_OE#")
	)
	(segment
		(start 146.0881 -56.3372)
		(end 147.1295 -56.3372)
		(width 0.1143)
		(layer "F.Cu")
		(net "BUS_SW_SEL")
	)
	(segment
		(start 148.3741 -53.06695)
		(end 148.10359 -53.06695)
		(width 0.1143)
		(layer "F.Cu")
		(net "BUS_SW_SEL")
	)
	(segment
		(start 147.2184 -56.8071)
		(end 147.3073 -56.896)
		(width 0.1143)
		(layer "F.Cu")
		(net "BUS_SW_SEL")
	)
	(segment
		(start 147.84705 -52.280058)
		(end 147.50923 -51.942238)
		(width 0.1143)
		(layer "F.Cu")
		(net "BUS_SW_SEL")
	)
	(segment
		(start 147.2184 -56.4261)
		(end 147.2184 -56.8071)
		(width 0.1143)
		(layer "F.Cu")
		(net "BUS_SW_SEL")
	)
	(segment
		(start 148.463 -53.15585)
		(end 148.3741 -53.06695)
		(width 0.1143)
		(layer "F.Cu")
		(net "BUS_SW_SEL")
	)
	(segment
		(start 148.6916 -56.896)
		(end 149.00529 -56.58231)
		(width 0.1143)
		(layer "F.Cu")
		(net "BUS_SW_SEL")
	)
	(segment
		(start 149.00529 -54.73065)
		(end 148.463 -54.18836)
		(width 0.1143)
		(layer "F.Cu")
		(net "BUS_SW_SEL")
	)
	(segment
		(start 144.500346 -55.245)
		(end 145.592546 -56.3372)
		(width 0.1143)
		(layer "F.Cu")
		(net "BUS_SW_SEL")
	)
	(segment
		(start 147.84705 -52.81041)
		(end 147.84705 -52.280058)
		(width 0.1143)
		(layer "F.Cu")
		(net "BUS_SW_SEL")
	)
	(segment
		(start 147.50923 -51.942238)
		(end 147.50923 -51.4223)
		(width 0.1143)
		(layer "F.Cu")
		(net "BUS_SW_SEL")
	)
	(segment
		(start 147.1295 -56.3372)
		(end 147.2184 -56.4261)
		(width 0.1143)
		(layer "F.Cu")
		(net "BUS_SW_SEL")
	)
	(segment
		(start 144.272 -55.245)
		(end 144.500346 -55.245)
		(width 0.1143)
		(layer "F.Cu")
		(net "BUS_SW_SEL")
	)
	(segment
		(start 147.3073 -56.896)
		(end 148.6916 -56.896)
		(width 0.1143)
		(layer "F.Cu")
		(net "BUS_SW_SEL")
	)
	(segment
		(start 148.463 -54.18836)
		(end 148.463 -53.15585)
		(width 0.1143)
		(layer "F.Cu")
		(net "BUS_SW_SEL")
	)
	(segment
		(start 148.10359 -53.06695)
		(end 147.84705 -52.81041)
		(width 0.1143)
		(layer "F.Cu")
		(net "BUS_SW_SEL")
	)
	(segment
		(start 149.00529 -56.58231)
		(end 149.00529 -54.73065)
		(width 0.1143)
		(layer "F.Cu")
		(net "BUS_SW_SEL")
	)
	(segment
		(start 145.592546 -56.3372)
		(end 146.0881 -56.3372)
		(width 0.1143)
		(layer "F.Cu")
		(net "BUS_SW_SEL")
	)
	(via
		(at 144.272 -55.245)
		(size 0.7112)
		(drill 0.3556)
		(layers "F.Cu" "B.Cu")
		(net "BUS_SW_SEL")
	)
	(segment
		(start 148.2852 -52.6288)
		(end 148.2852 -51.429666)
		(width 0.1143)
		(layer "F.Cu")
		(net "SPI_SW_CSO#")
	)
	(segment
		(start 147.598384 -50.74285)
		(end 147.345146 -50.74285)
		(width 0.1143)
		(layer "F.Cu")
		(net "SPI_SW_CSO#")
	)
	(segment
		(start 147.318476 -50.71618)
		(end 146.558 -50.71618)
		(width 0.1143)
		(layer "F.Cu")
		(net "SPI_SW_CSO#")
	)
	(segment
		(start 150.206202 -52.930298)
		(end 150.69947 -52.43703)
		(width 0.1143)
		(layer "F.Cu")
		(net "SPI_SW_CSO#")
	)
	(segment
		(start 147.345146 -50.74285)
		(end 147.318476 -50.71618)
		(width 0.1143)
		(layer "F.Cu")
		(net "SPI_SW_CSO#")
	)
	(segment
		(start 150.69947 -52.43703)
		(end 151.5999 -52.43703)
		(width 0.1143)
		(layer "F.Cu")
		(net "SPI_SW_CSO#")
	)
	(segment
		(start 148.2852 -51.429666)
		(end 147.598384 -50.74285)
		(width 0.1143)
		(layer "F.Cu")
		(net "SPI_SW_CSO#")
	)
	(via
		(at 148.2852 -52.6288)
		(size 0.508)
		(drill 0.254)
		(layers "F.Cu" "B.Cu")
		(net "SPI_SW_CSO#")
	)
	(via
		(at 150.206202 -52.930298)
		(size 0.508)
		(drill 0.254)
		(layers "F.Cu" "B.Cu")
		(net "SPI_SW_CSO#")
	)
	(via
		(at 151.12111 -52.62245)
		(size 0.7112)
		(drill 0.3556)
		(layers "F.Cu" "B.Cu")
		(net "SPI_SW_CSO#")
	)
	(segment
		(start 150.206202 -52.930298)
		(end 148.586698 -52.930298)
		(width 0.1143)
		(layer "B.Cu")
		(net "SPI_SW_CSO#")
	)
	(segment
		(start 150.206202 -52.930298)
		(end 150.813262 -52.930298)
		(width 0.1143)
		(layer "B.Cu")
		(net "SPI_SW_CSO#")
	)
	(segment
		(start 148.586698 -52.930298)
		(end 148.2852 -52.6288)
		(width 0.1143)
		(layer "B.Cu")
		(net "SPI_SW_CSO#")
	)
	(segment
		(start 150.813262 -52.930298)
		(end 151.12111 -52.62245)
		(width 0.1143)
		(layer "B.Cu")
		(net "SPI_SW_CSO#")
	)
	(segment
		(start 145.198084 -49.21631)
		(end 146.558 -49.21631)
		(width 0.1143)
		(layer "F.Cu")
		(net "SPI_SW_DCLK")
	)
	(segment
		(start 147.7137 -56.220868)
		(end 148.169122 -56.220868)
		(width 0.1143)
		(layer "F.Cu")
		(net "SPI_SW_DCLK")
	)
	(segment
		(start 146.33194 -51.5366)
		(end 145.0086 -51.5366)
		(width 0.1143)
		(layer "F.Cu")
		(net "SPI_SW_DCLK")
	)
	(segment
		(start 147.08505 -53.99405)
		(end 147.9677 -53.99405)
		(width 0.1143)
		(layer "F.Cu")
		(net "SPI_SW_DCLK")
	)
	(segment
		(start 146.97075 -52.17541)
		(end 146.33194 -51.5366)
		(width 0.1143)
		(layer "F.Cu")
		(net "SPI_SW_DCLK")
	)
	(segment
		(start 148.28139 -54.7878)
		(end 147.05965 -54.7878)
		(width 0.1143)
		(layer "F.Cu")
		(net "SPI_SW_DCLK")
	)
	(segment
		(start 146.97075 -53.30825)
		(end 146.97075 -52.17541)
		(width 0.1143)
		(layer "F.Cu")
		(net "SPI_SW_DCLK")
	)
	(segment
		(start 147.9677 -53.42255)
		(end 147.08505 -53.42255)
		(width 0.1143)
		(layer "F.Cu")
		(net "SPI_SW_DCLK")
	)
	(segment
		(start 144.72285 -49.691544)
		(end 145.198084 -49.21631)
		(width 0.1143)
		(layer "F.Cu")
		(net "SPI_SW_DCLK")
	)
	(segment
		(start 146.97075 -54.6989)
		(end 146.97075 -54.10835)
		(width 0.1143)
		(layer "F.Cu")
		(net "SPI_SW_DCLK")
	)
	(segment
		(start 148.0566 -53.51145)
		(end 147.9677 -53.42255)
		(width 0.1143)
		(layer "F.Cu")
		(net "SPI_SW_DCLK")
	)
	(segment
		(start 147.179792 -55.68696)
		(end 147.7137 -56.220868)
		(width 0.1143)
		(layer "F.Cu")
		(net "SPI_SW_DCLK")
	)
	(segment
		(start 147.08505 -53.42255)
		(end 146.97075 -53.30825)
		(width 0.1143)
		(layer "F.Cu")
		(net "SPI_SW_DCLK")
	)
	(segment
		(start 148.0566 -53.90515)
		(end 148.0566 -53.51145)
		(width 0.1143)
		(layer "F.Cu")
		(net "SPI_SW_DCLK")
	)
	(segment
		(start 147.9677 -53.99405)
		(end 148.0566 -53.90515)
		(width 0.1143)
		(layer "F.Cu")
		(net "SPI_SW_DCLK")
	)
	(segment
		(start 148.169122 -56.220868)
		(end 148.50999 -55.88)
		(width 0.1143)
		(layer "F.Cu")
		(net "SPI_SW_DCLK")
	)
	(segment
		(start 147.05965 -54.7878)
		(end 146.97075 -54.6989)
		(width 0.1143)
		(layer "F.Cu")
		(net "SPI_SW_DCLK")
	)
	(segment
		(start 148.50999 -55.88)
		(end 148.50999 -55.0164)
		(width 0.1143)
		(layer "F.Cu")
		(net "SPI_SW_DCLK")
	)
	(segment
		(start 148.50999 -55.0164)
		(end 148.28139 -54.7878)
		(width 0.1143)
		(layer "F.Cu")
		(net "SPI_SW_DCLK")
	)
	(segment
		(start 146.0881 -55.68696)
		(end 147.179792 -55.68696)
		(width 0.1143)
		(layer "F.Cu")
		(net "SPI_SW_DCLK")
	)
	(segment
		(start 144.72285 -51.25085)
		(end 144.72285 -49.691544)
		(width 0.1143)
		(layer "F.Cu")
		(net "SPI_SW_DCLK")
	)
	(segment
		(start 144.907 -51.435)
		(end 144.72285 -51.25085)
		(width 0.1143)
		(layer "F.Cu")
		(net "SPI_SW_DCLK")
	)
	(segment
		(start 145.0086 -51.5366)
		(end 144.907 -51.435)
		(width 0.1143)
		(layer "F.Cu")
		(net "SPI_SW_DCLK")
	)
	(segment
		(start 146.97075 -54.10835)
		(end 147.08505 -53.99405)
		(width 0.1143)
		(layer "F.Cu")
		(net "SPI_SW_DCLK")
	)
	(via
		(at 144.907 -51.435)
		(size 0.7112)
		(drill 0.3556)
		(layers "F.Cu" "B.Cu")
		(net "SPI_SW_DCLK")
	)
	(segment
		(start 150.241 -53.584856)
		(end 150.241 -54.164484)
		(width 0.1143)
		(layer "F.Cu")
		(net "SPI_SW_DATA0")
	)
	(segment
		(start 149.768052 -52.748688)
		(end 149.768052 -53.111908)
		(width 0.1143)
		(layer "F.Cu")
		(net "SPI_SW_DATA0")
	)
	(segment
		(start 150.241 -54.164484)
		(end 151.113236 -55.03672)
		(width 0.1143)
		(layer "F.Cu")
		(net "SPI_SW_DATA0")
	)
	(segment
		(start 150.5458 -50.03165)
		(end 150.36038 -50.21707)
		(width 0.1143)
		(layer "F.Cu")
		(net "SPI_SW_DATA0")
	)
	(segment
		(start 152.68575 -49.76495)
		(end 152.68575 -51.161188)
		(width 0.1143)
		(layer "F.Cu")
		(net "SPI_SW_DATA0")
	)
	(segment
		(start 151.113236 -55.03672)
		(end 151.5999 -55.03672)
		(width 0.1143)
		(layer "F.Cu")
		(net "SPI_SW_DATA0")
	)
	(segment
		(start 149.768052 -53.111908)
		(end 150.241 -53.584856)
		(width 0.1143)
		(layer "F.Cu")
		(net "SPI_SW_DATA0")
	)
	(segment
		(start 150.431246 -52.085494)
		(end 149.768052 -52.748688)
		(width 0.1143)
		(layer "F.Cu")
		(net "SPI_SW_DATA0")
	)
	(segment
		(start 151.7142 -50.03165)
		(end 150.5458 -50.03165)
		(width 0.1143)
		(layer "F.Cu")
		(net "SPI_SW_DATA0")
	)
	(segment
		(start 152.654 -49.7332)
		(end 152.01265 -49.7332)
		(width 0.1143)
		(layer "F.Cu")
		(net "SPI_SW_DATA0")
	)
	(segment
		(start 152.01265 -49.7332)
		(end 151.7142 -50.03165)
		(width 0.1143)
		(layer "F.Cu")
		(net "SPI_SW_DATA0")
	)
	(segment
		(start 152.68575 -51.161188)
		(end 151.878538 -51.9684)
		(width 0.1143)
		(layer "F.Cu")
		(net "SPI_SW_DATA0")
	)
	(segment
		(start 150.36038 -50.21707)
		(end 149.9616 -50.21707)
		(width 0.1143)
		(layer "F.Cu")
		(net "SPI_SW_DATA0")
	)
	(segment
		(start 152.654 -49.7332)
		(end 152.68575 -49.76495)
		(width 0.1143)
		(layer "F.Cu")
		(net "SPI_SW_DATA0")
	)
	(segment
		(start 151.878538 -51.9684)
		(end 150.548594 -51.9684)
		(width 0.1143)
		(layer "F.Cu")
		(net "SPI_SW_DATA0")
	)
	(segment
		(start 150.548594 -51.9684)
		(end 150.431246 -52.085494)
		(width 0.1143)
		(layer "F.Cu")
		(net "SPI_SW_DATA0")
	)
	(via
		(at 152.654 -49.7332)
		(size 0.7112)
		(drill 0.3556)
		(layers "F.Cu" "B.Cu")
		(net "SPI_SW_DATA0")
	)
	(segment
		(start 149.7457 -53.6067)
		(end 149.11705 -52.97805)
		(width 0.1143)
		(layer "F.Cu")
		(net "SPI_SW_ASDO")
	)
	(segment
		(start 152.794716 -55.68696)
		(end 153.173938 -55.307738)
		(width 0.1143)
		(layer "F.Cu")
		(net "SPI_SW_ASDO")
	)
	(segment
		(start 149.34692 -51.85918)
		(end 149.34692 -48.998886)
		(width 0.1143)
		(layer "F.Cu")
		(net "SPI_SW_ASDO")
	)
	(segment
		(start 149.11705 -52.08905)
		(end 149.34692 -51.85918)
		(width 0.1143)
		(layer "F.Cu")
		(net "SPI_SW_ASDO")
	)
	(segment
		(start 149.629876 -48.71593)
		(end 149.9616 -48.71593)
		(width 0.1143)
		(layer "F.Cu")
		(net "SPI_SW_ASDO")
	)
	(segment
		(start 149.7457 -54.369716)
		(end 149.7457 -53.6067)
		(width 0.1143)
		(layer "F.Cu")
		(net "SPI_SW_ASDO")
	)
	(segment
		(start 151.062944 -55.68696)
		(end 149.7457 -54.369716)
		(width 0.1143)
		(layer "F.Cu")
		(net "SPI_SW_ASDO")
	)
	(segment
		(start 151.5999 -55.68696)
		(end 152.794716 -55.68696)
		(width 0.1143)
		(layer "F.Cu")
		(net "SPI_SW_ASDO")
	)
	(segment
		(start 149.34692 -48.998886)
		(end 149.629876 -48.71593)
		(width 0.1143)
		(layer "F.Cu")
		(net "SPI_SW_ASDO")
	)
	(segment
		(start 151.5999 -55.68696)
		(end 151.062944 -55.68696)
		(width 0.1143)
		(layer "F.Cu")
		(net "SPI_SW_ASDO")
	)
	(segment
		(start 149.11705 -52.97805)
		(end 149.11705 -52.08905)
		(width 0.1143)
		(layer "F.Cu")
		(net "SPI_SW_ASDO")
	)
	(via
		(at 153.173938 -55.307738)
		(size 0.7112)
		(drill 0.3556)
		(layers "F.Cu" "B.Cu")
		(net "SPI_SW_ASDO")
	)
	(segment
		(start 147.09775 -47.09414)
		(end 147.09775 -49.945544)
		(width 0.1143)
		(layer "F.Cu")
		(net "FPGA_CSO#")
	)
	(segment
		(start 146.826224 -50.21707)
		(end 146.558 -50.21707)
		(width 0.1143)
		(layer "F.Cu")
		(net "FPGA_CSO#")
	)
	(segment
		(start 147.09775 -49.945544)
		(end 146.826224 -50.21707)
		(width 0.1143)
		(layer "F.Cu")
		(net "FPGA_CSO#")
	)
	(segment
		(start 147.99818 -45.71492)
		(end 147.454366 -46.258734)
		(width 0.1143)
		(layer "F.Cu")
		(net "FPGA_CSO#")
	)
	(segment
		(start 147.454366 -46.737524)
		(end 147.09775 -47.09414)
		(width 0.1143)
		(layer "F.Cu")
		(net "FPGA_CSO#")
	)
	(segment
		(start 147.454366 -46.258734)
		(end 147.454366 -46.737524)
		(width 0.1143)
		(layer "F.Cu")
		(net "FPGA_CSO#")
	)
	(segment
		(start 147.99818 -45.1612)
		(end 147.99818 -45.71492)
		(width 0.1143)
		(layer "F.Cu")
		(net "FPGA_CSO#")
	)
	(segment
		(start 146.289776 -48.71593)
		(end 146.030696 -48.97501)
		(width 0.1143)
		(layer "F.Cu")
		(net "FPGA_DCLK")
	)
	(segment
		(start 143.764 -49.276)
		(end 144.2212 -48.8188)
		(width 0.1143)
		(layer "F.Cu")
		(net "FPGA_DCLK")
	)
	(segment
		(start 146.85645 -47.28845)
		(end 146.685 -47.117)
		(width 0.1143)
		(layer "F.Cu")
		(net "FPGA_DCLK")
	)
	(segment
		(start 143.512794 -51.004724)
		(end 142.513304 -50.005234)
		(width 0.1143)
		(layer "F.Cu")
		(net "FPGA_DCLK")
	)
	(segment
		(start 144.48155 -50.8)
		(end 144.276826 -51.004724)
		(width 0.1143)
		(layer "F.Cu")
		(net "FPGA_DCLK")
	)
	(segment
		(start 145.90776 -47.879)
		(end 146.655536 -47.879)
		(width 0.1143)
		(layer "F.Cu")
		(net "FPGA_DCLK")
	)
	(segment
		(start 145.94078 -46.9138)
		(end 145.94078 -46.40199)
		(width 0.1143)
		(layer "F.Cu")
		(net "FPGA_DCLK")
	)
	(segment
		(start 144.48155 -49.591468)
		(end 144.48155 -50.8)
		(width 0.1143)
		(layer "F.Cu")
		(net "FPGA_DCLK")
	)
	(segment
		(start 145.315432 -47.286672)
		(end 145.90776 -47.879)
		(width 0.1143)
		(layer "F.Cu")
		(net "FPGA_DCLK")
	)
	(segment
		(start 146.558 -48.71593)
		(end 146.289776 -48.71593)
		(width 0.1143)
		(layer "F.Cu")
		(net "FPGA_DCLK")
	)
	(segment
		(start 144.416018 -47.286672)
		(end 145.315432 -47.286672)
		(width 0.1143)
		(layer "F.Cu")
		(net "FPGA_DCLK")
	)
	(segment
		(start 145.94078 -46.40199)
		(end 145.99793 -46.34484)
		(width 0.1143)
		(layer "F.Cu")
		(net "FPGA_DCLK")
	)
	(segment
		(start 145.098008 -48.97501)
		(end 144.48155 -49.591468)
		(width 0.1143)
		(layer "F.Cu")
		(net "FPGA_DCLK")
	)
	(segment
		(start 143.764 -47.93869)
		(end 144.416018 -47.286672)
		(width 0.1143)
		(layer "F.Cu")
		(net "FPGA_DCLK")
	)
	(segment
		(start 145.99793 -46.34484)
		(end 145.99793 -45.1612)
		(width 0.1143)
		(layer "F.Cu")
		(net "FPGA_DCLK")
	)
	(segment
		(start 146.030696 -48.97501)
		(end 145.098008 -48.97501)
		(width 0.1143)
		(layer "F.Cu")
		(net "FPGA_DCLK")
	)
	(segment
		(start 146.655536 -47.879)
		(end 146.85645 -47.678086)
		(width 0.1143)
		(layer "F.Cu")
		(net "FPGA_DCLK")
	)
	(segment
		(start 144.2212 -48.5648)
		(end 143.764 -48.1076)
		(width 0.1143)
		(layer "F.Cu")
		(net "FPGA_DCLK")
	)
	(segment
		(start 142.513304 -49.548542)
		(end 143.141446 -48.9204)
		(width 0.1143)
		(layer "F.Cu")
		(net "FPGA_DCLK")
	)
	(segment
		(start 143.4084 -48.9204)
		(end 143.764 -49.276)
		(width 0.1143)
		(layer "F.Cu")
		(net "FPGA_DCLK")
	)
	(segment
		(start 144.276826 -51.004724)
		(end 143.512794 -51.004724)
		(width 0.1143)
		(layer "F.Cu")
		(net "FPGA_DCLK")
	)
	(segment
		(start 146.85645 -47.678086)
		(end 146.85645 -47.28845)
		(width 0.1143)
		(layer "F.Cu")
		(net "FPGA_DCLK")
	)
	(segment
		(start 146.14398 -47.117)
		(end 145.94078 -46.9138)
		(width 0.1143)
		(layer "F.Cu")
		(net "FPGA_DCLK")
	)
	(segment
		(start 142.513304 -50.005234)
		(end 142.513304 -49.548542)
		(width 0.1143)
		(layer "F.Cu")
		(net "FPGA_DCLK")
	)
	(segment
		(start 143.141446 -48.9204)
		(end 143.4084 -48.9204)
		(width 0.1143)
		(layer "F.Cu")
		(net "FPGA_DCLK")
	)
	(segment
		(start 144.2212 -48.8188)
		(end 144.2212 -48.5648)
		(width 0.1143)
		(layer "F.Cu")
		(net "FPGA_DCLK")
	)
	(segment
		(start 143.764 -48.1076)
		(end 143.764 -47.93869)
		(width 0.1143)
		(layer "F.Cu")
		(net "FPGA_DCLK")
	)
	(segment
		(start 146.685 -47.117)
		(end 146.14398 -47.117)
		(width 0.1143)
		(layer "F.Cu")
		(net "FPGA_DCLK")
	)
	(via
		(at 143.764 -49.276)
		(size 0.7112)
		(drill 0.3556)
		(layers "F.Cu" "B.Cu")
		(net "FPGA_DCLK")
	)
	(segment
		(start 151.870664 -49.218342)
		(end 151.372316 -49.71669)
		(width 0.1143)
		(layer "F.Cu")
		(net "FPGA_DATA0")
	)
	(segment
		(start 145.50263 -46.5582)
		(end 145.49755 -46.55312)
		(width 0.1143)
		(layer "F.Cu")
		(net "FPGA_DATA0")
	)
	(segment
		(start 145.49755 -46.55312)
		(end 145.49755 -45.1612)
		(width 0.1143)
		(layer "F.Cu")
		(net "FPGA_DATA0")
	)
	(segment
		(start 151.870664 -47.348394)
		(end 151.870664 -49.218342)
		(width 0.1143)
		(layer "F.Cu")
		(net "FPGA_DATA0")
	)
	(segment
		(start 150.76805 -47.244)
		(end 151.76627 -47.244)
		(width 0.1143)
		(layer "F.Cu")
		(net "FPGA_DATA0")
	)
	(segment
		(start 150.3299 -47.68215)
		(end 150.76805 -47.244)
		(width 0.1143)
		(layer "F.Cu")
		(net "FPGA_DATA0")
	)
	(segment
		(start 151.372316 -49.71669)
		(end 149.9616 -49.71669)
		(width 0.1143)
		(layer "F.Cu")
		(net "FPGA_DATA0")
	)
	(segment
		(start 151.76627 -47.244)
		(end 151.870664 -47.348394)
		(width 0.1143)
		(layer "F.Cu")
		(net "FPGA_DATA0")
	)
	(via
		(at 150.3299 -47.68215)
		(size 0.508)
		(drill 0.254)
		(layers "F.Cu" "B.Cu")
		(net "FPGA_DATA0")
	)
	(via
		(at 145.50263 -46.5582)
		(size 0.508)
		(drill 0.254)
		(layers "F.Cu" "B.Cu")
		(net "FPGA_DATA0")
	)
	(via
		(at 151.870664 -47.348394)
		(size 0.7112)
		(drill 0.3556)
		(layers "F.Cu" "B.Cu")
		(net "FPGA_DATA0")
	)
	(segment
		(start 150.3299 -47.68215)
		(end 150.142702 -47.494952)
		(width 0.1143)
		(layer "B.Cu")
		(net "FPGA_DATA0")
	)
	(segment
		(start 150.142702 -47.494952)
		(end 146.439382 -47.494952)
		(width 0.1143)
		(layer "B.Cu")
		(net "FPGA_DATA0")
	)
	(segment
		(start 146.439382 -47.494952)
		(end 145.50263 -46.5582)
		(width 0.1143)
		(layer "B.Cu")
		(net "FPGA_DATA0")
	)
	(segment
		(start 149.3647 -47.0916)
		(end 149.3647 -47.8409)
		(width 0.1143)
		(layer "F.Cu")
		(net "FPGA_ASDO")
	)
	(segment
		(start 149.74062 -48.21682)
		(end 149.9616 -48.21682)
		(width 0.1143)
		(layer "F.Cu")
		(net "FPGA_ASDO")
	)
	(segment
		(start 148.99767 -46.72457)
		(end 149.3647 -47.0916)
		(width 0.1143)
		(layer "F.Cu")
		(net "FPGA_ASDO")
	)
	(segment
		(start 149.3647 -47.8409)
		(end 149.74062 -48.21682)
		(width 0.1143)
		(layer "F.Cu")
		(net "FPGA_ASDO")
	)
	(segment
		(start 148.99767 -45.1612)
		(end 148.99767 -46.72457)
		(width 0.1143)
		(layer "F.Cu")
		(net "FPGA_ASDO")
	)
	(segment
		(start 87.838788 -34.757614)
		(end 87.838788 -34.365692)
		(width 0.1143)
		(layer "F.Cu")
		(net "BD_REV_1")
	)
	(segment
		(start 87.838788 -34.365692)
		(end 88.300814 -33.903666)
		(width 0.1143)
		(layer "F.Cu")
		(net "BD_REV_1")
	)
	(via
		(at 88.300814 -33.903666)
		(size 0.4318)
		(drill 0.2032)
		(layers "F.Cu" "B.Cu")
		(net "BD_REV_1")
	)
	(via
		(at 88.0364 -31.9024)
		(size 0.7112)
		(drill 0.3556)
		(layers "F.Cu" "B.Cu")
		(net "BD_REV_1")
	)
	(segment
		(start 88.38438 -32.69234)
		(end 88.38438 -33.8201)
		(width 0.1143)
		(layer "B.Cu")
		(net "BD_REV_1")
	)
	(segment
		(start 88.232234 -31.453328)
		(end 88.232234 -31.706566)
		(width 0.1143)
		(layer "B.Cu")
		(net "BD_REV_1")
	)
	(segment
		(start 87.45474 -27.999944)
		(end 87.619332 -27.999944)
		(width 0.1143)
		(layer "B.Cu")
		(net "BD_REV_1")
	)
	(segment
		(start 88.38438 -33.8201)
		(end 88.300814 -33.903666)
		(width 0.1143)
		(layer "B.Cu")
		(net "BD_REV_1")
	)
	(segment
		(start 88.0364 -31.9024)
		(end 88.0364 -32.34436)
		(width 0.1143)
		(layer "B.Cu")
		(net "BD_REV_1")
	)
	(segment
		(start 88.265 -33.93948)
		(end 88.300814 -33.903666)
		(width 0.1143)
		(layer "B.Cu")
		(net "BD_REV_1")
	)
	(segment
		(start 88.62695 -29.007562)
		(end 88.62695 -31.058612)
		(width 0.1143)
		(layer "B.Cu")
		(net "BD_REV_1")
	)
	(segment
		(start 88.0364 -32.34436)
		(end 88.38438 -32.69234)
		(width 0.1143)
		(layer "B.Cu")
		(net "BD_REV_1")
	)
	(segment
		(start 88.265 -34.5186)
		(end 88.265 -33.93948)
		(width 0.1143)
		(layer "B.Cu")
		(net "BD_REV_1")
	)
	(segment
		(start 88.62695 -31.058612)
		(end 88.232234 -31.453328)
		(width 0.1143)
		(layer "B.Cu")
		(net "BD_REV_1")
	)
	(segment
		(start 86.82736 -26.50236)
		(end 87.0966 -26.7716)
		(width 0.1143)
		(layer "B.Cu")
		(net "BD_REV_1")
	)
	(segment
		(start 88.232234 -31.706566)
		(end 88.0364 -31.9024)
		(width 0.1143)
		(layer "B.Cu")
		(net "BD_REV_1")
	)
	(segment
		(start 87.0966 -26.7716)
		(end 87.0966 -27.641804)
		(width 0.1143)
		(layer "B.Cu")
		(net "BD_REV_1")
	)
	(segment
		(start 87.0966 -27.641804)
		(end 87.45474 -27.999944)
		(width 0.1143)
		(layer "B.Cu")
		(net "BD_REV_1")
	)
	(segment
		(start 87.619332 -27.999944)
		(end 88.62695 -29.007562)
		(width 0.1143)
		(layer "B.Cu")
		(net "BD_REV_1")
	)
	(segment
		(start 88.00973 -33.061656)
		(end 88.00973 -33.02)
		(width 0.1143)
		(layer "F.Cu")
		(net "BD_REV_2")
	)
	(segment
		(start 88.374728 -33.426654)
		(end 88.00973 -33.061656)
		(width 0.1143)
		(layer "F.Cu")
		(net "BD_REV_2")
	)
	(via
		(at 88.00973 -33.02)
		(size 0.4318)
		(drill 0.2032)
		(layers "F.Cu" "B.Cu")
		(net "BD_REV_2")
	)
	(via
		(at 85.4202 -26.3398)
		(size 0.7112)
		(drill 0.3556)
		(layers "F.Cu" "B.Cu")
		(net "BD_REV_2")
	)
	(segment
		(start 87.49665 -31.678626)
		(end 87.49665 -32.36595)
		(width 0.1143)
		(layer "B.Cu")
		(net "BD_REV_2")
	)
	(segment
		(start 85.4202 -26.3398)
		(end 85.90534 -26.3398)
		(width 0.1143)
		(layer "B.Cu")
		(net "BD_REV_2")
	)
	(segment
		(start 87.49665 -32.36595)
		(end 88.00973 -32.87903)
		(width 0.1143)
		(layer "B.Cu")
		(net "BD_REV_2")
	)
	(segment
		(start 88.41105 -29.097224)
		(end 88.41105 -30.914594)
		(width 0.1143)
		(layer "B.Cu")
		(net "BD_REV_2")
	)
	(segment
		(start 87.962994 -31.36265)
		(end 87.812626 -31.36265)
		(width 0.1143)
		(layer "B.Cu")
		(net "BD_REV_2")
	)
	(segment
		(start 84.201 -27.051)
		(end 84.532978 -26.719022)
		(width 0.1143)
		(layer "B.Cu")
		(net "BD_REV_2")
	)
	(segment
		(start 88.41105 -30.914594)
		(end 87.962994 -31.36265)
		(width 0.1143)
		(layer "B.Cu")
		(net "BD_REV_2")
	)
	(segment
		(start 87.365078 -28.215844)
		(end 87.52967 -28.215844)
		(width 0.1143)
		(layer "B.Cu")
		(net "BD_REV_2")
	)
	(segment
		(start 84.532978 -26.719022)
		(end 85.040978 -26.719022)
		(width 0.1143)
		(layer "B.Cu")
		(net "BD_REV_2")
	)
	(segment
		(start 86.8807 -27.731466)
		(end 87.365078 -28.215844)
		(width 0.1143)
		(layer "B.Cu")
		(net "BD_REV_2")
	)
	(segment
		(start 87.52967 -28.215844)
		(end 88.41105 -29.097224)
		(width 0.1143)
		(layer "B.Cu")
		(net "BD_REV_2")
	)
	(segment
		(start 85.90534 -26.3398)
		(end 86.8807 -27.31516)
		(width 0.1143)
		(layer "B.Cu")
		(net "BD_REV_2")
	)
	(segment
		(start 82.5754 -27.051)
		(end 81.7118 -27.051)
		(width 0.1143)
		(layer "B.Cu")
		(net "BD_REV_2")
	)
	(segment
		(start 85.040978 -26.719022)
		(end 85.4202 -26.3398)
		(width 0.1143)
		(layer "B.Cu")
		(net "BD_REV_2")
	)
	(segment
		(start 86.8807 -27.31516)
		(end 86.8807 -27.731466)
		(width 0.1143)
		(layer "B.Cu")
		(net "BD_REV_2")
	)
	(segment
		(start 82.5754 -27.051)
		(end 84.201 -27.051)
		(width 0.1143)
		(layer "B.Cu")
		(net "BD_REV_2")
	)
	(segment
		(start 87.812626 -31.36265)
		(end 87.49665 -31.678626)
		(width 0.1143)
		(layer "B.Cu")
		(net "BD_REV_2")
	)
	(segment
		(start 88.00973 -32.87903)
		(end 88.00973 -33.02)
		(width 0.1143)
		(layer "B.Cu")
		(net "BD_REV_2")
	)
	(segment
		(start 89.659968 -32.283654)
		(end 88.908128 -31.531814)
		(width 0.1143)
		(layer "F.Cu")
		(net "BD_REV_0")
	)
	(segment
		(start 88.908128 -31.531814)
		(end 88.683846 -31.531814)
		(width 0.1143)
		(layer "F.Cu")
		(net "BD_REV_0")
	)
	(via
		(at 88.683846 -31.531814)
		(size 0.4318)
		(drill 0.2032)
		(layers "F.Cu" "B.Cu")
		(net "BD_REV_0")
	)
	(via
		(at 87.64016 -27.42184)
		(size 0.7112)
		(drill 0.3556)
		(layers "F.Cu" "B.Cu")
		(net "BD_REV_0")
	)
	(segment
		(start 88.683846 -31.307278)
		(end 88.683846 -31.531814)
		(width 0.1143)
		(layer "B.Cu")
		(net "BD_REV_0")
	)
	(segment
		(start 89.17305 -32.021018)
		(end 89.17305 -32.56915)
		(width 0.1143)
		(layer "B.Cu")
		(net "BD_REV_0")
	)
	(segment
		(start 87.64016 -27.71521)
		(end 88.84285 -28.9179)
		(width 0.1143)
		(layer "B.Cu")
		(net "BD_REV_0")
	)
	(segment
		(start 89.17305 -32.56915)
		(end 88.9 -32.8422)
		(width 0.1143)
		(layer "B.Cu")
		(net "BD_REV_0")
	)
	(segment
		(start 87.58936 -27.37104)
		(end 87.64016 -27.42184)
		(width 0.1143)
		(layer "B.Cu")
		(net "BD_REV_0")
	)
	(segment
		(start 88.683846 -31.531814)
		(end 89.17305 -32.021018)
		(width 0.1143)
		(layer "B.Cu")
		(net "BD_REV_0")
	)
	(segment
		(start 87.58936 -26.50236)
		(end 87.58936 -27.37104)
		(width 0.1143)
		(layer "B.Cu")
		(net "BD_REV_0")
	)
	(segment
		(start 88.84285 -28.9179)
		(end 88.84285 -31.148274)
		(width 0.1143)
		(layer "B.Cu")
		(net "BD_REV_0")
	)
	(segment
		(start 88.84285 -31.148274)
		(end 88.683846 -31.307278)
		(width 0.1143)
		(layer "B.Cu")
		(net "BD_REV_0")
	)
	(segment
		(start 87.64016 -27.42184)
		(end 87.64016 -27.71521)
		(width 0.1143)
		(layer "B.Cu")
		(net "BD_REV_0")
	)
	(segment
		(start 83.647788 -33.472374)
		(end 83.617054 -33.472374)
		(width 0.1143)
		(layer "F.Cu")
		(net "GBE_SDP0")
	)
	(segment
		(start 83.617054 -33.472374)
		(end 83.274916 -33.130236)
		(width 0.1143)
		(layer "F.Cu")
		(net "GBE_SDP0")
	)
	(via
		(at 83.274916 -33.130236)
		(size 0.4318)
		(drill 0.2032)
		(layers "F.Cu" "B.Cu")
		(net "GBE_SDP0")
	)
	(segment
		(start 78.8162 -28.702)
		(end 75.914504 -25.800304)
		(width 0.1143)
		(layer "B.Cu")
		(net "GBE_SDP0")
	)
	(segment
		(start 75.914504 -25.800304)
		(end 72.396096 -25.800304)
		(width 0.1143)
		(layer "B.Cu")
		(net "GBE_SDP0")
	)
	(segment
		(start 79.4766 -29.270198)
		(end 79.4766 -28.9052)
		(width 0.1143)
		(layer "B.Cu")
		(net "GBE_SDP0")
	)
	(segment
		(start 83.274916 -33.130236)
		(end 83.037172 -32.892492)
		(width 0.1143)
		(layer "B.Cu")
		(net "GBE_SDP0")
	)
	(segment
		(start 71.952866 -26.243534)
		(end 70.8914 -27.305)
		(width 0.1143)
		(layer "B.Cu")
		(net "GBE_SDP0")
	)
	(segment
		(start 82.573114 -31.7246)
		(end 82.123788 -31.7246)
		(width 0.1143)
		(layer "B.Cu")
		(net "GBE_SDP0")
	)
	(segment
		(start 70.8914 -27.305)
		(end 70.739 -27.305)
		(width 0.1143)
		(layer "B.Cu")
		(net "GBE_SDP0")
	)
	(segment
		(start 83.037172 -32.188658)
		(end 82.573114 -31.7246)
		(width 0.1143)
		(layer "B.Cu")
		(net "GBE_SDP0")
	)
	(segment
		(start 79.4766 -28.9052)
		(end 79.2734 -28.702)
		(width 0.1143)
		(layer "B.Cu")
		(net "GBE_SDP0")
	)
	(segment
		(start 79.2734 -28.702)
		(end 78.8162 -28.702)
		(width 0.1143)
		(layer "B.Cu")
		(net "GBE_SDP0")
	)
	(segment
		(start 83.037172 -32.892492)
		(end 83.037172 -32.188658)
		(width 0.1143)
		(layer "B.Cu")
		(net "GBE_SDP0")
	)
	(segment
		(start 72.396096 -25.800304)
		(end 71.952866 -26.243534)
		(width 0.1143)
		(layer "B.Cu")
		(net "GBE_SDP0")
	)
	(segment
		(start 80.686402 -30.48)
		(end 79.4766 -29.270198)
		(width 0.1143)
		(layer "B.Cu")
		(net "GBE_SDP0")
	)
	(segment
		(start 80.879188 -30.48)
		(end 80.686402 -30.48)
		(width 0.1143)
		(layer "B.Cu")
		(net "GBE_SDP0")
	)
	(segment
		(start 82.123788 -31.7246)
		(end 80.879188 -30.48)
		(width 0.1143)
		(layer "B.Cu")
		(net "GBE_SDP0")
	)
	(segment
		(start 152.379934 -53.73624)
		(end 151.5999 -53.73624)
		(width 0.1143)
		(layer "F.Cu")
		(net "SPI_SW_RST#")
	)
	(segment
		(start 153.16835 -52.947824)
		(end 152.379934 -53.73624)
		(width 0.1143)
		(layer "F.Cu")
		(net "SPI_SW_RST#")
	)
	(segment
		(start 153.16835 -51.6763)
		(end 153.16835 -52.947824)
		(width 0.1143)
		(layer "F.Cu")
		(net "SPI_SW_RST#")
	)
	(segment
		(start 153.1112 -51.61915)
		(end 153.16835 -51.6763)
		(width 0.1143)
		(layer "F.Cu")
		(net "SPI_SW_RST#")
	)
	(via
		(at 153.1112 -51.61915)
		(size 0.508)
		(drill 0.254)
		(layers "F.Cu" "B.Cu")
		(net "SPI_SW_RST#")
	)
	(via
		(at 176.276 -44.45)
		(size 0.7112)
		(drill 0.3556)
		(layers "F.Cu" "B.Cu")
		(net "SPI_SW_RST#")
	)
	(segment
		(start 171.145454 -47.912274)
		(end 171.29633 -48.06315)
		(width 0.1143)
		(layer "B.Cu")
		(net "SPI_SW_RST#")
	)
	(segment
		(start 153.17978 -51.55057)
		(end 155.726384 -51.55057)
		(width 0.1143)
		(layer "B.Cu")
		(net "SPI_SW_RST#")
	)
	(segment
		(start 155.726384 -51.55057)
		(end 158.020004 -49.25695)
		(width 0.1143)
		(layer "B.Cu")
		(net "SPI_SW_RST#")
	)
	(segment
		(start 177.292 -42.9768)
		(end 176.3014 -42.9768)
		(width 0.1143)
		(layer "B.Cu")
		(net "SPI_SW_RST#")
	)
	(segment
		(start 166.526464 -47.912274)
		(end 171.145454 -47.912274)
		(width 0.1143)
		(layer "B.Cu")
		(net "SPI_SW_RST#")
	)
	(segment
		(start 175.7934 -46.883828)
		(end 175.7934 -45.5168)
		(width 0.1143)
		(layer "B.Cu")
		(net "SPI_SW_RST#")
	)
	(segment
		(start 171.29633 -48.06315)
		(end 174.613824 -48.06315)
		(width 0.1143)
		(layer "B.Cu")
		(net "SPI_SW_RST#")
	)
	(segment
		(start 177.292 -42.9768)
		(end 178.054 -42.9768)
		(width 0.1143)
		(layer "B.Cu")
		(net "SPI_SW_RST#")
	)
	(segment
		(start 175.640492 -47.036482)
		(end 175.7934 -46.883828)
		(width 0.1143)
		(layer "B.Cu")
		(net "SPI_SW_RST#")
	)
	(segment
		(start 176.276 -45.0342)
		(end 176.276 -44.45)
		(width 0.1143)
		(layer "B.Cu")
		(net "SPI_SW_RST#")
	)
	(segment
		(start 158.020004 -49.25695)
		(end 165.181788 -49.25695)
		(width 0.1143)
		(layer "B.Cu")
		(net "SPI_SW_RST#")
	)
	(segment
		(start 153.1112 -51.61915)
		(end 153.17978 -51.55057)
		(width 0.1143)
		(layer "B.Cu")
		(net "SPI_SW_RST#")
	)
	(segment
		(start 175.7934 -45.5168)
		(end 176.276 -45.0342)
		(width 0.1143)
		(layer "B.Cu")
		(net "SPI_SW_RST#")
	)
	(segment
		(start 176.276 -42.9514)
		(end 176.276 -44.45)
		(width 0.1143)
		(layer "B.Cu")
		(net "SPI_SW_RST#")
	)
	(segment
		(start 165.181788 -49.25695)
		(end 166.526464 -47.912274)
		(width 0.1143)
		(layer "B.Cu")
		(net "SPI_SW_RST#")
	)
	(segment
		(start 176.3014 -42.9768)
		(end 176.276 -42.9514)
		(width 0.1143)
		(layer "B.Cu")
		(net "SPI_SW_RST#")
	)
	(segment
		(start 174.613824 -48.06315)
		(end 175.640492 -47.036482)
		(width 0.1143)
		(layer "B.Cu")
		(net "SPI_SW_RST#")
	)
	(segment
		(start 143.686784 -56.132984)
		(end 144.907762 -56.132984)
		(width 0.1143)
		(layer "F.Cu")
		(net "SPI_SW_INT#")
	)
	(segment
		(start 145.161 -56.386222)
		(end 145.161 -56.73217)
		(width 0.1143)
		(layer "F.Cu")
		(net "SPI_SW_INT#")
	)
	(segment
		(start 142.7988 -55.245)
		(end 141.0462 -55.245)
		(width 0.1143)
		(layer "F.Cu")
		(net "SPI_SW_INT#")
	)
	(segment
		(start 144.907762 -56.132984)
		(end 145.161 -56.386222)
		(width 0.1143)
		(layer "F.Cu")
		(net "SPI_SW_INT#")
	)
	(segment
		(start 145.415 -56.98617)
		(end 146.0881 -56.98617)
		(width 0.1143)
		(layer "F.Cu")
		(net "SPI_SW_INT#")
	)
	(segment
		(start 142.8242 -55.2704)
		(end 143.686784 -56.132984)
		(width 0.1143)
		(layer "F.Cu")
		(net "SPI_SW_INT#")
	)
	(segment
		(start 145.161 -56.73217)
		(end 145.415 -56.98617)
		(width 0.1143)
		(layer "F.Cu")
		(net "SPI_SW_INT#")
	)
	(segment
		(start 142.8242 -55.2704)
		(end 142.7988 -55.245)
		(width 0.1143)
		(layer "F.Cu")
		(net "SPI_SW_INT#")
	)
	(via
		(at 142.8242 -55.2704)
		(size 0.7112)
		(drill 0.3556)
		(layers "F.Cu" "B.Cu")
		(net "SPI_SW_INT#")
	)
	(segment
		(start 144.89303 -52.43703)
		(end 146.0881 -52.43703)
		(width 0.1143)
		(layer "F.Cu")
		(net "SPI_SW_ADDR2")
	)
	(segment
		(start 141.21765 -50.79365)
		(end 141.0208 -50.5968)
		(width 0.1143)
		(layer "F.Cu")
		(net "SPI_SW_ADDR2")
	)
	(segment
		(start 143.377412 -51.569874)
		(end 142.601188 -50.79365)
		(width 0.1143)
		(layer "F.Cu")
		(net "SPI_SW_ADDR2")
	)
	(segment
		(start 143.695166 -51.569874)
		(end 144.025874 -51.569874)
		(width 0.1143)
		(layer "F.Cu")
		(net "SPI_SW_ADDR2")
	)
	(segment
		(start 144.025874 -51.569874)
		(end 144.89303 -52.43703)
		(width 0.1143)
		(layer "F.Cu")
		(net "SPI_SW_ADDR2")
	)
	(segment
		(start 142.601188 -50.79365)
		(end 141.21765 -50.79365)
		(width 0.1143)
		(layer "F.Cu")
		(net "SPI_SW_ADDR2")
	)
	(segment
		(start 143.695166 -51.569874)
		(end 143.377412 -51.569874)
		(width 0.1143)
		(layer "F.Cu")
		(net "SPI_SW_ADDR2")
	)
	(via
		(at 143.695166 -51.569874)
		(size 0.7112)
		(drill 0.3556)
		(layers "F.Cu" "B.Cu")
		(net "SPI_SW_ADDR2")
	)
	(segment
		(start 141.0208 -51.3588)
		(end 142.367 -51.3588)
		(width 0.1143)
		(layer "F.Cu")
		(net "SPI_SW_ADDR1")
	)
	(segment
		(start 142.367 -51.3588)
		(end 142.5956 -51.3588)
		(width 0.1143)
		(layer "F.Cu")
		(net "SPI_SW_ADDR1")
	)
	(segment
		(start 142.5956 -51.3588)
		(end 144.3228 -53.086)
		(width 0.1143)
		(layer "F.Cu")
		(net "SPI_SW_ADDR1")
	)
	(segment
		(start 144.3228 -53.086)
		(end 146.0881 -53.086)
		(width 0.1143)
		(layer "F.Cu")
		(net "SPI_SW_ADDR1")
	)
	(via
		(at 142.367 -51.3588)
		(size 0.7112)
		(drill 0.3556)
		(layers "F.Cu" "B.Cu")
		(net "SPI_SW_ADDR1")
	)
	(segment
		(start 144.100296 -53.73624)
		(end 144.399 -53.73624)
		(width 0.1143)
		(layer "F.Cu")
		(net "SPI_SW_ADDR0")
	)
	(segment
		(start 141.0208 -52.1208)
		(end 142.484856 -52.1208)
		(width 0.1143)
		(layer "F.Cu")
		(net "SPI_SW_ADDR0")
	)
	(segment
		(start 144.399 -53.73624)
		(end 146.0881 -53.73624)
		(width 0.1143)
		(layer "F.Cu")
		(net "SPI_SW_ADDR0")
	)
	(segment
		(start 142.484856 -52.1208)
		(end 144.100296 -53.73624)
		(width 0.1143)
		(layer "F.Cu")
		(net "SPI_SW_ADDR0")
	)
	(via
		(at 144.399 -53.73624)
		(size 0.7112)
		(drill 0.3556)
		(layers "F.Cu" "B.Cu")
		(net "SPI_SW_ADDR0")
	)
	(segment
		(start 152.3746 -53.086)
		(end 151.5999 -53.086)
		(width 0.1143)
		(layer "F.Cu")
		(net "SPI_SW_NCONFIG#")
	)
	(segment
		(start 152.7048 -52.7558)
		(end 152.3746 -53.086)
		(width 0.1143)
		(layer "F.Cu")
		(net "SPI_SW_NCONFIG#")
	)
	(segment
		(start 138.8364 -51.9684)
		(end 138.8364 -52.832)
		(width 0.1143)
		(layer "F.Cu")
		(net "SPI_SW_NCONFIG#")
	)
	(segment
		(start 138.8364 -52.832)
		(end 139.2682 -53.2638)
		(width 0.1143)
		(layer "F.Cu")
		(net "SPI_SW_NCONFIG#")
	)
	(via
		(at 139.2682 -53.2638)
		(size 0.508)
		(drill 0.254)
		(layers "F.Cu" "B.Cu")
		(net "SPI_SW_NCONFIG#")
	)
	(via
		(at 140.253212 -52.278788)
		(size 0.7112)
		(drill 0.3556)
		(layers "F.Cu" "B.Cu")
		(net "SPI_SW_NCONFIG#")
	)
	(via
		(at 152.7048 -52.7558)
		(size 0.508)
		(drill 0.254)
		(layers "F.Cu" "B.Cu")
		(net "SPI_SW_NCONFIG#")
	)
	(segment
		(start 139.2682 -53.2638)
		(end 140.253212 -52.278788)
		(width 0.1143)
		(layer "B.Cu")
		(net "SPI_SW_NCONFIG#")
	)
	(segment
		(start 151.27605 -51.83505)
		(end 152.1968 -52.7558)
		(width 0.1143)
		(layer "B.Cu")
		(net "SPI_SW_NCONFIG#")
	)
	(segment
		(start 140.253212 -52.278788)
		(end 140.69695 -51.83505)
		(width 0.1143)
		(layer "B.Cu")
		(net "SPI_SW_NCONFIG#")
	)
	(segment
		(start 152.1968 -52.7558)
		(end 152.7048 -52.7558)
		(width 0.1143)
		(layer "B.Cu")
		(net "SPI_SW_NCONFIG#")
	)
	(segment
		(start 140.69695 -51.83505)
		(end 151.27605 -51.83505)
		(width 0.1143)
		(layer "B.Cu")
		(net "SPI_SW_NCONFIG#")
	)
	(segment
		(start 65.4812 -22.0472)
		(end 65.4812 -21.2344)
		(width 0.1143)
		(layer "B.Cu")
		(net "MSATA_ACT#")
	)
	(segment
		(start 65.768474 -22.334474)
		(end 65.4812 -22.0472)
		(width 0.1143)
		(layer "B.Cu")
		(net "MSATA_ACT#")
	)
	(segment
		(start 67.437 -22.334474)
		(end 65.768474 -22.334474)
		(width 0.1143)
		(layer "B.Cu")
		(net "MSATA_ACT#")
	)
	(segment
		(start 63.946532 -21.100034)
		(end 65.346834 -21.100034)
		(width 0.1143)
		(layer "B.Cu")
		(net "MSATA_ACT#")
	)
	(segment
		(start 65.346834 -21.100034)
		(end 65.4812 -21.2344)
		(width 0.1143)
		(layer "B.Cu")
		(net "MSATA_ACT#")
	)
	(segment
		(start 165.8366 -54.102)
		(end 167.1066 -52.832)
		(width 0.1143)
		(layer "F.Cu")
		(net "C_R_DATA0")
	)
	(segment
		(start 168.021 -52.832)
		(end 167.1066 -52.832)
		(width 0.1143)
		(layer "F.Cu")
		(net "C_R_DATA0")
	)
	(segment
		(start 164.874194 -54.102)
		(end 165.8366 -54.102)
		(width 0.1143)
		(layer "F.Cu")
		(net "C_R_DATA0")
	)
	(via
		(at 167.1066 -52.832)
		(size 0.7112)
		(drill 0.3556)
		(layers "F.Cu" "B.Cu")
		(net "C_R_DATA0")
	)
	(segment
		(start 165.831266 -52.832)
		(end 167.253666 -51.4096)
		(width 0.1143)
		(layer "F.Cu")
		(net "C_R_CSO#")
	)
	(segment
		(start 168.021 -52.07)
		(end 168.021 -51.5366)
		(width 0.1143)
		(layer "F.Cu")
		(net "C_R_CSO#")
	)
	(segment
		(start 167.894 -51.4096)
		(end 167.253666 -51.4096)
		(width 0.1143)
		(layer "F.Cu")
		(net "C_R_CSO#")
	)
	(segment
		(start 164.874194 -52.832)
		(end 165.831266 -52.832)
		(width 0.1143)
		(layer "F.Cu")
		(net "C_R_CSO#")
	)
	(segment
		(start 168.021 -51.5366)
		(end 167.894 -51.4096)
		(width 0.1143)
		(layer "F.Cu")
		(net "C_R_CSO#")
	)
	(via
		(at 167.253666 -51.4096)
		(size 0.7112)
		(drill 0.3556)
		(layers "F.Cu" "B.Cu")
		(net "C_R_CSO#")
	)
	(segment
		(start 158.877 -55.372)
		(end 157.353 -53.848)
		(width 0.1143)
		(layer "F.Cu")
		(net "C_R_DCLK")
	)
	(segment
		(start 157.353 -53.848)
		(end 155.448 -53.848)
		(width 0.1143)
		(layer "F.Cu")
		(net "C_R_DCLK")
	)
	(segment
		(start 155.448 -53.0098)
		(end 155.575 -52.8828)
		(width 0.1143)
		(layer "F.Cu")
		(net "C_R_DCLK")
	)
	(segment
		(start 155.448 -53.848)
		(end 155.448 -53.0098)
		(width 0.1143)
		(layer "F.Cu")
		(net "C_R_DCLK")
	)
	(segment
		(start 159.229806 -55.372)
		(end 158.877 -55.372)
		(width 0.1143)
		(layer "F.Cu")
		(net "C_R_DCLK")
	)
	(via
		(at 155.448 -53.848)
		(size 0.7112)
		(drill 0.3556)
		(layers "F.Cu" "B.Cu")
		(net "C_R_DCLK")
	)
	(segment
		(start 157.988 -56.642)
		(end 159.229806 -56.642)
		(width 0.1143)
		(layer "F.Cu")
		(net "C_R_ASDO")
	)
	(segment
		(start 156.959046 -55.245)
		(end 157.086046 -55.118)
		(width 0.1143)
		(layer "F.Cu")
		(net "C_R_ASDO")
	)
	(segment
		(start 157.861 -56.515)
		(end 157.988 -56.642)
		(width 0.1143)
		(layer "F.Cu")
		(net "C_R_ASDO")
	)
	(segment
		(start 156.959046 -56.8452)
		(end 156.959046 -55.245)
		(width 0.1143)
		(layer "F.Cu")
		(net "C_R_ASDO")
	)
	(segment
		(start 154.305 -56.769)
		(end 154.432 -56.896)
		(width 0.1143)
		(layer "F.Cu")
		(net "C_R_ASDO")
	)
	(segment
		(start 157.734 -55.118)
		(end 157.861 -55.245)
		(width 0.1143)
		(layer "F.Cu")
		(net "C_R_ASDO")
	)
	(segment
		(start 157.086046 -55.118)
		(end 157.734 -55.118)
		(width 0.1143)
		(layer "F.Cu")
		(net "C_R_ASDO")
	)
	(segment
		(start 154.8892 -55.8038)
		(end 154.305 -56.388)
		(width 0.1143)
		(layer "F.Cu")
		(net "C_R_ASDO")
	)
	(segment
		(start 154.432 -56.896)
		(end 156.908246 -56.896)
		(width 0.1143)
		(layer "F.Cu")
		(net "C_R_ASDO")
	)
	(segment
		(start 157.861 -55.245)
		(end 157.861 -56.515)
		(width 0.1143)
		(layer "F.Cu")
		(net "C_R_ASDO")
	)
	(segment
		(start 156.908246 -56.896)
		(end 156.959046 -56.8452)
		(width 0.1143)
		(layer "F.Cu")
		(net "C_R_ASDO")
	)
	(segment
		(start 154.305 -56.388)
		(end 154.305 -56.769)
		(width 0.1143)
		(layer "F.Cu")
		(net "C_R_ASDO")
	)
	(segment
		(start 155.575 -55.8038)
		(end 154.8892 -55.8038)
		(width 0.1143)
		(layer "F.Cu")
		(net "C_R_ASDO")
	)
	(via
		(at 156.959046 -56.8452)
		(size 0.7112)
		(drill 0.3556)
		(layers "F.Cu" "B.Cu")
		(net "C_R_ASDO")
	)
	(segment
		(start 79.121 -63.927482)
		(end 79.121 -65.4812)
		(width 0.127)
		(layer "F.Cu")
		(net "VOL1_SEN_ADDR1")
	)
	(segment
		(start 77.99832 -61.76772)
		(end 78.6638 -62.4332)
		(width 0.127)
		(layer "F.Cu")
		(net "VOL1_SEN_ADDR1")
	)
	(segment
		(start 76.8731 -61.76772)
		(end 77.99832 -61.76772)
		(width 0.127)
		(layer "F.Cu")
		(net "VOL1_SEN_ADDR1")
	)
	(segment
		(start 78.6638 -63.470282)
		(end 79.121 -63.927482)
		(width 0.127)
		(layer "F.Cu")
		(net "VOL1_SEN_ADDR1")
	)
	(segment
		(start 78.6638 -62.4332)
		(end 78.6638 -63.470282)
		(width 0.127)
		(layer "F.Cu")
		(net "VOL1_SEN_ADDR1")
	)
	(segment
		(start 79.883 -65.4812)
		(end 79.121 -65.4812)
		(width 0.127)
		(layer "F.Cu")
		(net "VOL1_SEN_ADDR1")
	)
	(via
		(at 78.6638 -62.4332)
		(size 0.7112)
		(drill 0.3556)
		(layers "F.Cu" "B.Cu")
		(net "VOL1_SEN_ADDR1")
	)
	(segment
		(start 81.026 -65.4812)
		(end 80.5561 -65.0113)
		(width 0.127)
		(layer "F.Cu")
		(net "VOL1_SEN_ADDR0")
	)
	(segment
		(start 79.6544 -63.6524)
		(end 79.502 -63.5)
		(width 0.127)
		(layer "F.Cu")
		(net "VOL1_SEN_ADDR0")
	)
	(segment
		(start 80.5561 -65.0113)
		(end 79.942182 -65.0113)
		(width 0.127)
		(layer "F.Cu")
		(net "VOL1_SEN_ADDR0")
	)
	(segment
		(start 79.942182 -65.0113)
		(end 79.6544 -64.723518)
		(width 0.127)
		(layer "F.Cu")
		(net "VOL1_SEN_ADDR0")
	)
	(segment
		(start 76.8731 -61.11748)
		(end 78.23708 -61.11748)
		(width 0.127)
		(layer "F.Cu")
		(net "VOL1_SEN_ADDR0")
	)
	(segment
		(start 78.23708 -61.11748)
		(end 79.502 -62.3824)
		(width 0.127)
		(layer "F.Cu")
		(net "VOL1_SEN_ADDR0")
	)
	(segment
		(start 81.788 -65.4812)
		(end 81.026 -65.4812)
		(width 0.127)
		(layer "F.Cu")
		(net "VOL1_SEN_ADDR0")
	)
	(segment
		(start 79.502 -62.3824)
		(end 79.502 -63.5)
		(width 0.127)
		(layer "F.Cu")
		(net "VOL1_SEN_ADDR0")
	)
	(segment
		(start 79.6544 -64.723518)
		(end 79.6544 -63.6524)
		(width 0.127)
		(layer "F.Cu")
		(net "VOL1_SEN_ADDR0")
	)
	(via
		(at 79.502 -63.5)
		(size 0.7112)
		(drill 0.3556)
		(layers "F.Cu" "B.Cu")
		(net "VOL1_SEN_ADDR0")
	)
	(segment
		(start 76.8731 -59.817)
		(end 78.5368 -59.817)
		(width 0.127)
		(layer "F.Cu")
		(net "VOL1_SEN_VREF")
	)
	(segment
		(start 78.867 -59.4868)
		(end 79.6544 -59.4868)
		(width 0.127)
		(layer "F.Cu")
		(net "VOL1_SEN_VREF")
	)
	(segment
		(start 79.6544 -59.4868)
		(end 79.7814 -59.3598)
		(width 0.127)
		(layer "F.Cu")
		(net "VOL1_SEN_VREF")
	)
	(segment
		(start 78.5368 -59.817)
		(end 78.867 -59.4868)
		(width 0.127)
		(layer "F.Cu")
		(net "VOL1_SEN_VREF")
	)
	(via
		(at 79.7814 -59.3598)
		(size 0.7112)
		(drill 0.3556)
		(layers "F.Cu" "B.Cu")
		(net "VOL1_SEN_VREF")
	)
	(segment
		(start 75.389994 -66.900044)
		(end 73.255124 -66.900044)
		(width 1.016)
		(layer "F.Cu")
		(net "DYMMY_NET1")
	)
	(segment
		(start 73.255124 -66.900044)
		(end 72.743822 -67.411346)
		(width 1.016)
		(layer "F.Cu")
		(net "DYMMY_NET1")
	)
	(segment
		(start 72.743822 -67.411346)
		(end 70.821296 -67.411346)
		(width 1.016)
		(layer "F.Cu")
		(net "DYMMY_NET1")
	)
	(segment
		(start 70.821296 -67.411346)
		(end 70.309994 -66.900044)
		(width 1.016)
		(layer "F.Cu")
		(net "DYMMY_NET1")
	)
	(segment
		(start 73.255124 -66.900044)
		(end 72.743822 -67.411346)
		(width 1.016)
		(layer "In4.Cu")
		(net "DYMMY_NET1")
	)
	(segment
		(start 70.821296 -67.411346)
		(end 70.309994 -66.900044)
		(width 1.016)
		(layer "In4.Cu")
		(net "DYMMY_NET1")
	)
	(segment
		(start 72.743822 -67.411346)
		(end 70.821296 -67.411346)
		(width 1.016)
		(layer "In4.Cu")
		(net "DYMMY_NET1")
	)
	(segment
		(start 75.389994 -66.900044)
		(end 73.255124 -66.900044)
		(width 1.016)
		(layer "In4.Cu")
		(net "DYMMY_NET1")
	)
	(segment
		(start 70.821296 -67.411346)
		(end 72.771254 -67.411346)
		(width 1.016)
		(layer "In7.Cu")
		(net "DYMMY_NET1")
	)
	(segment
		(start 70.309994 -66.900044)
		(end 70.821296 -67.411346)
		(width 1.016)
		(layer "In7.Cu")
		(net "DYMMY_NET1")
	)
	(segment
		(start 73.1012 -67.0814)
		(end 75.208638 -67.0814)
		(width 1.016)
		(layer "In7.Cu")
		(net "DYMMY_NET1")
	)
	(segment
		(start 75.208638 -67.0814)
		(end 75.389994 -66.900044)
		(width 1.016)
		(layer "In7.Cu")
		(net "DYMMY_NET1")
	)
	(segment
		(start 72.771254 -67.411346)
		(end 73.1012 -67.0814)
		(width 1.016)
		(layer "In7.Cu")
		(net "DYMMY_NET1")
	)
	(segment
		(start 121.389902 -11.500104)
		(end 116.309902 -11.500104)
		(width 1.016)
		(layer "In2.Cu")
		(net "DYMMY_NET2")
	)
	(segment
		(start 121.389902 -11.500104)
		(end 116.309902 -11.500104)
		(width 1.016)
		(layer "In4.Cu")
		(net "DYMMY_NET2")
	)
	(segment
		(start 121.389902 -11.500104)
		(end 116.309902 -11.500104)
		(width 1.016)
		(layer "In9.Cu")
		(net "DYMMY_NET2")
	)
	(segment
		(start 30.77718 -20.5486)
		(end 29.845 -19.61642)
		(width 0.1143)
		(layer "F.Cu")
		(net "XDP_BUF_RTEST#")
	)
	(segment
		(start 87.533988 -37.444934)
		(end 87.884 -37.094922)
		(width 0.1143)
		(layer "F.Cu")
		(net "XDP_BUF_RTEST#")
	)
	(segment
		(start 29.845 -19.61642)
		(end 29.845 -18.410174)
		(width 0.1143)
		(layer "F.Cu")
		(net "XDP_BUF_RTEST#")
	)
	(segment
		(start 45.0088 -37.7698)
		(end 45.70984 -37.06876)
		(width 0.1143)
		(layer "F.Cu")
		(net "XDP_BUF_RTEST#")
	)
	(segment
		(start 29.845 -18.410174)
		(end 29.379926 -17.9451)
		(width 0.1143)
		(layer "F.Cu")
		(net "XDP_BUF_RTEST#")
	)
	(segment
		(start 45.70984 -37.06876)
		(end 45.84192 -37.06876)
		(width 0.1143)
		(layer "F.Cu")
		(net "XDP_BUF_RTEST#")
	)
	(segment
		(start 87.457788 -37.444934)
		(end 87.533988 -37.444934)
		(width 0.1143)
		(layer "F.Cu")
		(net "XDP_BUF_RTEST#")
	)
	(via
		(at 61.722 -13.97)
		(size 0.7112)
		(drill 0.3556)
		(layers "F.Cu" "B.Cu")
		(net "XDP_BUF_RTEST#")
	)
	(via
		(at 58.64225 -27.0002)
		(size 0.508)
		(drill 0.254)
		(layers "F.Cu" "B.Cu")
		(net "XDP_BUF_RTEST#")
	)
	(via
		(at 45.0088 -37.7698)
		(size 0.508)
		(drill 0.254)
		(layers "F.Cu" "B.Cu")
		(net "XDP_BUF_RTEST#")
	)
	(via
		(at 30.77718 -20.5486)
		(size 0.508)
		(drill 0.254)
		(layers "F.Cu" "B.Cu")
		(net "XDP_BUF_RTEST#")
	)
	(via
		(at 87.884 -37.094922)
		(size 0.4318)
		(drill 0.2032)
		(layers "F.Cu" "B.Cu")
		(net "XDP_BUF_RTEST#")
	)
	(segment
		(start 61.30925 -17.93875)
		(end 61.49975 -17.74825)
		(width 0.1143)
		(layer "B.Cu")
		(net "XDP_BUF_RTEST#")
	)
	(segment
		(start 61.55817 -19.160998)
		(end 61.30925 -18.912078)
		(width 0.1143)
		(layer "B.Cu")
		(net "XDP_BUF_RTEST#")
	)
	(segment
		(start 60.706 -22.606)
		(end 61.55817 -21.75383)
		(width 0.1143)
		(layer "B.Cu")
		(net "XDP_BUF_RTEST#")
	)
	(segment
		(start 58.64225 -27.0002)
		(end 58.64225 -26.70175)
		(width 0.1143)
		(layer "B.Cu")
		(net "XDP_BUF_RTEST#")
	)
	(segment
		(start 61.49975 -17.74825)
		(end 61.49975 -14.19225)
		(width 0.1143)
		(layer "B.Cu")
		(net "XDP_BUF_RTEST#")
	)
	(segment
		(start 60.706 -24.638)
		(end 60.706 -22.606)
		(width 0.1143)
		(layer "B.Cu")
		(net "XDP_BUF_RTEST#")
	)
	(segment
		(start 58.64225 -26.70175)
		(end 60.706 -24.638)
		(width 0.1143)
		(layer "B.Cu")
		(net "XDP_BUF_RTEST#")
	)
	(segment
		(start 61.55817 -21.75383)
		(end 61.55817 -19.160998)
		(width 0.1143)
		(layer "B.Cu")
		(net "XDP_BUF_RTEST#")
	)
	(segment
		(start 61.49975 -14.19225)
		(end 61.722 -13.97)
		(width 0.1143)
		(layer "B.Cu")
		(net "XDP_BUF_RTEST#")
	)
	(segment
		(start 61.30925 -18.912078)
		(end 61.30925 -17.93875)
		(width 0.1143)
		(layer "B.Cu")
		(net "XDP_BUF_RTEST#")
	)
	(segment
		(start 51.29149 -29.122116)
		(end 45.3898 -35.023806)
		(width 0.0889)
		(layer "In4.Cu")
		(net "XDP_BUF_RTEST#")
	)
	(segment
		(start 45.3898 -35.023806)
		(end 45.3898 -37.3888)
		(width 0.0889)
		(layer "In4.Cu")
		(net "XDP_BUF_RTEST#")
	)
	(segment
		(start 45.3898 -37.3888)
		(end 45.0088 -37.7698)
		(width 0.0889)
		(layer "In4.Cu")
		(net "XDP_BUF_RTEST#")
	)
	(segment
		(start 52.43195 -29.122116)
		(end 51.29149 -29.122116)
		(width 0.0889)
		(layer "In4.Cu")
		(net "XDP_BUF_RTEST#")
	)
	(segment
		(start 55.366666 -28.13685)
		(end 53.14315 -28.13685)
		(width 0.0889)
		(layer "In4.Cu")
		(net "XDP_BUF_RTEST#")
	)
	(segment
		(start 55.54345 -27.960066)
		(end 55.366666 -28.13685)
		(width 0.0889)
		(layer "In4.Cu")
		(net "XDP_BUF_RTEST#")
	)
	(segment
		(start 53.14315 -28.13685)
		(end 52.695856 -28.584144)
		(width 0.0889)
		(layer "In4.Cu")
		(net "XDP_BUF_RTEST#")
	)
	(segment
		(start 58.64225 -27.0002)
		(end 58.64225 -27.41676)
		(width 0.0889)
		(layer "In4.Cu")
		(net "XDP_BUF_RTEST#")
	)
	(segment
		(start 58.098944 -27.960066)
		(end 55.54345 -27.960066)
		(width 0.0889)
		(layer "In4.Cu")
		(net "XDP_BUF_RTEST#")
	)
	(segment
		(start 52.695856 -28.584144)
		(end 52.695856 -28.85821)
		(width 0.0889)
		(layer "In4.Cu")
		(net "XDP_BUF_RTEST#")
	)
	(segment
		(start 58.64225 -27.41676)
		(end 58.098944 -27.960066)
		(width 0.0889)
		(layer "In4.Cu")
		(net "XDP_BUF_RTEST#")
	)
	(segment
		(start 52.695856 -28.85821)
		(end 52.43195 -29.122116)
		(width 0.0889)
		(layer "In4.Cu")
		(net "XDP_BUF_RTEST#")
	)
	(segment
		(start 59.2709 -26.37155)
		(end 58.64225 -27.0002)
		(width 0.0889)
		(layer "In7.Cu")
		(net "XDP_BUF_RTEST#")
	)
	(segment
		(start 82.885534 -37.510974)
		(end 82.29854 -36.92398)
		(width 0.0889)
		(layer "In7.Cu")
		(net "XDP_BUF_RTEST#")
	)
	(segment
		(start 87.463122 -37.5158)
		(end 83.312 -37.5158)
		(width 0.0889)
		(layer "In7.Cu")
		(net "XDP_BUF_RTEST#")
	)
	(segment
		(start 79.277464 -36.92398)
		(end 76.4921 -34.138616)
		(width 0.0889)
		(layer "In7.Cu")
		(net "XDP_BUF_RTEST#")
	)
	(segment
		(start 61.67755 -27.64155)
		(end 60.40755 -26.37155)
		(width 0.0889)
		(layer "In7.Cu")
		(net "XDP_BUF_RTEST#")
	)
	(segment
		(start 39.468806 -32.7025)
		(end 44.536106 -37.7698)
		(width 0.0889)
		(layer "In7.Cu")
		(net "XDP_BUF_RTEST#")
	)
	(segment
		(start 71.681594 -30.0355)
		(end 67.3735 -30.0355)
		(width 0.0889)
		(layer "In7.Cu")
		(net "XDP_BUF_RTEST#")
	)
	(segment
		(start 44.536106 -37.7698)
		(end 45.0088 -37.7698)
		(width 0.0889)
		(layer "In7.Cu")
		(net "XDP_BUF_RTEST#")
	)
	(segment
		(start 73.63333 -29.61005)
		(end 72.107044 -29.61005)
		(width 0.0889)
		(layer "In7.Cu")
		(net "XDP_BUF_RTEST#")
	)
	(segment
		(start 31.848806 -22.3774)
		(end 34.843212 -22.3774)
		(width 0.0889)
		(layer "In7.Cu")
		(net "XDP_BUF_RTEST#")
	)
	(segment
		(start 38.713664 -32.7025)
		(end 39.468806 -32.7025)
		(width 0.0889)
		(layer "In7.Cu")
		(net "XDP_BUF_RTEST#")
	)
	(segment
		(start 83.307174 -37.510974)
		(end 82.885534 -37.510974)
		(width 0.0889)
		(layer "In7.Cu")
		(net "XDP_BUF_RTEST#")
	)
	(segment
		(start 60.40755 -26.37155)
		(end 59.2709 -26.37155)
		(width 0.0889)
		(layer "In7.Cu")
		(net "XDP_BUF_RTEST#")
	)
	(segment
		(start 30.7848 -21.313648)
		(end 31.848806 -22.3774)
		(width 0.0889)
		(layer "In7.Cu")
		(net "XDP_BUF_RTEST#")
	)
	(segment
		(start 34.843212 -22.3774)
		(end 37.134546 -24.668734)
		(width 0.0889)
		(layer "In7.Cu")
		(net "XDP_BUF_RTEST#")
	)
	(segment
		(start 83.312 -37.5158)
		(end 83.307174 -37.510974)
		(width 0.0889)
		(layer "In7.Cu")
		(net "XDP_BUF_RTEST#")
	)
	(segment
		(start 30.77718 -20.5486)
		(end 30.7848 -20.55622)
		(width 0.0889)
		(layer "In7.Cu")
		(net "XDP_BUF_RTEST#")
	)
	(segment
		(start 76.4921 -32.468566)
		(end 73.63333 -29.61005)
		(width 0.0889)
		(layer "In7.Cu")
		(net "XDP_BUF_RTEST#")
	)
	(segment
		(start 37.134546 -24.668734)
		(end 37.134546 -31.123382)
		(width 0.0889)
		(layer "In7.Cu")
		(net "XDP_BUF_RTEST#")
	)
	(segment
		(start 37.134546 -31.123382)
		(end 38.713664 -32.7025)
		(width 0.0889)
		(layer "In7.Cu")
		(net "XDP_BUF_RTEST#")
	)
	(segment
		(start 64.97955 -27.64155)
		(end 61.67755 -27.64155)
		(width 0.0889)
		(layer "In7.Cu")
		(net "XDP_BUF_RTEST#")
	)
	(segment
		(start 30.7848 -20.55622)
		(end 30.7848 -21.313648)
		(width 0.0889)
		(layer "In7.Cu")
		(net "XDP_BUF_RTEST#")
	)
	(segment
		(start 72.107044 -29.61005)
		(end 71.681594 -30.0355)
		(width 0.0889)
		(layer "In7.Cu")
		(net "XDP_BUF_RTEST#")
	)
	(segment
		(start 82.29854 -36.92398)
		(end 79.277464 -36.92398)
		(width 0.0889)
		(layer "In7.Cu")
		(net "XDP_BUF_RTEST#")
	)
	(segment
		(start 87.884 -37.094922)
		(end 87.463122 -37.5158)
		(width 0.0889)
		(layer "In7.Cu")
		(net "XDP_BUF_RTEST#")
	)
	(segment
		(start 76.4921 -34.138616)
		(end 76.4921 -32.468566)
		(width 0.0889)
		(layer "In7.Cu")
		(net "XDP_BUF_RTEST#")
	)
	(segment
		(start 67.3735 -30.0355)
		(end 64.97955 -27.64155)
		(width 0.0889)
		(layer "In7.Cu")
		(net "XDP_BUF_RTEST#")
	)
	(segment
		(start 71.0692 -34.417)
		(end 70.9676 -34.3154)
		(width 0.1143)
		(layer "B.Cu")
		(net "SRTCRST_BUF_IN#")
	)
	(segment
		(start 71.0438 -35.179)
		(end 71.0692 -35.1536)
		(width 0.1143)
		(layer "B.Cu")
		(net "SRTCRST_BUF_IN#")
	)
	(segment
		(start 70.3326 -35.4076)
		(end 70.8152 -35.4076)
		(width 0.1143)
		(layer "B.Cu")
		(net "SRTCRST_BUF_IN#")
	)
	(segment
		(start 69.8246 -35.9156)
		(end 70.3326 -35.4076)
		(width 0.1143)
		(layer "B.Cu")
		(net "SRTCRST_BUF_IN#")
	)
	(segment
		(start 70.8152 -35.4076)
		(end 71.0438 -35.179)
		(width 0.1143)
		(layer "B.Cu")
		(net "SRTCRST_BUF_IN#")
	)
	(segment
		(start 70.9676 -34.3154)
		(end 70.07352 -34.3154)
		(width 0.1143)
		(layer "B.Cu")
		(net "SRTCRST_BUF_IN#")
	)
	(segment
		(start 71.0692 -35.1536)
		(end 71.0692 -34.417)
		(width 0.1143)
		(layer "B.Cu")
		(net "SRTCRST_BUF_IN#")
	)
	(segment
		(start 53.848 -13.2588)
		(end 53.848 -13.688314)
		(width 0.1143)
		(layer "F.Cu")
		(net "GF_GBE_SMBALRT#")
	)
	(segment
		(start 54.4322 -14.5288)
		(end 54.4322 -14.272514)
		(width 0.1143)
		(layer "F.Cu")
		(net "GF_GBE_SMBALRT#")
	)
	(segment
		(start 53.86705 -15.09395)
		(end 54.4322 -14.5288)
		(width 0.1143)
		(layer "F.Cu")
		(net "GF_GBE_SMBALRT#")
	)
	(segment
		(start 52.197 -14.986)
		(end 52.30495 -15.09395)
		(width 0.1143)
		(layer "F.Cu")
		(net "GF_GBE_SMBALRT#")
	)
	(segment
		(start 53.848 -13.688314)
		(end 54.4322 -14.272514)
		(width 0.1143)
		(layer "F.Cu")
		(net "GF_GBE_SMBALRT#")
	)
	(segment
		(start 52.30495 -15.09395)
		(end 53.86705 -15.09395)
		(width 0.1143)
		(layer "F.Cu")
		(net "GF_GBE_SMBALRT#")
	)
	(via
		(at 52.197 -14.986)
		(size 0.7112)
		(drill 0.3556)
		(layers "F.Cu" "B.Cu")
		(net "GF_GBE_SMBALRT#")
	)
	(segment
		(start 56.76265 -13.5382)
		(end 57.43956 -14.21511)
		(width 0.1143)
		(layer "F.Cu")
		(net "GF_GBE_SMBCLK")
	)
	(segment
		(start 57.43956 -14.21511)
		(end 57.43956 -14.5923)
		(width 0.1143)
		(layer "F.Cu")
		(net "GF_GBE_SMBCLK")
	)
	(via
		(at 54.864 -12.4968)
		(size 0.7112)
		(drill 0.3556)
		(layers "F.Cu" "B.Cu")
		(net "GF_GBE_SMBCLK")
	)
	(via
		(at 56.76265 -13.5382)
		(size 0.508)
		(drill 0.254)
		(layers "F.Cu" "B.Cu")
		(net "GF_GBE_SMBCLK")
	)
	(segment
		(start 54.229 -13.1318)
		(end 54.864 -12.4968)
		(width 0.1143)
		(layer "B.Cu")
		(net "GF_GBE_SMBCLK")
	)
	(segment
		(start 54.864 -12.4968)
		(end 55.72125 -12.4968)
		(width 0.1143)
		(layer "B.Cu")
		(net "GF_GBE_SMBCLK")
	)
	(segment
		(start 55.72125 -12.4968)
		(end 56.76265 -13.5382)
		(width 0.1143)
		(layer "B.Cu")
		(net "GF_GBE_SMBCLK")
	)
	(segment
		(start 53.848 -13.1318)
		(end 54.229 -13.1318)
		(width 0.1143)
		(layer "B.Cu")
		(net "GF_GBE_SMBCLK")
	)
	(segment
		(start 56.63565 -12.27455)
		(end 58.37555 -12.27455)
		(width 0.1143)
		(layer "F.Cu")
		(net "GF_GBE_SMBDATA")
	)
	(segment
		(start 58.37555 -12.27455)
		(end 58.74004 -12.63904)
		(width 0.1143)
		(layer "F.Cu")
		(net "GF_GBE_SMBDATA")
	)
	(segment
		(start 58.74004 -12.63904)
		(end 58.74004 -12.9413)
		(width 0.1143)
		(layer "F.Cu")
		(net "GF_GBE_SMBDATA")
	)
	(segment
		(start 55.854346 -14.4272)
		(end 55.771796 -14.34465)
		(width 0.1143)
		(layer "F.Cu")
		(net "GF_GBE_SMBDATA")
	)
	(segment
		(start 55.771796 -14.34465)
		(end 55.771796 -13.138404)
		(width 0.1143)
		(layer "F.Cu")
		(net "GF_GBE_SMBDATA")
	)
	(segment
		(start 55.771796 -13.138404)
		(end 56.63565 -12.27455)
		(width 0.1143)
		(layer "F.Cu")
		(net "GF_GBE_SMBDATA")
	)
	(via
		(at 55.854346 -14.4272)
		(size 0.508)
		(drill 0.254)
		(layers "F.Cu" "B.Cu")
		(net "GF_GBE_SMBDATA")
	)
	(via
		(at 52.0954 -12.9286)
		(size 0.7112)
		(drill 0.3556)
		(layers "F.Cu" "B.Cu")
		(net "GF_GBE_SMBDATA")
	)
	(segment
		(start 53.086 -13.1318)
		(end 53.086 -13.208)
		(width 0.1143)
		(layer "B.Cu")
		(net "GF_GBE_SMBDATA")
	)
	(segment
		(start 55.092346 -13.6652)
		(end 55.854346 -14.4272)
		(width 0.1143)
		(layer "B.Cu")
		(net "GF_GBE_SMBDATA")
	)
	(segment
		(start 53.5432 -13.6652)
		(end 55.092346 -13.6652)
		(width 0.1143)
		(layer "B.Cu")
		(net "GF_GBE_SMBDATA")
	)
	(segment
		(start 52.0954 -12.9286)
		(end 52.2986 -13.1318)
		(width 0.1143)
		(layer "B.Cu")
		(net "GF_GBE_SMBDATA")
	)
	(segment
		(start 53.086 -13.208)
		(end 53.5432 -13.6652)
		(width 0.1143)
		(layer "B.Cu")
		(net "GF_GBE_SMBDATA")
	)
	(segment
		(start 52.2986 -13.1318)
		(end 53.086 -13.1318)
		(width 0.1143)
		(layer "B.Cu")
		(net "GF_GBE_SMBDATA")
	)
	(segment
		(start 57.5056 -16.410686)
		(end 58.039 -15.877286)
		(width 0.1143)
		(layer "F.Cu")
		(net "GF_GBE_SMB_SW_EN")
	)
	(segment
		(start 58.0898 -14.5923)
		(end 58.0898 -13.97)
		(width 0.1143)
		(layer "F.Cu")
		(net "GF_GBE_SMB_SW_EN")
	)
	(segment
		(start 58.0898 -13.6652)
		(end 58.0898 -12.9413)
		(width 0.1143)
		(layer "F.Cu")
		(net "GF_GBE_SMB_SW_EN")
	)
	(segment
		(start 58.039 -15.494)
		(end 58.0898 -15.4432)
		(width 0.1143)
		(layer "F.Cu")
		(net "GF_GBE_SMB_SW_EN")
	)
	(segment
		(start 59.944 -13.8176)
		(end 58.2422 -13.8176)
		(width 0.1143)
		(layer "F.Cu")
		(net "GF_GBE_SMB_SW_EN")
	)
	(segment
		(start 58.0898 -13.97)
		(end 58.2422 -13.8176)
		(width 0.1143)
		(layer "F.Cu")
		(net "GF_GBE_SMB_SW_EN")
	)
	(segment
		(start 58.2422 -13.8176)
		(end 58.0898 -13.6652)
		(width 0.1143)
		(layer "F.Cu")
		(net "GF_GBE_SMB_SW_EN")
	)
	(segment
		(start 57.025286 -16.891)
		(end 57.5056 -16.410686)
		(width 0.1143)
		(layer "F.Cu")
		(net "GF_GBE_SMB_SW_EN")
	)
	(segment
		(start 58.0898 -15.4432)
		(end 58.0898 -14.5923)
		(width 0.1143)
		(layer "F.Cu")
		(net "GF_GBE_SMB_SW_EN")
	)
	(segment
		(start 55.38216 -16.410686)
		(end 55.862474 -16.891)
		(width 0.1143)
		(layer "F.Cu")
		(net "GF_GBE_SMB_SW_EN")
	)
	(segment
		(start 58.039 -15.877286)
		(end 58.039 -15.494)
		(width 0.1143)
		(layer "F.Cu")
		(net "GF_GBE_SMB_SW_EN")
	)
	(segment
		(start 55.862474 -16.891)
		(end 57.025286 -16.891)
		(width 0.1143)
		(layer "F.Cu")
		(net "GF_GBE_SMB_SW_EN")
	)
	(via
		(at 57.5056 -16.410686)
		(size 0.7112)
		(drill 0.3556)
		(layers "F.Cu" "B.Cu")
		(net "GF_GBE_SMB_SW_EN")
	)
	(segment
		(start 47.117 -23.1648)
		(end 47.8282 -23.1648)
		(width 0.1143)
		(layer "F.Cu")
		(net "BMC_PWRBTN#")
	)
	(segment
		(start 44.2722 -30.80131)
		(end 44.57573 -31.10484)
		(width 0.1143)
		(layer "F.Cu")
		(net "BMC_PWRBTN#")
	)
	(segment
		(start 45.1104 -29.1592)
		(end 44.646596 -29.1592)
		(width 0.1143)
		(layer "F.Cu")
		(net "BMC_PWRBTN#")
	)
	(segment
		(start 44.646596 -29.1592)
		(end 44.2722 -29.533596)
		(width 0.1143)
		(layer "F.Cu")
		(net "BMC_PWRBTN#")
	)
	(segment
		(start 47.117 -23.1648)
		(end 47.117 -24.765)
		(width 0.1143)
		(layer "F.Cu")
		(net "BMC_PWRBTN#")
	)
	(segment
		(start 47.8282 -23.1648)
		(end 47.9806 -23.3172)
		(width 0.1143)
		(layer "F.Cu")
		(net "BMC_PWRBTN#")
	)
	(segment
		(start 44.57573 -31.10484)
		(end 44.79544 -31.10484)
		(width 0.1143)
		(layer "F.Cu")
		(net "BMC_PWRBTN#")
	)
	(segment
		(start 45.90796 -28.36164)
		(end 45.1104 -29.1592)
		(width 0.1143)
		(layer "F.Cu")
		(net "BMC_PWRBTN#")
	)
	(segment
		(start 45.90796 -25.97404)
		(end 45.90796 -28.36164)
		(width 0.1143)
		(layer "F.Cu")
		(net "BMC_PWRBTN#")
	)
	(segment
		(start 44.2722 -29.533596)
		(end 44.2722 -30.80131)
		(width 0.1143)
		(layer "F.Cu")
		(net "BMC_PWRBTN#")
	)
	(segment
		(start 47.117 -24.765)
		(end 45.90796 -25.97404)
		(width 0.1143)
		(layer "F.Cu")
		(net "BMC_PWRBTN#")
	)
	(via
		(at 47.9806 -23.3172)
		(size 0.508)
		(drill 0.254)
		(layers "F.Cu" "B.Cu")
		(net "BMC_PWRBTN#")
	)
	(via
		(at 90.533728 -11.088878)
		(size 0.508)
		(drill 0.254)
		(layers "F.Cu" "B.Cu")
		(net "BMC_PWRBTN#")
	)
	(via
		(at 90.1192 -12.7508)
		(size 0.7112)
		(drill 0.3556)
		(layers "F.Cu" "B.Cu")
		(net "BMC_PWRBTN#")
	)
	(segment
		(start 90.533728 -11.701272)
		(end 90.533728 -11.088878)
		(width 0.1143)
		(layer "B.Cu")
		(net "BMC_PWRBTN#")
	)
	(segment
		(start 91.2622 -13.8938)
		(end 90.1192 -12.7508)
		(width 0.1143)
		(layer "B.Cu")
		(net "BMC_PWRBTN#")
	)
	(segment
		(start 90.1192 -12.1158)
		(end 90.533728 -11.701272)
		(width 0.1143)
		(layer "B.Cu")
		(net "BMC_PWRBTN#")
	)
	(segment
		(start 92.329 -13.8938)
		(end 91.2622 -13.8938)
		(width 0.1143)
		(layer "B.Cu")
		(net "BMC_PWRBTN#")
	)
	(segment
		(start 90.1192 -12.7508)
		(end 90.1192 -12.1158)
		(width 0.1143)
		(layer "B.Cu")
		(net "BMC_PWRBTN#")
	)
	(segment
		(start 47.9806 -23.3172)
		(end 47.9806 -23.2156)
		(width 0.0889)
		(layer "In7.Cu")
		(net "BMC_PWRBTN#")
	)
	(segment
		(start 73.9394 -10.795)
		(end 76.5175 -13.3731)
		(width 0.0889)
		(layer "In7.Cu")
		(net "BMC_PWRBTN#")
	)
	(segment
		(start 45.5168 -11.9126)
		(end 55.5244 -11.9126)
		(width 0.0889)
		(layer "In7.Cu")
		(net "BMC_PWRBTN#")
	)
	(segment
		(start 70.9168 -10.795)
		(end 73.9394 -10.795)
		(width 0.0889)
		(layer "In7.Cu")
		(net "BMC_PWRBTN#")
	)
	(segment
		(start 47.9806 -23.2156)
		(end 47.26305 -22.49805)
		(width 0.0889)
		(layer "In7.Cu")
		(net "BMC_PWRBTN#")
	)
	(segment
		(start 44.191682 -13.237718)
		(end 45.5168 -11.9126)
		(width 0.0889)
		(layer "In7.Cu")
		(net "BMC_PWRBTN#")
	)
	(segment
		(start 59.694318 -10.0838)
		(end 60.6806 -9.097518)
		(width 0.0889)
		(layer "In7.Cu")
		(net "BMC_PWRBTN#")
	)
	(segment
		(start 44.191682 -14.143482)
		(end 44.191682 -13.237718)
		(width 0.0889)
		(layer "In7.Cu")
		(net "BMC_PWRBTN#")
	)
	(segment
		(start 88.10498 -13.3731)
		(end 90.389202 -11.088878)
		(width 0.0889)
		(layer "In7.Cu")
		(net "BMC_PWRBTN#")
	)
	(segment
		(start 76.5175 -13.3731)
		(end 88.10498 -13.3731)
		(width 0.0889)
		(layer "In7.Cu")
		(net "BMC_PWRBTN#")
	)
	(segment
		(start 90.389202 -11.088878)
		(end 90.533728 -11.088878)
		(width 0.0889)
		(layer "In7.Cu")
		(net "BMC_PWRBTN#")
	)
	(segment
		(start 58.0898 -10.0838)
		(end 59.694318 -10.0838)
		(width 0.0889)
		(layer "In7.Cu")
		(net "BMC_PWRBTN#")
	)
	(segment
		(start 60.6806 -9.097518)
		(end 69.219318 -9.097518)
		(width 0.0889)
		(layer "In7.Cu")
		(net "BMC_PWRBTN#")
	)
	(segment
		(start 56.7436 -11.43)
		(end 58.0898 -10.0838)
		(width 0.0889)
		(layer "In7.Cu")
		(net "BMC_PWRBTN#")
	)
	(segment
		(start 56.007 -11.43)
		(end 56.7436 -11.43)
		(width 0.0889)
		(layer "In7.Cu")
		(net "BMC_PWRBTN#")
	)
	(segment
		(start 47.26305 -17.21485)
		(end 44.191682 -14.143482)
		(width 0.0889)
		(layer "In7.Cu")
		(net "BMC_PWRBTN#")
	)
	(segment
		(start 47.26305 -22.49805)
		(end 47.26305 -17.21485)
		(width 0.0889)
		(layer "In7.Cu")
		(net "BMC_PWRBTN#")
	)
	(segment
		(start 69.219318 -9.097518)
		(end 70.9168 -10.795)
		(width 0.0889)
		(layer "In7.Cu")
		(net "BMC_PWRBTN#")
	)
	(segment
		(start 55.5244 -11.9126)
		(end 56.007 -11.43)
		(width 0.0889)
		(layer "In7.Cu")
		(net "BMC_PWRBTN#")
	)
	(segment
		(start 46.27626 -28.93314)
		(end 46.27626 -27.403806)
		(width 0.1143)
		(layer "F.Cu")
		(net "FPGA_PWRBTN#")
	)
	(segment
		(start 113.3348 -1.498854)
		(end 113.3348 -1.4986)
		(width 0.1143)
		(layer "F.Cu")
		(net "FPGA_PWRBTN#")
	)
	(segment
		(start 117.709442 -3.625596)
		(end 116.045996 -1.96215)
		(width 0.1143)
		(layer "F.Cu")
		(net "FPGA_PWRBTN#")
	)
	(segment
		(start 113.798096 -1.96215)
		(end 113.3348 -1.498854)
		(width 0.1143)
		(layer "F.Cu")
		(net "FPGA_PWRBTN#")
	)
	(segment
		(start 134.5692 -18.3642)
		(end 133.858 -17.653)
		(width 0.1143)
		(layer "F.Cu")
		(net "FPGA_PWRBTN#")
	)
	(segment
		(start 44.79544 -29.80436)
		(end 45.40504 -29.80436)
		(width 0.1143)
		(layer "F.Cu")
		(net "FPGA_PWRBTN#")
	)
	(segment
		(start 132.759704 -14.515592)
		(end 132.759704 -13.978636)
		(width 0.1143)
		(layer "F.Cu")
		(net "FPGA_PWRBTN#")
	)
	(segment
		(start 130.479292 -11.698224)
		(end 128.287018 -11.698224)
		(width 0.1143)
		(layer "F.Cu")
		(net "FPGA_PWRBTN#")
	)
	(segment
		(start 46.27626 -27.403806)
		(end 46.666404 -27.013662)
		(width 0.1143)
		(layer "F.Cu")
		(net "FPGA_PWRBTN#")
	)
	(segment
		(start 128.287018 -11.698224)
		(end 120.21439 -3.625596)
		(width 0.1143)
		(layer "F.Cu")
		(net "FPGA_PWRBTN#")
	)
	(segment
		(start 120.21439 -3.625596)
		(end 117.709442 -3.625596)
		(width 0.1143)
		(layer "F.Cu")
		(net "FPGA_PWRBTN#")
	)
	(segment
		(start 45.40504 -29.80436)
		(end 46.27626 -28.93314)
		(width 0.1143)
		(layer "F.Cu")
		(net "FPGA_PWRBTN#")
	)
	(segment
		(start 132.75945 -16.55445)
		(end 132.75945 -14.515846)
		(width 0.1143)
		(layer "F.Cu")
		(net "FPGA_PWRBTN#")
	)
	(segment
		(start 134.62 -18.3642)
		(end 134.5692 -18.3642)
		(width 0.1143)
		(layer "F.Cu")
		(net "FPGA_PWRBTN#")
	)
	(segment
		(start 132.75945 -14.515846)
		(end 132.759704 -14.515592)
		(width 0.1143)
		(layer "F.Cu")
		(net "FPGA_PWRBTN#")
	)
	(segment
		(start 133.858 -17.653)
		(end 132.75945 -16.55445)
		(width 0.1143)
		(layer "F.Cu")
		(net "FPGA_PWRBTN#")
	)
	(segment
		(start 116.045996 -1.96215)
		(end 113.798096 -1.96215)
		(width 0.1143)
		(layer "F.Cu")
		(net "FPGA_PWRBTN#")
	)
	(segment
		(start 134.62 -18.3642)
		(end 135.509 -18.3642)
		(width 0.1143)
		(layer "F.Cu")
		(net "FPGA_PWRBTN#")
	)
	(segment
		(start 132.759704 -13.978636)
		(end 130.479292 -11.698224)
		(width 0.1143)
		(layer "F.Cu")
		(net "FPGA_PWRBTN#")
	)
	(via
		(at 133.858 -17.653)
		(size 0.7112)
		(drill 0.3556)
		(layers "F.Cu" "B.Cu")
		(net "FPGA_PWRBTN#")
	)
	(via
		(at 46.666404 -27.013662)
		(size 0.508)
		(drill 0.254)
		(layers "F.Cu" "B.Cu")
		(net "FPGA_PWRBTN#")
	)
	(via
		(at 113.3348 -1.4986)
		(size 0.508)
		(drill 0.254)
		(layers "F.Cu" "B.Cu")
		(net "FPGA_PWRBTN#")
	)
	(segment
		(start 98.1456 -10.55751)
		(end 98.1456 -11.400282)
		(width 0.0889)
		(layer "In9.Cu")
		(net "FPGA_PWRBTN#")
	)
	(segment
		(start 85.00872 -10.84072)
		(end 86.074504 -11.906504)
		(width 0.0889)
		(layer "In9.Cu")
		(net "FPGA_PWRBTN#")
	)
	(segment
		(start 90.356182 -9.135618)
		(end 96.723708 -9.135618)
		(width 0.0889)
		(layer "In9.Cu")
		(net "FPGA_PWRBTN#")
	)
	(segment
		(start 112.801146 -0.9652)
		(end 113.334546 -1.4986)
		(width 0.0889)
		(layer "In9.Cu")
		(net "FPGA_PWRBTN#")
	)
	(segment
		(start 99.252024 -12.506706)
		(end 104.748076 -12.506706)
		(width 0.0889)
		(layer "In9.Cu")
		(net "FPGA_PWRBTN#")
	)
	(segment
		(start 38.51275 -8.50265)
		(end 80.923892 -8.50265)
		(width 0.0889)
		(layer "In9.Cu")
		(net "FPGA_PWRBTN#")
	)
	(segment
		(start 46.0248 -22.5552)
		(end 37.9984 -14.5288)
		(width 0.0889)
		(layer "In9.Cu")
		(net "FPGA_PWRBTN#")
	)
	(segment
		(start 106.677206 -0.9652)
		(end 112.801146 -0.9652)
		(width 0.0889)
		(layer "In9.Cu")
		(net "FPGA_PWRBTN#")
	)
	(segment
		(start 37.523928 -14.5288)
		(end 36.99002 -13.994892)
		(width 0.0889)
		(layer "In9.Cu")
		(net "FPGA_PWRBTN#")
	)
	(segment
		(start 105.806494 -11.448288)
		(end 105.806494 -1.835912)
		(width 0.0889)
		(layer "In9.Cu")
		(net "FPGA_PWRBTN#")
	)
	(segment
		(start 98.1456 -11.400282)
		(end 99.252024 -12.506706)
		(width 0.0889)
		(layer "In9.Cu")
		(net "FPGA_PWRBTN#")
	)
	(segment
		(start 83.20913 -10.83818)
		(end 83.222084 -10.84072)
		(width 0.0889)
		(layer "In9.Cu")
		(net "FPGA_PWRBTN#")
	)
	(segment
		(start 83.222084 -10.84072)
		(end 85.00872 -10.84072)
		(width 0.0889)
		(layer "In9.Cu")
		(net "FPGA_PWRBTN#")
	)
	(segment
		(start 46.666404 -24.633682)
		(end 46.0248 -23.992078)
		(width 0.0889)
		(layer "In9.Cu")
		(net "FPGA_PWRBTN#")
	)
	(segment
		(start 36.99002 -13.994892)
		(end 36.99002 -10.02538)
		(width 0.0889)
		(layer "In9.Cu")
		(net "FPGA_PWRBTN#")
	)
	(segment
		(start 36.99002 -10.02538)
		(end 38.51275 -8.50265)
		(width 0.0889)
		(layer "In9.Cu")
		(net "FPGA_PWRBTN#")
	)
	(segment
		(start 46.666404 -27.013662)
		(end 46.666404 -24.633682)
		(width 0.0889)
		(layer "In9.Cu")
		(net "FPGA_PWRBTN#")
	)
	(segment
		(start 96.723708 -9.135618)
		(end 98.1456 -10.55751)
		(width 0.0889)
		(layer "In9.Cu")
		(net "FPGA_PWRBTN#")
	)
	(segment
		(start 82.296 -9.92505)
		(end 83.20913 -10.83818)
		(width 0.0889)
		(layer "In9.Cu")
		(net "FPGA_PWRBTN#")
	)
	(segment
		(start 113.334546 -1.4986)
		(end 113.3348 -1.4986)
		(width 0.0889)
		(layer "In9.Cu")
		(net "FPGA_PWRBTN#")
	)
	(segment
		(start 82.296 -9.874758)
		(end 82.296 -9.92505)
		(width 0.0889)
		(layer "In9.Cu")
		(net "FPGA_PWRBTN#")
	)
	(segment
		(start 105.806494 -1.835912)
		(end 106.677206 -0.9652)
		(width 0.0889)
		(layer "In9.Cu")
		(net "FPGA_PWRBTN#")
	)
	(segment
		(start 104.748076 -12.506706)
		(end 105.806494 -11.448288)
		(width 0.0889)
		(layer "In9.Cu")
		(net "FPGA_PWRBTN#")
	)
	(segment
		(start 87.585296 -11.906504)
		(end 90.356182 -9.135618)
		(width 0.0889)
		(layer "In9.Cu")
		(net "FPGA_PWRBTN#")
	)
	(segment
		(start 37.9984 -14.5288)
		(end 37.523928 -14.5288)
		(width 0.0889)
		(layer "In9.Cu")
		(net "FPGA_PWRBTN#")
	)
	(segment
		(start 86.074504 -11.906504)
		(end 87.585296 -11.906504)
		(width 0.0889)
		(layer "In9.Cu")
		(net "FPGA_PWRBTN#")
	)
	(segment
		(start 80.923892 -8.50265)
		(end 82.296 -9.874758)
		(width 0.0889)
		(layer "In9.Cu")
		(net "FPGA_PWRBTN#")
	)
	(segment
		(start 46.0248 -23.992078)
		(end 46.0248 -22.5552)
		(width 0.0889)
		(layer "In9.Cu")
		(net "FPGA_PWRBTN#")
	)
	(segment
		(start 46.54296 -31.10484)
		(end 46.69536 -31.10484)
		(width 0.1143)
		(layer "F.Cu")
		(net "XDP_PWRBTN#")
	)
	(segment
		(start 45.7962 -33.274)
		(end 45.7454 -33.3248)
		(width 0.1143)
		(layer "F.Cu")
		(net "XDP_PWRBTN#")
	)
	(segment
		(start 45.7962 -32.9692)
		(end 45.7962 -33.274)
		(width 0.1143)
		(layer "F.Cu")
		(net "XDP_PWRBTN#")
	)
	(segment
		(start 45.7454 -33.3248)
		(end 45.7454 -35.1282)
		(width 0.1143)
		(layer "F.Cu")
		(net "XDP_PWRBTN#")
	)
	(segment
		(start 46.092364 -35.475164)
		(end 46.092364 -36.08451)
		(width 0.1143)
		(layer "F.Cu")
		(net "XDP_PWRBTN#")
	)
	(segment
		(start 46.3296 -31.3182)
		(end 46.54296 -31.10484)
		(width 0.1143)
		(layer "F.Cu")
		(net "XDP_PWRBTN#")
	)
	(segment
		(start 46.3296 -32.4358)
		(end 45.7962 -32.9692)
		(width 0.1143)
		(layer "F.Cu")
		(net "XDP_PWRBTN#")
	)
	(segment
		(start 45.7454 -35.1282)
		(end 46.092364 -35.475164)
		(width 0.1143)
		(layer "F.Cu")
		(net "XDP_PWRBTN#")
	)
	(segment
		(start 45.45711 -36.08451)
		(end 44.958 -35.5854)
		(width 0.1143)
		(layer "F.Cu")
		(net "XDP_PWRBTN#")
	)
	(segment
		(start 46.092364 -36.08451)
		(end 45.45711 -36.08451)
		(width 0.1143)
		(layer "F.Cu")
		(net "XDP_PWRBTN#")
	)
	(segment
		(start 46.3296 -32.4358)
		(end 46.3296 -31.3182)
		(width 0.1143)
		(layer "F.Cu")
		(net "XDP_PWRBTN#")
	)
	(via
		(at 46.092364 -36.08451)
		(size 0.7112)
		(drill 0.3556)
		(layers "F.Cu" "B.Cu")
		(net "XDP_PWRBTN#")
	)
	(segment
		(start 68.86956 -13.47724)
		(end 68.39204 -13.47724)
		(width 0.1143)
		(layer "F.Cu")
		(net "PMU_RESETBUTTON#")
	)
	(segment
		(start 65.786 -11.4046)
		(end 66.3194 -10.8712)
		(width 0.1143)
		(layer "F.Cu")
		(net "PMU_RESETBUTTON#")
	)
	(segment
		(start 66.3194 -10.8712)
		(end 69.3928 -10.8712)
		(width 0.1143)
		(layer "F.Cu")
		(net "PMU_RESETBUTTON#")
	)
	(segment
		(start 69.3928 -10.8712)
		(end 69.9262 -11.4046)
		(width 0.1143)
		(layer "F.Cu")
		(net "PMU_RESETBUTTON#")
	)
	(segment
		(start 65.786 -12.5222)
		(end 65.786 -11.4046)
		(width 0.1143)
		(layer "F.Cu")
		(net "PMU_RESETBUTTON#")
	)
	(segment
		(start 69.0626 -13.2842)
		(end 68.86956 -13.47724)
		(width 0.1143)
		(layer "F.Cu")
		(net "PMU_RESETBUTTON#")
	)
	(segment
		(start 69.9262 -11.4046)
		(end 69.9262 -11.6332)
		(width 0.1143)
		(layer "F.Cu")
		(net "PMU_RESETBUTTON#")
	)
	(segment
		(start 69.0626 -12.4968)
		(end 69.0626 -13.2842)
		(width 0.1143)
		(layer "F.Cu")
		(net "PMU_RESETBUTTON#")
	)
	(segment
		(start 69.9262 -11.6332)
		(end 69.0626 -12.4968)
		(width 0.1143)
		(layer "F.Cu")
		(net "PMU_RESETBUTTON#")
	)
	(via
		(at 72.771 -46.736)
		(size 0.7112)
		(drill 0.3556)
		(layers "F.Cu" "B.Cu")
		(net "PMU_RESETBUTTON#")
	)
	(via
		(at 71.8693 -46.0629)
		(size 0.508)
		(drill 0.254)
		(layers "F.Cu" "B.Cu")
		(net "PMU_RESETBUTTON#")
	)
	(via
		(at 69.9262 -11.4046)
		(size 0.508)
		(drill 0.254)
		(layers "F.Cu" "B.Cu")
		(net "PMU_RESETBUTTON#")
	)
	(segment
		(start 73.1012 -46.736)
		(end 72.771 -46.736)
		(width 0.1143)
		(layer "B.Cu")
		(net "PMU_RESETBUTTON#")
	)
	(segment
		(start 72.5424 -46.736)
		(end 71.8693 -46.0629)
		(width 0.1143)
		(layer "B.Cu")
		(net "PMU_RESETBUTTON#")
	)
	(segment
		(start 72.771 -46.736)
		(end 72.5424 -46.736)
		(width 0.1143)
		(layer "B.Cu")
		(net "PMU_RESETBUTTON#")
	)
	(segment
		(start 73.7362 -46.101)
		(end 73.1012 -46.736)
		(width 0.1143)
		(layer "B.Cu")
		(net "PMU_RESETBUTTON#")
	)
	(segment
		(start 74.7649 -15.959582)
		(end 72.5297 -18.194782)
		(width 0.0889)
		(layer "In2.Cu")
		(net "PMU_RESETBUTTON#")
	)
	(segment
		(start 74.7649 -14.7447)
		(end 74.7649 -15.959582)
		(width 0.0889)
		(layer "In2.Cu")
		(net "PMU_RESETBUTTON#")
	)
	(segment
		(start 64.40805 -41.14165)
		(end 65.922398 -42.655998)
		(width 0.0889)
		(layer "In2.Cu")
		(net "PMU_RESETBUTTON#")
	)
	(segment
		(start 68.689982 -45.9867)
		(end 71.7931 -45.9867)
		(width 0.0889)
		(layer "In2.Cu")
		(net "PMU_RESETBUTTON#")
	)
	(segment
		(start 72.5297 -18.194782)
		(end 72.5297 -18.520156)
		(width 0.0889)
		(layer "In2.Cu")
		(net "PMU_RESETBUTTON#")
	)
	(segment
		(start 65.922398 -43.319192)
		(end 67.021456 -44.41825)
		(width 0.0889)
		(layer "In2.Cu")
		(net "PMU_RESETBUTTON#")
	)
	(segment
		(start 67.021456 -44.41825)
		(end 67.121532 -44.41825)
		(width 0.0889)
		(layer "In2.Cu")
		(net "PMU_RESETBUTTON#")
	)
	(segment
		(start 67.121532 -44.41825)
		(end 68.689982 -45.9867)
		(width 0.0889)
		(layer "In2.Cu")
		(net "PMU_RESETBUTTON#")
	)
	(segment
		(start 72.5297 -18.520156)
		(end 65.13195 -25.917906)
		(width 0.0889)
		(layer "In2.Cu")
		(net "PMU_RESETBUTTON#")
	)
	(segment
		(start 65.13195 -25.917906)
		(end 65.13195 -29.280358)
		(width 0.0889)
		(layer "In2.Cu")
		(net "PMU_RESETBUTTON#")
	)
	(segment
		(start 64.40805 -30.004258)
		(end 64.40805 -41.14165)
		(width 0.0889)
		(layer "In2.Cu")
		(net "PMU_RESETBUTTON#")
	)
	(segment
		(start 70.6882 -12.1666)
		(end 72.1868 -12.1666)
		(width 0.0889)
		(layer "In2.Cu")
		(net "PMU_RESETBUTTON#")
	)
	(segment
		(start 65.922398 -42.655998)
		(end 65.922398 -43.319192)
		(width 0.0889)
		(layer "In2.Cu")
		(net "PMU_RESETBUTTON#")
	)
	(segment
		(start 69.9262 -11.4046)
		(end 70.6882 -12.1666)
		(width 0.0889)
		(layer "In2.Cu")
		(net "PMU_RESETBUTTON#")
	)
	(segment
		(start 65.13195 -29.280358)
		(end 64.40805 -30.004258)
		(width 0.0889)
		(layer "In2.Cu")
		(net "PMU_RESETBUTTON#")
	)
	(segment
		(start 72.1868 -12.1666)
		(end 74.7649 -14.7447)
		(width 0.0889)
		(layer "In2.Cu")
		(net "PMU_RESETBUTTON#")
	)
	(segment
		(start 71.7931 -45.9867)
		(end 71.8693 -46.0629)
		(width 0.0889)
		(layer "In2.Cu")
		(net "PMU_RESETBUTTON#")
	)
	(via
		(at 18.669 -50.419)
		(size 0.7112)
		(drill 0.3556)
		(layers "F.Cu" "B.Cu")
		(net "P3V3_DISCHARGE_D")
	)
	(segment
		(start 18.669 -50.419)
		(end 18.669 -48.902366)
		(width 0.2032)
		(layer "B.Cu")
		(net "P3V3_DISCHARGE_D")
	)
	(segment
		(start 17.272 -51.8414)
		(end 18.669 -50.4444)
		(width 0.2032)
		(layer "B.Cu")
		(net "P3V3_DISCHARGE_D")
	)
	(segment
		(start 18.669 -48.902366)
		(end 18.415 -48.648366)
		(width 0.2032)
		(layer "B.Cu")
		(net "P3V3_DISCHARGE_D")
	)
	(segment
		(start 18.669 -50.4444)
		(end 18.669 -50.419)
		(width 0.2032)
		(layer "B.Cu")
		(net "P3V3_DISCHARGE_D")
	)
	(segment
		(start 18.415 -47.043086)
		(end 18.923 -46.535086)
		(width 0.2032)
		(layer "B.Cu")
		(net "P3V3_DISCHARGE_D")
	)
	(segment
		(start 18.415 -48.648366)
		(end 18.415 -47.043086)
		(width 0.2032)
		(layer "B.Cu")
		(net "P3V3_DISCHARGE_D")
	)
	(segment
		(start 16.002 -51.8414)
		(end 17.272 -51.8414)
		(width 0.2032)
		(layer "B.Cu")
		(net "P3V3_DISCHARGE_D")
	)
	(segment
		(start 129.252472 -32.79394)
		(end 124.792232 -28.3337)
		(width 0.1143)
		(layer "F.Cu")
		(net "IRQ_CPU_LV_IERR#")
	)
	(segment
		(start 107.472226 -10.2616)
		(end 107.451144 -10.2616)
		(width 0.1143)
		(layer "F.Cu")
		(net "IRQ_CPU_LV_IERR#")
	)
	(segment
		(start 109.72546 -12.514834)
		(end 107.472226 -10.2616)
		(width 0.1143)
		(layer "F.Cu")
		(net "IRQ_CPU_LV_IERR#")
	)
	(segment
		(start 116.763546 -22.720808)
		(end 116.763546 -16.806926)
		(width 0.1143)
		(layer "F.Cu")
		(net "IRQ_CPU_LV_IERR#")
	)
	(segment
		(start 107.451144 -10.2616)
		(end 107.438444 -10.2489)
		(width 0.1143)
		(layer "F.Cu")
		(net "IRQ_CPU_LV_IERR#")
	)
	(segment
		(start 124.792232 -28.3337)
		(end 122.376438 -28.3337)
		(width 0.1143)
		(layer "F.Cu")
		(net "IRQ_CPU_LV_IERR#")
	)
	(segment
		(start 122.376438 -28.3337)
		(end 116.763546 -22.720808)
		(width 0.1143)
		(layer "F.Cu")
		(net "IRQ_CPU_LV_IERR#")
	)
	(segment
		(start 132.1308 -32.79394)
		(end 129.252472 -32.79394)
		(width 0.1143)
		(layer "F.Cu")
		(net "IRQ_CPU_LV_IERR#")
	)
	(segment
		(start 116.763546 -16.806926)
		(end 112.471454 -12.514834)
		(width 0.1143)
		(layer "F.Cu")
		(net "IRQ_CPU_LV_IERR#")
	)
	(segment
		(start 112.471454 -12.514834)
		(end 109.72546 -12.514834)
		(width 0.1143)
		(layer "F.Cu")
		(net "IRQ_CPU_LV_IERR#")
	)
	(via
		(at 107.438444 -10.2489)
		(size 0.508)
		(drill 0.254)
		(layers "F.Cu" "B.Cu")
		(net "IRQ_CPU_LV_IERR#")
	)
	(via
		(at 109.72546 -12.514834)
		(size 0.7112)
		(drill 0.3556)
		(layers "F.Cu" "B.Cu")
		(net "IRQ_CPU_LV_IERR#")
	)
	(segment
		(start 104.18572 -16.39824)
		(end 104.32796 -16.39824)
		(width 0.1143)
		(layer "B.Cu")
		(net "IRQ_CPU_LV_IERR#")
	)
	(segment
		(start 107.90555 -12.82065)
		(end 107.90555 -10.85215)
		(width 0.1143)
		(layer "B.Cu")
		(net "IRQ_CPU_LV_IERR#")
	)
	(segment
		(start 104.32796 -16.39824)
		(end 105.283 -15.4432)
		(width 0.1143)
		(layer "B.Cu")
		(net "IRQ_CPU_LV_IERR#")
	)
	(segment
		(start 105.283 -15.4432)
		(end 107.90555 -12.82065)
		(width 0.1143)
		(layer "B.Cu")
		(net "IRQ_CPU_LV_IERR#")
	)
	(segment
		(start 107.90555 -10.85215)
		(end 107.438444 -10.385044)
		(width 0.1143)
		(layer "B.Cu")
		(net "IRQ_CPU_LV_IERR#")
	)
	(segment
		(start 107.438444 -10.385044)
		(end 107.438444 -10.2489)
		(width 0.1143)
		(layer "B.Cu")
		(net "IRQ_CPU_LV_IERR#")
	)
	(segment
		(start 110.7694 -7.8486)
		(end 110.7694 -7.992872)
		(width 0.1143)
		(layer "F.Cu")
		(net "IRQ_LV_MCERR#")
	)
	(segment
		(start 118.859046 -21.852128)
		(end 118.859046 -15.938246)
		(width 0.1143)
		(layer "F.Cu")
		(net "IRQ_LV_MCERR#")
	)
	(segment
		(start 126.004828 -26.2255)
		(end 123.232418 -26.2255)
		(width 0.1143)
		(layer "F.Cu")
		(net "IRQ_LV_MCERR#")
	)
	(segment
		(start 132.1308 -28.79344)
		(end 128.572768 -28.79344)
		(width 0.1143)
		(layer "F.Cu")
		(net "IRQ_LV_MCERR#")
	)
	(segment
		(start 128.572768 -28.79344)
		(end 126.004828 -26.2255)
		(width 0.1143)
		(layer "F.Cu")
		(net "IRQ_LV_MCERR#")
	)
	(segment
		(start 110.7694 -7.992872)
		(end 111.929164 -9.152636)
		(width 0.1143)
		(layer "F.Cu")
		(net "IRQ_LV_MCERR#")
	)
	(segment
		(start 123.232418 -26.2255)
		(end 118.859046 -21.852128)
		(width 0.1143)
		(layer "F.Cu")
		(net "IRQ_LV_MCERR#")
	)
	(segment
		(start 112.073436 -9.152636)
		(end 111.929164 -9.152636)
		(width 0.1143)
		(layer "F.Cu")
		(net "IRQ_LV_MCERR#")
	)
	(segment
		(start 118.859046 -15.938246)
		(end 112.073436 -9.152636)
		(width 0.1143)
		(layer "F.Cu")
		(net "IRQ_LV_MCERR#")
	)
	(via
		(at 111.929164 -9.152636)
		(size 0.7112)
		(drill 0.3556)
		(layers "F.Cu" "B.Cu")
		(net "IRQ_LV_MCERR#")
	)
	(via
		(at 110.7694 -7.8486)
		(size 0.508)
		(drill 0.254)
		(layers "F.Cu" "B.Cu")
		(net "IRQ_LV_MCERR#")
	)
	(segment
		(start 112.79124 -6.30428)
		(end 112.31372 -6.30428)
		(width 0.1143)
		(layer "B.Cu")
		(net "IRQ_LV_MCERR#")
	)
	(segment
		(start 110.109 -6.1468)
		(end 110.109 -6.639814)
		(width 0.1143)
		(layer "B.Cu")
		(net "IRQ_LV_MCERR#")
	)
	(segment
		(start 110.64875 -7.72795)
		(end 110.7694 -7.8486)
		(width 0.1143)
		(layer "B.Cu")
		(net "IRQ_LV_MCERR#")
	)
	(segment
		(start 110.64875 -7.179564)
		(end 110.64875 -7.72795)
		(width 0.1143)
		(layer "B.Cu")
		(net "IRQ_LV_MCERR#")
	)
	(segment
		(start 112.31372 -6.30428)
		(end 110.7694 -7.8486)
		(width 0.1143)
		(layer "B.Cu")
		(net "IRQ_LV_MCERR#")
	)
	(segment
		(start 110.109 -6.639814)
		(end 110.64875 -7.179564)
		(width 0.1143)
		(layer "B.Cu")
		(net "IRQ_LV_MCERR#")
	)
	(segment
		(start 132.1308 -26.29408)
		(end 130.56108 -26.29408)
		(width 0.1143)
		(layer "F.Cu")
		(net "PMU_PLD_R_PLTRST#")
	)
	(segment
		(start 130.4798 -26.2128)
		(end 130.556 -26.289)
		(width 0.1143)
		(layer "F.Cu")
		(net "PMU_PLD_R_PLTRST#")
	)
	(segment
		(start 129.3368 -26.2128)
		(end 130.4798 -26.2128)
		(width 0.1143)
		(layer "F.Cu")
		(net "PMU_PLD_R_PLTRST#")
	)
	(segment
		(start 130.56108 -26.29408)
		(end 130.556 -26.289)
		(width 0.1143)
		(layer "F.Cu")
		(net "PMU_PLD_R_PLTRST#")
	)
	(via
		(at 130.556 -26.289)
		(size 0.7112)
		(drill 0.3556)
		(layers "F.Cu" "B.Cu")
		(net "PMU_PLD_R_PLTRST#")
	)
	(segment
		(start 132.1308 -26.79446)
		(end 132.679694 -26.79446)
		(width 0.1143)
		(layer "F.Cu")
		(net "PMU_SLP_R_S45#")
	)
	(segment
		(start 132.679694 -26.79446)
		(end 135.382 -29.496766)
		(width 0.1143)
		(layer "F.Cu")
		(net "PMU_SLP_R_S45#")
	)
	(segment
		(start 135.382 -29.496766)
		(end 135.382 -30.353)
		(width 0.1143)
		(layer "F.Cu")
		(net "PMU_SLP_R_S45#")
	)
	(via
		(at 137.414 -30.353)
		(size 0.7112)
		(drill 0.3556)
		(layers "F.Cu" "B.Cu")
		(net "PMU_SLP_R_S45#")
	)
	(via
		(at 135.382 -30.353)
		(size 0.508)
		(drill 0.254)
		(layers "F.Cu" "B.Cu")
		(net "PMU_SLP_R_S45#")
	)
	(segment
		(start 135.382 -30.353)
		(end 135.84555 -29.88945)
		(width 0.1143)
		(layer "B.Cu")
		(net "PMU_SLP_R_S45#")
	)
	(segment
		(start 135.84555 -29.88945)
		(end 136.95045 -29.88945)
		(width 0.1143)
		(layer "B.Cu")
		(net "PMU_SLP_R_S45#")
	)
	(segment
		(start 136.95045 -29.88945)
		(end 137.414 -30.353)
		(width 0.1143)
		(layer "B.Cu")
		(net "PMU_SLP_R_S45#")
	)
	(segment
		(start 138.6332 -30.353)
		(end 137.414 -30.353)
		(width 0.1143)
		(layer "B.Cu")
		(net "PMU_SLP_R_S45#")
	)
	(segment
		(start 69.542914 -53.320188)
		(end 68.665344 -52.442618)
		(width 0.1143)
		(layer "F.Cu")
		(net "SMBUS_SW_INV_D")
	)
	(segment
		(start 68.665344 -52.442618)
		(end 67.6402 -51.417474)
		(width 0.1143)
		(layer "F.Cu")
		(net "SMBUS_SW_INV_D")
	)
	(segment
		(start 69.542914 -53.467)
		(end 69.542914 -53.320188)
		(width 0.1143)
		(layer "F.Cu")
		(net "SMBUS_SW_INV_D")
	)
	(segment
		(start 67.6402 -51.054)
		(end 67.6402 -50.292)
		(width 0.1143)
		(layer "F.Cu")
		(net "SMBUS_SW_INV_D")
	)
	(segment
		(start 67.6402 -51.417474)
		(end 67.6402 -51.054)
		(width 0.1143)
		(layer "F.Cu")
		(net "SMBUS_SW_INV_D")
	)
	(via
		(at 68.665344 -52.442618)
		(size 0.7112)
		(drill 0.3556)
		(layers "F.Cu" "B.Cu")
		(net "SMBUS_SW_INV_D")
	)
	(segment
		(start 133.731 -20.574)
		(end 133.477 -20.828)
		(width 0.1143)
		(layer "F.Cu")
		(net "POWER_GOOD_R")
	)
	(segment
		(start 133.477 -21.386546)
		(end 134.505954 -22.4155)
		(width 0.1143)
		(layer "F.Cu")
		(net "POWER_GOOD_R")
	)
	(segment
		(start 134.505954 -22.4155)
		(end 134.59841 -22.4155)
		(width 0.1143)
		(layer "F.Cu")
		(net "POWER_GOOD_R")
	)
	(segment
		(start 134.99846 -22.81555)
		(end 134.99846 -23.9268)
		(width 0.1143)
		(layer "F.Cu")
		(net "POWER_GOOD_R")
	)
	(segment
		(start 132.8674 -18.9992)
		(end 133.731 -19.8628)
		(width 0.1143)
		(layer "F.Cu")
		(net "POWER_GOOD_R")
	)
	(segment
		(start 132.842 -18.9992)
		(end 132.8674 -18.9992)
		(width 0.1143)
		(layer "F.Cu")
		(net "POWER_GOOD_R")
	)
	(segment
		(start 133.731 -19.8628)
		(end 133.731 -20.574)
		(width 0.1143)
		(layer "F.Cu")
		(net "POWER_GOOD_R")
	)
	(segment
		(start 133.477 -21.209)
		(end 133.477 -21.386546)
		(width 0.1143)
		(layer "F.Cu")
		(net "POWER_GOOD_R")
	)
	(segment
		(start 133.477 -20.828)
		(end 133.477 -21.209)
		(width 0.1143)
		(layer "F.Cu")
		(net "POWER_GOOD_R")
	)
	(segment
		(start 134.59841 -22.4155)
		(end 134.99846 -22.81555)
		(width 0.1143)
		(layer "F.Cu")
		(net "POWER_GOOD_R")
	)
	(via
		(at 133.477 -21.209)
		(size 0.7112)
		(drill 0.3556)
		(layers "F.Cu" "B.Cu")
		(net "POWER_GOOD_R")
	)
	(segment
		(start 170.9166 -44.0944)
		(end 171.1706 -44.0944)
		(width 0.508)
		(layer "F.Cu")
		(net "P2V5_STBY_BYPASS")
	)
	(segment
		(start 171.663106 -43.601894)
		(end 171.1706 -44.0944)
		(width 0.508)
		(layer "F.Cu")
		(net "P2V5_STBY_BYPASS")
	)
	(segment
		(start 170.3832 -43.561)
		(end 170.9166 -44.0944)
		(width 0.508)
		(layer "F.Cu")
		(net "P2V5_STBY_BYPASS")
	)
	(segment
		(start 171.663106 -43.11396)
		(end 171.663106 -43.601894)
		(width 0.508)
		(layer "F.Cu")
		(net "P2V5_STBY_BYPASS")
	)
	(via
		(at 171.1706 -44.0944)
		(size 0.7112)
		(drill 0.3556)
		(layers "F.Cu" "B.Cu")
		(net "P2V5_STBY_BYPASS")
	)
	(segment
		(start 171.663106 -42.164)
		(end 170.4594 -42.164)
		(width 0.254)
		(layer "F.Cu")
		(net "P2V5_STBY_FB")
	)
	(segment
		(start 169.545 -41.8592)
		(end 170.0276 -41.8592)
		(width 0.254)
		(layer "F.Cu")
		(net "P2V5_STBY_FB")
	)
	(segment
		(start 169.4688 -40.894)
		(end 169.4688 -41.783)
		(width 0.254)
		(layer "F.Cu")
		(net "P2V5_STBY_FB")
	)
	(segment
		(start 169.4942 -40.132)
		(end 169.4688 -40.1574)
		(width 0.254)
		(layer "F.Cu")
		(net "P2V5_STBY_FB")
	)
	(segment
		(start 170.3324 -42.164)
		(end 170.4594 -42.164)
		(width 0.254)
		(layer "F.Cu")
		(net "P2V5_STBY_FB")
	)
	(segment
		(start 169.4688 -41.783)
		(end 169.545 -41.8592)
		(width 0.254)
		(layer "F.Cu")
		(net "P2V5_STBY_FB")
	)
	(segment
		(start 169.4688 -40.1574)
		(end 169.4688 -40.894)
		(width 0.254)
		(layer "F.Cu")
		(net "P2V5_STBY_FB")
	)
	(segment
		(start 170.0276 -41.8592)
		(end 170.3324 -42.164)
		(width 0.254)
		(layer "F.Cu")
		(net "P2V5_STBY_FB")
	)
	(via
		(at 170.4594 -42.164)
		(size 0.7112)
		(drill 0.3556)
		(layers "F.Cu" "B.Cu")
		(net "P2V5_STBY_FB")
	)
	(via
		(at 171.3865 -38.5318)
		(size 0.7112)
		(drill 0.3556)
		(layers "F.Cu" "B.Cu")
		(net "P2V5_STBY_OUT")
	)
	(segment
		(start 70.666356 -68.85305)
		(end 68.3514 -66.538094)
		(width 0.1143)
		(layer "F.Cu")
		(net "FPGA_SMB_HOST_DATA")
	)
	(segment
		(start 73.60158 -68.52158)
		(end 73.27011 -68.85305)
		(width 0.1143)
		(layer "F.Cu")
		(net "FPGA_SMB_HOST_DATA")
	)
	(segment
		(start 79.711296 -71.18477)
		(end 79.711296 -70.491096)
		(width 0.1143)
		(layer "F.Cu")
		(net "FPGA_SMB_HOST_DATA")
	)
	(segment
		(start 79.711296 -70.491096)
		(end 79.2226 -70.0024)
		(width 0.1143)
		(layer "F.Cu")
		(net "FPGA_SMB_HOST_DATA")
	)
	(segment
		(start 74.089514 -68.0339)
		(end 73.60158 -68.52158)
		(width 0.1143)
		(layer "F.Cu")
		(net "FPGA_SMB_HOST_DATA")
	)
	(segment
		(start 79.2226 -70.0024)
		(end 79.088996 -70.0024)
		(width 0.1143)
		(layer "F.Cu")
		(net "FPGA_SMB_HOST_DATA")
	)
	(segment
		(start 67.31 -58.3438)
		(end 67.564 -58.0898)
		(width 0.1143)
		(layer "F.Cu")
		(net "FPGA_SMB_HOST_DATA")
	)
	(segment
		(start 79.088996 -70.0024)
		(end 77.012546 -67.92595)
		(width 0.1143)
		(layer "F.Cu")
		(net "FPGA_SMB_HOST_DATA")
	)
	(segment
		(start 67.564 -62.07506)
		(end 67.564 -60.5282)
		(width 0.1143)
		(layer "F.Cu")
		(net "FPGA_SMB_HOST_DATA")
	)
	(segment
		(start 67.564 -60.5282)
		(end 67.31 -60.2742)
		(width 0.1143)
		(layer "F.Cu")
		(net "FPGA_SMB_HOST_DATA")
	)
	(segment
		(start 77.012546 -67.92595)
		(end 74.197464 -67.92595)
		(width 0.1143)
		(layer "F.Cu")
		(net "FPGA_SMB_HOST_DATA")
	)
	(segment
		(start 74.197464 -67.92595)
		(end 74.089514 -68.0339)
		(width 0.1143)
		(layer "F.Cu")
		(net "FPGA_SMB_HOST_DATA")
	)
	(segment
		(start 67.91325 -63.733172)
		(end 67.91325 -62.42431)
		(width 0.1143)
		(layer "F.Cu")
		(net "FPGA_SMB_HOST_DATA")
	)
	(segment
		(start 153.3652 -31.79445)
		(end 154.60853 -31.79445)
		(width 0.1143)
		(layer "F.Cu")
		(net "FPGA_SMB_HOST_DATA")
	)
	(segment
		(start 156.464 -29.3878)
		(end 156.464 -30.226)
		(width 0.1143)
		(layer "F.Cu")
		(net "FPGA_SMB_HOST_DATA")
	)
	(segment
		(start 67.31 -60.2742)
		(end 67.31 -58.3438)
		(width 0.1143)
		(layer "F.Cu")
		(net "FPGA_SMB_HOST_DATA")
	)
	(segment
		(start 73.27011 -68.85305)
		(end 70.666356 -68.85305)
		(width 0.1143)
		(layer "F.Cu")
		(net "FPGA_SMB_HOST_DATA")
	)
	(segment
		(start 155.7655 -30.9245)
		(end 156.337 -30.353)
		(width 0.1143)
		(layer "F.Cu")
		(net "FPGA_SMB_HOST_DATA")
	)
	(segment
		(start 68.3514 -64.171322)
		(end 67.91325 -63.733172)
		(width 0.1143)
		(layer "F.Cu")
		(net "FPGA_SMB_HOST_DATA")
	)
	(segment
		(start 154.60853 -31.79445)
		(end 155.47848 -30.9245)
		(width 0.1143)
		(layer "F.Cu")
		(net "FPGA_SMB_HOST_DATA")
	)
	(segment
		(start 156.464 -30.226)
		(end 156.337 -30.353)
		(width 0.1143)
		(layer "F.Cu")
		(net "FPGA_SMB_HOST_DATA")
	)
	(segment
		(start 67.91325 -62.42431)
		(end 67.564 -62.07506)
		(width 0.1143)
		(layer "F.Cu")
		(net "FPGA_SMB_HOST_DATA")
	)
	(segment
		(start 68.3514 -66.538094)
		(end 68.3514 -64.171322)
		(width 0.1143)
		(layer "F.Cu")
		(net "FPGA_SMB_HOST_DATA")
	)
	(segment
		(start 155.47848 -30.9245)
		(end 155.7655 -30.9245)
		(width 0.1143)
		(layer "F.Cu")
		(net "FPGA_SMB_HOST_DATA")
	)
	(via
		(at 119.126 -69.9008)
		(size 0.508)
		(drill 0.254)
		(layers "F.Cu" "B.Cu")
		(net "FPGA_SMB_HOST_DATA")
	)
	(via
		(at 156.337 -30.353)
		(size 0.7112)
		(drill 0.3556)
		(layers "F.Cu" "B.Cu")
		(net "FPGA_SMB_HOST_DATA")
	)
	(via
		(at 155.47848 -30.9245)
		(size 0.508)
		(drill 0.254)
		(layers "F.Cu" "B.Cu")
		(net "FPGA_SMB_HOST_DATA")
	)
	(via
		(at 79.711296 -71.18477)
		(size 0.508)
		(drill 0.254)
		(layers "F.Cu" "B.Cu")
		(net "FPGA_SMB_HOST_DATA")
	)
	(segment
		(start 116.541296 -72.485504)
		(end 80.588104 -72.485504)
		(width 0.1143)
		(layer "B.Cu")
		(net "FPGA_SMB_HOST_DATA")
	)
	(segment
		(start 79.711296 -71.608696)
		(end 79.711296 -71.18477)
		(width 0.1143)
		(layer "B.Cu")
		(net "FPGA_SMB_HOST_DATA")
	)
	(segment
		(start 80.588104 -72.485504)
		(end 79.711296 -71.608696)
		(width 0.1143)
		(layer "B.Cu")
		(net "FPGA_SMB_HOST_DATA")
	)
	(segment
		(start 119.126 -69.9008)
		(end 116.541296 -72.485504)
		(width 0.1143)
		(layer "B.Cu")
		(net "FPGA_SMB_HOST_DATA")
	)
	(segment
		(start 189.501526 -70.859904)
		(end 190.623698 -69.737732)
		(width 0.0889)
		(layer "In7.Cu")
		(net "FPGA_SMB_HOST_DATA")
	)
	(segment
		(start 166.878 -29.21)
		(end 163.7538 -29.21)
		(width 0.0889)
		(layer "In7.Cu")
		(net "FPGA_SMB_HOST_DATA")
	)
	(segment
		(start 176.7078 -42.91076)
		(end 169.38752 -35.59048)
		(width 0.0889)
		(layer "In7.Cu")
		(net "FPGA_SMB_HOST_DATA")
	)
	(segment
		(start 163.7538 -29.21)
		(end 160.4518 -32.512)
		(width 0.0889)
		(layer "In7.Cu")
		(net "FPGA_SMB_HOST_DATA")
	)
	(segment
		(start 169.38752 -35.59048)
		(end 169.38752 -31.71952)
		(width 0.0889)
		(layer "In7.Cu")
		(net "FPGA_SMB_HOST_DATA")
	)
	(segment
		(start 156.36748 -32.512)
		(end 155.47848 -31.623)
		(width 0.0889)
		(layer "In7.Cu")
		(net "FPGA_SMB_HOST_DATA")
	)
	(segment
		(start 185.73115 -54.46649)
		(end 181.03596 -49.7713)
		(width 0.0889)
		(layer "In7.Cu")
		(net "FPGA_SMB_HOST_DATA")
	)
	(segment
		(start 160.4518 -32.512)
		(end 156.36748 -32.512)
		(width 0.0889)
		(layer "In7.Cu")
		(net "FPGA_SMB_HOST_DATA")
	)
	(segment
		(start 191.135 -65.659)
		(end 191.135 -62.644274)
		(width 0.0889)
		(layer "In7.Cu")
		(net "FPGA_SMB_HOST_DATA")
	)
	(segment
		(start 120.085104 -70.859904)
		(end 189.501526 -70.859904)
		(width 0.0889)
		(layer "In7.Cu")
		(net "FPGA_SMB_HOST_DATA")
	)
	(segment
		(start 119.126 -69.9008)
		(end 120.085104 -70.859904)
		(width 0.0889)
		(layer "In7.Cu")
		(net "FPGA_SMB_HOST_DATA")
	)
	(segment
		(start 185.73115 -57.240424)
		(end 185.73115 -54.46649)
		(width 0.0889)
		(layer "In7.Cu")
		(net "FPGA_SMB_HOST_DATA")
	)
	(segment
		(start 179.60086 -49.7713)
		(end 176.7078 -46.87824)
		(width 0.0889)
		(layer "In7.Cu")
		(net "FPGA_SMB_HOST_DATA")
	)
	(segment
		(start 190.623698 -69.737732)
		(end 190.623698 -66.170302)
		(width 0.0889)
		(layer "In7.Cu")
		(net "FPGA_SMB_HOST_DATA")
	)
	(segment
		(start 181.03596 -49.7713)
		(end 179.60086 -49.7713)
		(width 0.0889)
		(layer "In7.Cu")
		(net "FPGA_SMB_HOST_DATA")
	)
	(segment
		(start 176.7078 -46.87824)
		(end 176.7078 -42.91076)
		(width 0.0889)
		(layer "In7.Cu")
		(net "FPGA_SMB_HOST_DATA")
	)
	(segment
		(start 169.38752 -31.71952)
		(end 166.878 -29.21)
		(width 0.0889)
		(layer "In7.Cu")
		(net "FPGA_SMB_HOST_DATA")
	)
	(segment
		(start 190.623698 -66.170302)
		(end 191.135 -65.659)
		(width 0.0889)
		(layer "In7.Cu")
		(net "FPGA_SMB_HOST_DATA")
	)
	(segment
		(start 155.47848 -31.623)
		(end 155.47848 -30.9245)
		(width 0.0889)
		(layer "In7.Cu")
		(net "FPGA_SMB_HOST_DATA")
	)
	(segment
		(start 191.135 -62.644274)
		(end 185.73115 -57.240424)
		(width 0.0889)
		(layer "In7.Cu")
		(net "FPGA_SMB_HOST_DATA")
	)
	(segment
		(start 154.52344 -30.23616)
		(end 154.8384 -29.9212)
		(width 0.1143)
		(layer "F.Cu")
		(net "FPGA_SMB_HOST_CLK")
	)
	(segment
		(start 66.802 -60.071)
		(end 66.802 -58.0898)
		(width 0.1143)
		(layer "F.Cu")
		(net "FPGA_SMB_HOST_CLK")
	)
	(segment
		(start 76.915264 -68.5292)
		(end 74.294746 -68.5292)
		(width 0.1143)
		(layer "F.Cu")
		(net "FPGA_SMB_HOST_CLK")
	)
	(segment
		(start 74.294746 -68.5292)
		(end 73.361296 -69.46265)
		(width 0.1143)
		(layer "F.Cu")
		(net "FPGA_SMB_HOST_CLK")
	)
	(segment
		(start 67.41795 -66.305176)
		(end 67.41795 -63.993522)
		(width 0.1143)
		(layer "F.Cu")
		(net "FPGA_SMB_HOST_CLK")
	)
	(segment
		(start 154.16657 -31.29407)
		(end 154.52344 -30.9372)
		(width 0.1143)
		(layer "F.Cu")
		(net "FPGA_SMB_HOST_CLK")
	)
	(segment
		(start 66.97345 -61.76645)
		(end 66.49085 -61.28385)
		(width 0.1143)
		(layer "F.Cu")
		(net "FPGA_SMB_HOST_CLK")
	)
	(segment
		(start 70.575424 -69.46265)
		(end 67.41795 -66.305176)
		(width 0.1143)
		(layer "F.Cu")
		(net "FPGA_SMB_HOST_CLK")
	)
	(segment
		(start 66.49085 -60.38215)
		(end 66.802 -60.071)
		(width 0.1143)
		(layer "F.Cu")
		(net "FPGA_SMB_HOST_CLK")
	)
	(segment
		(start 153.3652 -31.29407)
		(end 154.16657 -31.29407)
		(width 0.1143)
		(layer "F.Cu")
		(net "FPGA_SMB_HOST_CLK")
	)
	(segment
		(start 66.49085 -61.28385)
		(end 66.49085 -60.38215)
		(width 0.1143)
		(layer "F.Cu")
		(net "FPGA_SMB_HOST_CLK")
	)
	(segment
		(start 154.52344 -30.9372)
		(end 154.52344 -30.23616)
		(width 0.1143)
		(layer "F.Cu")
		(net "FPGA_SMB_HOST_CLK")
	)
	(segment
		(start 67.41795 -63.993522)
		(end 66.97345 -63.549022)
		(width 0.1143)
		(layer "F.Cu")
		(net "FPGA_SMB_HOST_CLK")
	)
	(segment
		(start 155.1686 -29.9212)
		(end 154.8384 -29.9212)
		(width 0.1143)
		(layer "F.Cu")
		(net "FPGA_SMB_HOST_CLK")
	)
	(segment
		(start 73.361296 -69.46265)
		(end 70.575424 -69.46265)
		(width 0.1143)
		(layer "F.Cu")
		(net "FPGA_SMB_HOST_CLK")
	)
	(segment
		(start 78.947264 -70.5612)
		(end 76.915264 -68.5292)
		(width 0.1143)
		(layer "F.Cu")
		(net "FPGA_SMB_HOST_CLK")
	)
	(segment
		(start 66.97345 -63.549022)
		(end 66.97345 -61.76645)
		(width 0.1143)
		(layer "F.Cu")
		(net "FPGA_SMB_HOST_CLK")
	)
	(segment
		(start 79.0702 -70.5612)
		(end 78.947264 -70.5612)
		(width 0.1143)
		(layer "F.Cu")
		(net "FPGA_SMB_HOST_CLK")
	)
	(segment
		(start 155.702 -29.3878)
		(end 155.1686 -29.9212)
		(width 0.1143)
		(layer "F.Cu")
		(net "FPGA_SMB_HOST_CLK")
	)
	(via
		(at 79.0702 -70.5612)
		(size 0.508)
		(drill 0.254)
		(layers "F.Cu" "B.Cu")
		(net "FPGA_SMB_HOST_CLK")
	)
	(via
		(at 154.8384 -29.9212)
		(size 0.7112)
		(drill 0.3556)
		(layers "F.Cu" "B.Cu")
		(net "FPGA_SMB_HOST_CLK")
	)
	(via
		(at 119.9896 -69.8754)
		(size 0.508)
		(drill 0.254)
		(layers "F.Cu" "B.Cu")
		(net "FPGA_SMB_HOST_CLK")
	)
	(via
		(at 154.52344 -30.9372)
		(size 0.508)
		(drill 0.254)
		(layers "F.Cu" "B.Cu")
		(net "FPGA_SMB_HOST_CLK")
	)
	(segment
		(start 116.884196 -72.980804)
		(end 80.372204 -72.980804)
		(width 0.1143)
		(layer "B.Cu")
		(net "FPGA_SMB_HOST_CLK")
	)
	(segment
		(start 119.9896 -69.8754)
		(end 116.884196 -72.980804)
		(width 0.1143)
		(layer "B.Cu")
		(net "FPGA_SMB_HOST_CLK")
	)
	(segment
		(start 79.0702 -71.6788)
		(end 79.0702 -70.5612)
		(width 0.1143)
		(layer "B.Cu")
		(net "FPGA_SMB_HOST_CLK")
	)
	(segment
		(start 80.372204 -72.980804)
		(end 79.0702 -71.6788)
		(width 0.1143)
		(layer "B.Cu")
		(net "FPGA_SMB_HOST_CLK")
	)
	(segment
		(start 119.9896 -69.8754)
		(end 120.504204 -70.390004)
		(width 0.0889)
		(layer "In7.Cu")
		(net "FPGA_SMB_HOST_CLK")
	)
	(segment
		(start 185.250074 -54.66588)
		(end 180.83657 -50.252376)
		(width 0.0889)
		(layer "In7.Cu")
		(net "FPGA_SMB_HOST_CLK")
	)
	(segment
		(start 156.1338 -33.0708)
		(end 154.52344 -31.46044)
		(width 0.0889)
		(layer "In7.Cu")
		(net "FPGA_SMB_HOST_CLK")
	)
	(segment
		(start 190.153798 -69.637402)
		(end 190.153798 -65.975484)
		(width 0.0889)
		(layer "In7.Cu")
		(net "FPGA_SMB_HOST_CLK")
	)
	(segment
		(start 166.624 -29.718)
		(end 164.107876 -29.718)
		(width 0.0889)
		(layer "In7.Cu")
		(net "FPGA_SMB_HOST_CLK")
	)
	(segment
		(start 168.85666 -31.95066)
		(end 166.624 -29.718)
		(width 0.0889)
		(layer "In7.Cu")
		(net "FPGA_SMB_HOST_CLK")
	)
	(segment
		(start 168.85666 -35.740086)
		(end 168.85666 -31.95066)
		(width 0.0889)
		(layer "In7.Cu")
		(net "FPGA_SMB_HOST_CLK")
	)
	(segment
		(start 176.2379 -43.121326)
		(end 168.85666 -35.740086)
		(width 0.0889)
		(layer "In7.Cu")
		(net "FPGA_SMB_HOST_CLK")
	)
	(segment
		(start 160.755076 -33.0708)
		(end 156.1338 -33.0708)
		(width 0.0889)
		(layer "In7.Cu")
		(net "FPGA_SMB_HOST_CLK")
	)
	(segment
		(start 190.6651 -65.464182)
		(end 190.6651 -62.839092)
		(width 0.0889)
		(layer "In7.Cu")
		(net "FPGA_SMB_HOST_CLK")
	)
	(segment
		(start 154.52344 -31.46044)
		(end 154.52344 -30.9372)
		(width 0.0889)
		(layer "In7.Cu")
		(net "FPGA_SMB_HOST_CLK")
	)
	(segment
		(start 120.504204 -70.390004)
		(end 189.401196 -70.390004)
		(width 0.0889)
		(layer "In7.Cu")
		(net "FPGA_SMB_HOST_CLK")
	)
	(segment
		(start 190.6651 -62.839092)
		(end 185.250074 -57.424066)
		(width 0.0889)
		(layer "In7.Cu")
		(net "FPGA_SMB_HOST_CLK")
	)
	(segment
		(start 189.401196 -70.390004)
		(end 190.153798 -69.637402)
		(width 0.0889)
		(layer "In7.Cu")
		(net "FPGA_SMB_HOST_CLK")
	)
	(segment
		(start 179.40147 -50.252376)
		(end 176.2379 -47.088806)
		(width 0.0889)
		(layer "In7.Cu")
		(net "FPGA_SMB_HOST_CLK")
	)
	(segment
		(start 190.153798 -65.975484)
		(end 190.6651 -65.464182)
		(width 0.0889)
		(layer "In7.Cu")
		(net "FPGA_SMB_HOST_CLK")
	)
	(segment
		(start 185.250074 -57.424066)
		(end 185.250074 -54.66588)
		(width 0.0889)
		(layer "In7.Cu")
		(net "FPGA_SMB_HOST_CLK")
	)
	(segment
		(start 180.83657 -50.252376)
		(end 179.40147 -50.252376)
		(width 0.0889)
		(layer "In7.Cu")
		(net "FPGA_SMB_HOST_CLK")
	)
	(segment
		(start 164.107876 -29.718)
		(end 160.755076 -33.0708)
		(width 0.0889)
		(layer "In7.Cu")
		(net "FPGA_SMB_HOST_CLK")
	)
	(segment
		(start 176.2379 -47.088806)
		(end 176.2379 -43.121326)
		(width 0.0889)
		(layer "In7.Cu")
		(net "FPGA_SMB_HOST_CLK")
	)
	(segment
		(start 67.3989 -54.353968)
		(end 67.3989 -52.707032)
		(width 0.1143)
		(layer "F.Cu")
		(net "FPGA_SMB_HOST_R_CLK")
	)
	(segment
		(start 66.6496 -50.833274)
		(end 65.256156 -49.43983)
		(width 0.1143)
		(layer "F.Cu")
		(net "FPGA_SMB_HOST_R_CLK")
	)
	(segment
		(start 63.10122 -46.863)
		(end 63.10122 -45.8216)
		(width 0.1143)
		(layer "F.Cu")
		(net "FPGA_SMB_HOST_R_CLK")
	)
	(segment
		(start 63.32855 -48.60925)
		(end 63.32855 -47.09033)
		(width 0.1143)
		(layer "F.Cu")
		(net "FPGA_SMB_HOST_R_CLK")
	)
	(segment
		(start 67.87134 -55.19166)
		(end 67.87134 -54.826408)
		(width 0.1143)
		(layer "F.Cu")
		(net "FPGA_SMB_HOST_R_CLK")
	)
	(segment
		(start 67.3989 -52.707032)
		(end 66.6496 -51.957732)
		(width 0.1143)
		(layer "F.Cu")
		(net "FPGA_SMB_HOST_R_CLK")
	)
	(segment
		(start 67.87134 -54.826408)
		(end 67.3989 -54.353968)
		(width 0.1143)
		(layer "F.Cu")
		(net "FPGA_SMB_HOST_R_CLK")
	)
	(segment
		(start 65.256156 -49.43983)
		(end 64.15913 -49.43983)
		(width 0.1143)
		(layer "F.Cu")
		(net "FPGA_SMB_HOST_R_CLK")
	)
	(segment
		(start 66.6496 -51.957732)
		(end 66.6496 -50.833274)
		(width 0.1143)
		(layer "F.Cu")
		(net "FPGA_SMB_HOST_R_CLK")
	)
	(segment
		(start 64.15913 -49.43983)
		(end 63.32855 -48.60925)
		(width 0.1143)
		(layer "F.Cu")
		(net "FPGA_SMB_HOST_R_CLK")
	)
	(segment
		(start 63.32855 -47.09033)
		(end 63.10122 -46.863)
		(width 0.1143)
		(layer "F.Cu")
		(net "FPGA_SMB_HOST_R_CLK")
	)
	(segment
		(start 66.802 -56.261)
		(end 66.802 -57.2262)
		(width 0.1143)
		(layer "F.Cu")
		(net "FPGA_SMB_HOST_R_CLK")
	)
	(segment
		(start 66.802 -56.261)
		(end 67.87134 -55.19166)
		(width 0.1143)
		(layer "F.Cu")
		(net "FPGA_SMB_HOST_R_CLK")
	)
	(via
		(at 66.802 -56.261)
		(size 0.7112)
		(drill 0.3556)
		(layers "F.Cu" "B.Cu")
		(net "FPGA_SMB_HOST_R_CLK")
	)
	(segment
		(start 64.10198 -45.8216)
		(end 64.10198 -46.432724)
		(width 0.1143)
		(layer "F.Cu")
		(net "FPGA_SMB_HOST_R_DATA")
	)
	(segment
		(start 63.8429 -48.37811)
		(end 64.40932 -48.94453)
		(width 0.1143)
		(layer "F.Cu")
		(net "FPGA_SMB_HOST_R_DATA")
	)
	(segment
		(start 67.1449 -50.628042)
		(end 67.1449 -51.7525)
		(width 0.1143)
		(layer "F.Cu")
		(net "FPGA_SMB_HOST_R_DATA")
	)
	(segment
		(start 64.40932 -48.94453)
		(end 65.461388 -48.94453)
		(width 0.1143)
		(layer "F.Cu")
		(net "FPGA_SMB_HOST_R_DATA")
	)
	(segment
		(start 67.8942 -54.148736)
		(end 68.36664 -54.621176)
		(width 0.1143)
		(layer "F.Cu")
		(net "FPGA_SMB_HOST_R_DATA")
	)
	(segment
		(start 68.36664 -54.621176)
		(end 68.36664 -55.498746)
		(width 0.1143)
		(layer "F.Cu")
		(net "FPGA_SMB_HOST_R_DATA")
	)
	(segment
		(start 67.564 -57.2262)
		(end 67.564 -56.3118)
		(width 0.1143)
		(layer "F.Cu")
		(net "FPGA_SMB_HOST_R_DATA")
	)
	(segment
		(start 67.564 -56.3118)
		(end 68.2244 -55.6514)
		(width 0.1143)
		(layer "F.Cu")
		(net "FPGA_SMB_HOST_R_DATA")
	)
	(segment
		(start 68.2244 -55.6514)
		(end 68.2244 -55.640986)
		(width 0.1143)
		(layer "F.Cu")
		(net "FPGA_SMB_HOST_R_DATA")
	)
	(segment
		(start 67.1449 -51.7525)
		(end 67.8942 -52.5018)
		(width 0.1143)
		(layer "F.Cu")
		(net "FPGA_SMB_HOST_R_DATA")
	)
	(segment
		(start 64.10198 -46.432724)
		(end 63.8429 -46.691804)
		(width 0.1143)
		(layer "F.Cu")
		(net "FPGA_SMB_HOST_R_DATA")
	)
	(segment
		(start 68.36664 -55.498746)
		(end 68.2244 -55.640986)
		(width 0.1143)
		(layer "F.Cu")
		(net "FPGA_SMB_HOST_R_DATA")
	)
	(segment
		(start 65.461388 -48.94453)
		(end 67.1449 -50.628042)
		(width 0.1143)
		(layer "F.Cu")
		(net "FPGA_SMB_HOST_R_DATA")
	)
	(segment
		(start 67.8942 -52.5018)
		(end 67.8942 -54.148736)
		(width 0.1143)
		(layer "F.Cu")
		(net "FPGA_SMB_HOST_R_DATA")
	)
	(segment
		(start 63.8429 -46.691804)
		(end 63.8429 -48.37811)
		(width 0.1143)
		(layer "F.Cu")
		(net "FPGA_SMB_HOST_R_DATA")
	)
	(via
		(at 68.2244 -55.640986)
		(size 0.7112)
		(drill 0.3556)
		(layers "F.Cu" "B.Cu")
		(net "FPGA_SMB_HOST_R_DATA")
	)
	(segment
		(start 83.266788 -34.781236)
		(end 82.885788 -35.162236)
		(width 0.1143)
		(layer "F.Cu")
		(net "GBE_MDIO_DATA0")
	)
	(segment
		(start 83.266788 -34.757614)
		(end 83.266788 -34.781236)
		(width 0.1143)
		(layer "F.Cu")
		(net "GBE_MDIO_DATA0")
	)
	(via
		(at 82.885788 -35.162236)
		(size 0.4318)
		(drill 0.2032)
		(layers "F.Cu" "B.Cu")
		(net "GBE_MDIO_DATA0")
	)
	(segment
		(start 75.819 -32.2326)
		(end 75.5396 -31.9532)
		(width 0.1143)
		(layer "B.Cu")
		(net "GBE_MDIO_DATA0")
	)
	(segment
		(start 82.863944 -35.140392)
		(end 82.885788 -35.162236)
		(width 0.1143)
		(layer "B.Cu")
		(net "GBE_MDIO_DATA0")
	)
	(segment
		(start 76.327 -33.401)
		(end 76.60767 -33.401)
		(width 0.1143)
		(layer "B.Cu")
		(net "GBE_MDIO_DATA0")
	)
	(segment
		(start 79.069692 -34.7218)
		(end 81.187544 -34.7218)
		(width 0.1143)
		(layer "B.Cu")
		(net "GBE_MDIO_DATA0")
	)
	(segment
		(start 77.78242 -34.57575)
		(end 78.923642 -34.57575)
		(width 0.1143)
		(layer "B.Cu")
		(net "GBE_MDIO_DATA0")
	)
	(segment
		(start 75.819 -32.893)
		(end 76.327 -33.401)
		(width 0.1143)
		(layer "B.Cu")
		(net "GBE_MDIO_DATA0")
	)
	(segment
		(start 76.60767 -33.401)
		(end 77.78242 -34.57575)
		(width 0.1143)
		(layer "B.Cu")
		(net "GBE_MDIO_DATA0")
	)
	(segment
		(start 75.819 -32.893)
		(end 75.819 -32.2326)
		(width 0.1143)
		(layer "B.Cu")
		(net "GBE_MDIO_DATA0")
	)
	(segment
		(start 78.923642 -34.57575)
		(end 79.069692 -34.7218)
		(width 0.1143)
		(layer "B.Cu")
		(net "GBE_MDIO_DATA0")
	)
	(segment
		(start 81.606136 -35.140392)
		(end 82.863944 -35.140392)
		(width 0.1143)
		(layer "B.Cu")
		(net "GBE_MDIO_DATA0")
	)
	(segment
		(start 81.187544 -34.7218)
		(end 81.606136 -35.140392)
		(width 0.1143)
		(layer "B.Cu")
		(net "GBE_MDIO_DATA0")
	)
	(segment
		(start 75.5396 -31.9532)
		(end 74.676 -31.9532)
		(width 0.1143)
		(layer "B.Cu")
		(net "GBE_MDIO_DATA0")
	)
	(segment
		(start 74.676 -31.9532)
		(end 74.4728 -31.75)
		(width 0.1143)
		(layer "B.Cu")
		(net "GBE_MDIO_DATA0")
	)
	(segment
		(start 84.790788 -34.757614)
		(end 84.790788 -34.775394)
		(width 0.1143)
		(layer "F.Cu")
		(net "GBE_MDIO_CLK0")
	)
	(segment
		(start 84.790788 -34.775394)
		(end 84.449412 -35.11677)
		(width 0.1143)
		(layer "F.Cu")
		(net "GBE_MDIO_CLK0")
	)
	(via
		(at 84.449412 -35.11677)
		(size 0.4318)
		(drill 0.2032)
		(layers "F.Cu" "B.Cu")
		(net "GBE_MDIO_CLK0")
	)
	(segment
		(start 76.6064 -32.788606)
		(end 76.6064 -31.828232)
		(width 0.1143)
		(layer "B.Cu")
		(net "GBE_MDIO_CLK0")
	)
	(segment
		(start 81.714848 -34.26841)
		(end 79.227426 -34.26841)
		(width 0.1143)
		(layer "B.Cu")
		(net "GBE_MDIO_CLK0")
	)
	(segment
		(start 76.6064 -31.828232)
		(end 76.0095 -31.231332)
		(width 0.1143)
		(layer "B.Cu")
		(net "GBE_MDIO_CLK0")
	)
	(segment
		(start 79.096616 -34.1376)
		(end 77.955394 -34.1376)
		(width 0.1143)
		(layer "B.Cu")
		(net "GBE_MDIO_CLK0")
	)
	(segment
		(start 83.212686 -34.571686)
		(end 82.515456 -34.571686)
		(width 0.1143)
		(layer "B.Cu")
		(net "GBE_MDIO_CLK0")
	)
	(segment
		(start 82.118962 -34.175192)
		(end 81.808066 -34.175192)
		(width 0.1143)
		(layer "B.Cu")
		(net "GBE_MDIO_CLK0")
	)
	(segment
		(start 82.515456 -34.571686)
		(end 82.118962 -34.175192)
		(width 0.1143)
		(layer "B.Cu")
		(net "GBE_MDIO_CLK0")
	)
	(segment
		(start 75.4634 -30.226)
		(end 75.565 -30.1244)
		(width 0.1143)
		(layer "B.Cu")
		(net "GBE_MDIO_CLK0")
	)
	(segment
		(start 76.0095 -30.5689)
		(end 75.565 -30.1244)
		(width 0.1143)
		(layer "B.Cu")
		(net "GBE_MDIO_CLK0")
	)
	(segment
		(start 74.4728 -30.226)
		(end 75.4634 -30.226)
		(width 0.1143)
		(layer "B.Cu")
		(net "GBE_MDIO_CLK0")
	)
	(segment
		(start 76.0095 -31.231332)
		(end 76.0095 -30.5689)
		(width 0.1143)
		(layer "B.Cu")
		(net "GBE_MDIO_CLK0")
	)
	(segment
		(start 84.067904 -34.735262)
		(end 83.376262 -34.735262)
		(width 0.1143)
		(layer "B.Cu")
		(net "GBE_MDIO_CLK0")
	)
	(segment
		(start 83.376262 -34.735262)
		(end 83.212686 -34.571686)
		(width 0.1143)
		(layer "B.Cu")
		(net "GBE_MDIO_CLK0")
	)
	(segment
		(start 81.808066 -34.175192)
		(end 81.714848 -34.26841)
		(width 0.1143)
		(layer "B.Cu")
		(net "GBE_MDIO_CLK0")
	)
	(segment
		(start 84.449412 -35.11677)
		(end 84.067904 -34.735262)
		(width 0.1143)
		(layer "B.Cu")
		(net "GBE_MDIO_CLK0")
	)
	(segment
		(start 77.955394 -34.1376)
		(end 76.6064 -32.788606)
		(width 0.1143)
		(layer "B.Cu")
		(net "GBE_MDIO_CLK0")
	)
	(segment
		(start 79.227426 -34.26841)
		(end 79.096616 -34.1376)
		(width 0.1143)
		(layer "B.Cu")
		(net "GBE_MDIO_CLK0")
	)
	(segment
		(start 168.086024 -44.60875)
		(end 168.35755 -44.337224)
		(width 0.1143)
		(layer "F.Cu")
		(net "OSC_5M_CLK_R")
	)
	(segment
		(start 168.239948 -43.652948)
		(end 168.239948 -42.480992)
		(width 0.1143)
		(layer "F.Cu")
		(net "OSC_5M_CLK_R")
	)
	(segment
		(start 168.35755 -43.77055)
		(end 168.239948 -43.652948)
		(width 0.1143)
		(layer "F.Cu")
		(net "OSC_5M_CLK_R")
	)
	(segment
		(start 166.497 -43.9674)
		(end 167.13835 -44.60875)
		(width 0.1143)
		(layer "F.Cu")
		(net "OSC_5M_CLK_R")
	)
	(segment
		(start 168.35755 -44.337224)
		(end 168.35755 -43.77055)
		(width 0.1143)
		(layer "F.Cu")
		(net "OSC_5M_CLK_R")
	)
	(segment
		(start 166.4843 -43.942)
		(end 165.2778 -43.942)
		(width 0.1143)
		(layer "F.Cu")
		(net "OSC_5M_CLK_R")
	)
	(segment
		(start 166.497 -43.9674)
		(end 166.497 -43.9547)
		(width 0.1143)
		(layer "F.Cu")
		(net "OSC_5M_CLK_R")
	)
	(segment
		(start 167.13835 -44.60875)
		(end 168.086024 -44.60875)
		(width 0.1143)
		(layer "F.Cu")
		(net "OSC_5M_CLK_R")
	)
	(segment
		(start 166.497 -43.9547)
		(end 166.4843 -43.942)
		(width 0.1143)
		(layer "F.Cu")
		(net "OSC_5M_CLK_R")
	)
	(via
		(at 166.497 -43.9674)
		(size 0.7112)
		(drill 0.3556)
		(layers "F.Cu" "B.Cu")
		(net "OSC_5M_CLK_R")
	)
	(segment
		(start 165.579044 -40.386)
		(end 166.024052 -40.831008)
		(width 0.1143)
		(layer "F.Cu")
		(net "OSC_5M_EN")
	)
	(segment
		(start 164.084 -40.386)
		(end 165.579044 -40.386)
		(width 0.1143)
		(layer "F.Cu")
		(net "OSC_5M_EN")
	)
	(segment
		(start 163.83 -40.64)
		(end 164.084 -40.386)
		(width 0.1143)
		(layer "F.Cu")
		(net "OSC_5M_EN")
	)
	(segment
		(start 163.83 -41.9862)
		(end 163.83 -40.894)
		(width 0.1143)
		(layer "F.Cu")
		(net "OSC_5M_EN")
	)
	(segment
		(start 163.83 -40.894)
		(end 163.83 -40.64)
		(width 0.1143)
		(layer "F.Cu")
		(net "OSC_5M_EN")
	)
	(via
		(at 163.83 -40.894)
		(size 0.7112)
		(drill 0.3556)
		(layers "F.Cu" "B.Cu")
		(net "OSC_5M_EN")
	)
	(segment
		(start 136.525 -15.5702)
		(end 136.525 -16.468344)
		(width 0.1143)
		(layer "F.Cu")
		(net "HOST_LV_D_RSTBTN#")
	)
	(segment
		(start 135.4455 -15.367)
		(end 136.3218 -15.367)
		(width 0.1143)
		(layer "F.Cu")
		(net "HOST_LV_D_RSTBTN#")
	)
	(segment
		(start 136.3218 -15.367)
		(end 136.525 -15.5702)
		(width 0.1143)
		(layer "F.Cu")
		(net "HOST_LV_D_RSTBTN#")
	)
	(segment
		(start 136.4742 -16.519144)
		(end 136.4742 -17.78)
		(width 0.1143)
		(layer "F.Cu")
		(net "HOST_LV_D_RSTBTN#")
	)
	(segment
		(start 136.07796 -16.01724)
		(end 136.525 -15.5702)
		(width 0.1143)
		(layer "F.Cu")
		(net "HOST_LV_D_RSTBTN#")
	)
	(segment
		(start 136.525 -16.468344)
		(end 136.4742 -16.519144)
		(width 0.1143)
		(layer "F.Cu")
		(net "HOST_LV_D_RSTBTN#")
	)
	(segment
		(start 136.4742 -17.78)
		(end 137.1092 -18.415)
		(width 0.1143)
		(layer "F.Cu")
		(net "HOST_LV_D_RSTBTN#")
	)
	(segment
		(start 135.4455 -16.01724)
		(end 136.07796 -16.01724)
		(width 0.1143)
		(layer "F.Cu")
		(net "HOST_LV_D_RSTBTN#")
	)
	(via
		(at 136.4742 -16.519144)
		(size 0.7112)
		(drill 0.3556)
		(layers "F.Cu" "B.Cu")
		(net "HOST_LV_D_RSTBTN#")
	)
	(segment
		(start 70.29196 -13.47724)
		(end 71.136256 -13.47724)
		(width 0.1143)
		(layer "F.Cu")
		(net "HOST_LV_RSTBTN#")
	)
	(segment
		(start 80.086962 -11.3665)
		(end 80.410812 -11.04265)
		(width 0.1143)
		(layer "F.Cu")
		(net "HOST_LV_RSTBTN#")
	)
	(segment
		(start 128.541526 -11.431778)
		(end 120.367044 -3.257296)
		(width 0.1143)
		(layer "F.Cu")
		(net "HOST_LV_RSTBTN#")
	)
	(segment
		(start 71.136256 -13.47724)
		(end 73.246996 -11.3665)
		(width 0.1143)
		(layer "F.Cu")
		(net "HOST_LV_RSTBTN#")
	)
	(segment
		(start 120.367044 -3.257296)
		(end 118.30685 -3.257296)
		(width 0.1143)
		(layer "F.Cu")
		(net "HOST_LV_RSTBTN#")
	)
	(segment
		(start 70.29196 -14.77264)
		(end 70.01891 -15.04569)
		(width 0.1143)
		(layer "F.Cu")
		(net "HOST_LV_RSTBTN#")
	)
	(segment
		(start 133.7945 -14.71676)
		(end 133.7945 -14.492478)
		(width 0.1143)
		(layer "F.Cu")
		(net "HOST_LV_RSTBTN#")
	)
	(segment
		(start 70.01891 -15.04569)
		(end 67.81165 -15.04569)
		(width 0.1143)
		(layer "F.Cu")
		(net "HOST_LV_RSTBTN#")
	)
	(segment
		(start 70.29196 -13.47724)
		(end 70.29196 -14.77264)
		(width 0.1143)
		(layer "F.Cu")
		(net "HOST_LV_RSTBTN#")
	)
	(segment
		(start 73.246996 -11.3665)
		(end 80.086962 -11.3665)
		(width 0.1143)
		(layer "F.Cu")
		(net "HOST_LV_RSTBTN#")
	)
	(segment
		(start 130.7338 -11.431778)
		(end 128.541526 -11.431778)
		(width 0.1143)
		(layer "F.Cu")
		(net "HOST_LV_RSTBTN#")
	)
	(segment
		(start 116.1034 -1.4986)
		(end 117.665246 -3.060446)
		(width 0.1143)
		(layer "F.Cu")
		(net "HOST_LV_RSTBTN#")
	)
	(segment
		(start 133.7945 -14.492478)
		(end 130.7338 -11.431778)
		(width 0.1143)
		(layer "F.Cu")
		(net "HOST_LV_RSTBTN#")
	)
	(segment
		(start 117.665246 -3.060446)
		(end 118.11 -3.060446)
		(width 0.1143)
		(layer "F.Cu")
		(net "HOST_LV_RSTBTN#")
	)
	(segment
		(start 67.81165 -15.04569)
		(end 67.4878 -14.72184)
		(width 0.1143)
		(layer "F.Cu")
		(net "HOST_LV_RSTBTN#")
	)
	(segment
		(start 114.1984 -1.4986)
		(end 116.1034 -1.4986)
		(width 0.1143)
		(layer "F.Cu")
		(net "HOST_LV_RSTBTN#")
	)
	(segment
		(start 80.410812 -11.04265)
		(end 80.879188 -11.04265)
		(width 0.1143)
		(layer "F.Cu")
		(net "HOST_LV_RSTBTN#")
	)
	(segment
		(start 118.30685 -3.257296)
		(end 118.11 -3.060446)
		(width 0.1143)
		(layer "F.Cu")
		(net "HOST_LV_RSTBTN#")
	)
	(segment
		(start 80.879188 -11.04265)
		(end 81.012538 -11.176)
		(width 0.1143)
		(layer "F.Cu")
		(net "HOST_LV_RSTBTN#")
	)
	(segment
		(start 67.4878 -14.72184)
		(end 67.4878 -13.462)
		(width 0.1143)
		(layer "F.Cu")
		(net "HOST_LV_RSTBTN#")
	)
	(segment
		(start 81.012538 -11.176)
		(end 81.7626 -11.176)
		(width 0.1143)
		(layer "F.Cu")
		(net "HOST_LV_RSTBTN#")
	)
	(via
		(at 114.1984 -1.4986)
		(size 0.508)
		(drill 0.254)
		(layers "F.Cu" "B.Cu")
		(net "HOST_LV_RSTBTN#")
	)
	(via
		(at 118.11 -3.060446)
		(size 0.7112)
		(drill 0.3556)
		(layers "F.Cu" "B.Cu")
		(net "HOST_LV_RSTBTN#")
	)
	(via
		(at 81.7626 -11.176)
		(size 0.508)
		(drill 0.254)
		(layers "F.Cu" "B.Cu")
		(net "HOST_LV_RSTBTN#")
	)
	(segment
		(start 113.74755 -1.94945)
		(end 114.1984 -1.4986)
		(width 0.0889)
		(layer "In9.Cu")
		(net "HOST_LV_RSTBTN#")
	)
	(segment
		(start 81.7626 -11.176)
		(end 81.788 -11.1506)
		(width 0.0889)
		(layer "In9.Cu")
		(net "HOST_LV_RSTBTN#")
	)
	(segment
		(start 106.819446 -1.3081)
		(end 112.506506 -1.3081)
		(width 0.0889)
		(layer "In9.Cu")
		(net "HOST_LV_RSTBTN#")
	)
	(segment
		(start 112.506506 -1.3081)
		(end 113.147856 -1.94945)
		(width 0.0889)
		(layer "In9.Cu")
		(net "HOST_LV_RSTBTN#")
	)
	(segment
		(start 113.147856 -1.94945)
		(end 113.74755 -1.94945)
		(width 0.0889)
		(layer "In9.Cu")
		(net "HOST_LV_RSTBTN#")
	)
	(segment
		(start 90.743024 -11.6078)
		(end 91.689174 -12.55395)
		(width 0.0889)
		(layer "In9.Cu")
		(net "HOST_LV_RSTBTN#")
	)
	(segment
		(start 85.979 -12.319)
		(end 87.920576 -12.319)
		(width 0.0889)
		(layer "In9.Cu")
		(net "HOST_LV_RSTBTN#")
	)
	(segment
		(start 106.200194 -1.927352)
		(end 106.819446 -1.3081)
		(width 0.0889)
		(layer "In9.Cu")
		(net "HOST_LV_RSTBTN#")
	)
	(segment
		(start 104.911398 -12.900406)
		(end 106.200194 -11.61161)
		(width 0.0889)
		(layer "In9.Cu")
		(net "HOST_LV_RSTBTN#")
	)
	(segment
		(start 96.22409 -12.55395)
		(end 96.570546 -12.900406)
		(width 0.0889)
		(layer "In9.Cu")
		(net "HOST_LV_RSTBTN#")
	)
	(segment
		(start 106.200194 -11.61161)
		(end 106.200194 -1.927352)
		(width 0.0889)
		(layer "In9.Cu")
		(net "HOST_LV_RSTBTN#")
	)
	(segment
		(start 88.631776 -11.6078)
		(end 90.743024 -11.6078)
		(width 0.0889)
		(layer "In9.Cu")
		(net "HOST_LV_RSTBTN#")
	)
	(segment
		(start 87.920576 -12.319)
		(end 88.631776 -11.6078)
		(width 0.0889)
		(layer "In9.Cu")
		(net "HOST_LV_RSTBTN#")
	)
	(segment
		(start 81.788 -11.1506)
		(end 84.8106 -11.1506)
		(width 0.0889)
		(layer "In9.Cu")
		(net "HOST_LV_RSTBTN#")
	)
	(segment
		(start 84.8106 -11.1506)
		(end 85.979 -12.319)
		(width 0.0889)
		(layer "In9.Cu")
		(net "HOST_LV_RSTBTN#")
	)
	(segment
		(start 96.570546 -12.900406)
		(end 104.911398 -12.900406)
		(width 0.0889)
		(layer "In9.Cu")
		(net "HOST_LV_RSTBTN#")
	)
	(segment
		(start 91.689174 -12.55395)
		(end 96.22409 -12.55395)
		(width 0.0889)
		(layer "In9.Cu")
		(net "HOST_LV_RSTBTN#")
	)
	(segment
		(start 135.98398 -22.18436)
		(end 135.98398 -20.74418)
		(width 0.1143)
		(layer "F.Cu")
		(net "HOST_RSTBTN#")
	)
	(segment
		(start 135.8392 -20.5994)
		(end 135.8392 -20.3708)
		(width 0.1143)
		(layer "F.Cu")
		(net "HOST_RSTBTN#")
	)
	(segment
		(start 136.129268 -22.329648)
		(end 135.98398 -22.18436)
		(width 0.1143)
		(layer "F.Cu")
		(net "HOST_RSTBTN#")
	)
	(segment
		(start 136.271 -19.939)
		(end 136.271 -19.2278)
		(width 0.1143)
		(layer "F.Cu")
		(net "HOST_RSTBTN#")
	)
	(segment
		(start 135.99795 -23.269956)
		(end 136.129268 -23.138638)
		(width 0.1143)
		(layer "F.Cu")
		(net "HOST_RSTBTN#")
	)
	(segment
		(start 135.8392 -20.3708)
		(end 136.271 -19.939)
		(width 0.1143)
		(layer "F.Cu")
		(net "HOST_RSTBTN#")
	)
	(segment
		(start 135.99795 -23.9268)
		(end 135.99795 -23.269956)
		(width 0.1143)
		(layer "F.Cu")
		(net "HOST_RSTBTN#")
	)
	(segment
		(start 135.98398 -20.74418)
		(end 135.8392 -20.5994)
		(width 0.1143)
		(layer "F.Cu")
		(net "HOST_RSTBTN#")
	)
	(segment
		(start 136.129268 -23.138638)
		(end 136.129268 -22.329648)
		(width 0.1143)
		(layer "F.Cu")
		(net "HOST_RSTBTN#")
	)
	(via
		(at 135.8392 -20.5994)
		(size 0.7112)
		(drill 0.3556)
		(layers "F.Cu" "B.Cu")
		(net "HOST_RSTBTN#")
	)
	(segment
		(start 136.271 -18.288)
		(end 135.128 -17.145)
		(width 0.1143)
		(layer "F.Cu")
		(net "HOST_R_RSTBTN#")
	)
	(segment
		(start 133.12775 -15.762986)
		(end 133.12775 -16.271494)
		(width 0.1143)
		(layer "F.Cu")
		(net "HOST_R_RSTBTN#")
	)
	(segment
		(start 133.7945 -15.367)
		(end 133.523736 -15.367)
		(width 0.1143)
		(layer "F.Cu")
		(net "HOST_R_RSTBTN#")
	)
	(segment
		(start 133.523736 -15.367)
		(end 133.12775 -15.762986)
		(width 0.1143)
		(layer "F.Cu")
		(net "HOST_R_RSTBTN#")
	)
	(segment
		(start 137.0838 -19.177)
		(end 136.271 -18.3642)
		(width 0.1143)
		(layer "F.Cu")
		(net "HOST_R_RSTBTN#")
	)
	(segment
		(start 137.1092 -19.177)
		(end 137.0838 -19.177)
		(width 0.1143)
		(layer "F.Cu")
		(net "HOST_R_RSTBTN#")
	)
	(segment
		(start 133.620256 -16.764)
		(end 134.747 -16.764)
		(width 0.1143)
		(layer "F.Cu")
		(net "HOST_R_RSTBTN#")
	)
	(segment
		(start 134.747 -16.764)
		(end 135.128 -17.145)
		(width 0.1143)
		(layer "F.Cu")
		(net "HOST_R_RSTBTN#")
	)
	(segment
		(start 136.271 -18.3642)
		(end 136.271 -18.288)
		(width 0.1143)
		(layer "F.Cu")
		(net "HOST_R_RSTBTN#")
	)
	(segment
		(start 133.12775 -16.271494)
		(end 133.620256 -16.764)
		(width 0.1143)
		(layer "F.Cu")
		(net "HOST_R_RSTBTN#")
	)
	(via
		(at 135.128 -17.145)
		(size 0.7112)
		(drill 0.3556)
		(layers "F.Cu" "B.Cu")
		(net "HOST_R_RSTBTN#")
	)
	(segment
		(start 34.275014 -32.55645)
		(end 35.266122 -32.55645)
		(width 0.1143)
		(layer "F.Cu")
		(net "XDP_CPU_R_TDO")
	)
	(segment
		(start 33.360614 -32.801814)
		(end 34.02965 -32.801814)
		(width 0.1143)
		(layer "F.Cu")
		(net "XDP_CPU_R_TDO")
	)
	(segment
		(start 33.1724 -32.6136)
		(end 33.360614 -32.801814)
		(width 0.1143)
		(layer "F.Cu")
		(net "XDP_CPU_R_TDO")
	)
	(segment
		(start 35.267392 -32.55518)
		(end 36.37788 -32.55518)
		(width 0.1143)
		(layer "F.Cu")
		(net "XDP_CPU_R_TDO")
	)
	(segment
		(start 34.02965 -32.801814)
		(end 34.275014 -32.55645)
		(width 0.1143)
		(layer "F.Cu")
		(net "XDP_CPU_R_TDO")
	)
	(segment
		(start 35.266122 -32.55645)
		(end 35.267392 -32.55518)
		(width 0.1143)
		(layer "F.Cu")
		(net "XDP_CPU_R_TDO")
	)
	(via
		(at 22.098 -15.621)
		(size 0.7112)
		(drill 0.3556)
		(layers "F.Cu" "B.Cu")
		(net "XDP_CPU_R_TDO")
	)
	(via
		(at 23.0124 -16.0528)
		(size 0.508)
		(drill 0.254)
		(layers "F.Cu" "B.Cu")
		(net "XDP_CPU_R_TDO")
	)
	(via
		(at 34.02965 -32.801814)
		(size 0.508)
		(drill 0.254)
		(layers "F.Cu" "B.Cu")
		(net "XDP_CPU_R_TDO")
	)
	(segment
		(start 22.5806 -15.621)
		(end 23.0124 -16.0528)
		(width 0.1143)
		(layer "B.Cu")
		(net "XDP_CPU_R_TDO")
	)
	(segment
		(start 22.098 -15.621)
		(end 22.5806 -15.621)
		(width 0.1143)
		(layer "B.Cu")
		(net "XDP_CPU_R_TDO")
	)
	(segment
		(start 23.0124 -19.666712)
		(end 23.0124 -16.0528)
		(width 0.0889)
		(layer "In9.Cu")
		(net "XDP_CPU_R_TDO")
	)
	(segment
		(start 28.67025 -23.42515)
		(end 25.654 -20.4089)
		(width 0.0889)
		(layer "In9.Cu")
		(net "XDP_CPU_R_TDO")
	)
	(segment
		(start 34.02965 -32.801814)
		(end 33.192466 -32.801814)
		(width 0.0889)
		(layer "In9.Cu")
		(net "XDP_CPU_R_TDO")
	)
	(segment
		(start 28.67025 -31.31185)
		(end 28.67025 -23.42515)
		(width 0.0889)
		(layer "In9.Cu")
		(net "XDP_CPU_R_TDO")
	)
	(segment
		(start 25.654 -20.4089)
		(end 23.754588 -20.4089)
		(width 0.0889)
		(layer "In9.Cu")
		(net "XDP_CPU_R_TDO")
	)
	(segment
		(start 29.713174 -32.354774)
		(end 28.67025 -31.31185)
		(width 0.0889)
		(layer "In9.Cu")
		(net "XDP_CPU_R_TDO")
	)
	(segment
		(start 23.754588 -20.4089)
		(end 23.0124 -19.666712)
		(width 0.0889)
		(layer "In9.Cu")
		(net "XDP_CPU_R_TDO")
	)
	(segment
		(start 32.745426 -32.354774)
		(end 29.713174 -32.354774)
		(width 0.0889)
		(layer "In9.Cu")
		(net "XDP_CPU_R_TDO")
	)
	(segment
		(start 33.192466 -32.801814)
		(end 32.745426 -32.354774)
		(width 0.0889)
		(layer "In9.Cu")
		(net "XDP_CPU_R_TDO")
	)
	(segment
		(start 167.1955 -47.00524)
		(end 168.20261 -47.00524)
		(width 0.1143)
		(layer "F.Cu")
		(net "JTAG_RST_D#")
	)
	(segment
		(start 168.7068 -47.50943)
		(end 168.44137 -47.244)
		(width 0.1143)
		(layer "F.Cu")
		(net "JTAG_RST_D#")
	)
	(segment
		(start 168.20261 -47.00524)
		(end 168.44137 -47.244)
		(width 0.1143)
		(layer "F.Cu")
		(net "JTAG_RST_D#")
	)
	(segment
		(start 168.7068 -48.133)
		(end 168.7068 -47.50943)
		(width 0.1143)
		(layer "F.Cu")
		(net "JTAG_RST_D#")
	)
	(via
		(at 168.44137 -47.244)
		(size 0.7112)
		(drill 0.3556)
		(layers "F.Cu" "B.Cu")
		(net "JTAG_RST_D#")
	)
	(segment
		(start 167.366188 -48.9204)
		(end 167.8178 -48.9204)
		(width 0.1143)
		(layer "F.Cu")
		(net "JTAG_RST#")
	)
	(segment
		(start 167.8178 -48.9204)
		(end 167.8432 -48.895)
		(width 0.1143)
		(layer "F.Cu")
		(net "JTAG_RST#")
	)
	(segment
		(start 167.8432 -48.133)
		(end 167.8432 -48.895)
		(width 0.1143)
		(layer "F.Cu")
		(net "JTAG_RST#")
	)
	(segment
		(start 167.061388 -49.2252)
		(end 167.366188 -48.9204)
		(width 0.1143)
		(layer "F.Cu")
		(net "JTAG_RST#")
	)
	(via
		(at 167.061388 -49.2252)
		(size 0.508)
		(drill 0.254)
		(layers "F.Cu" "B.Cu")
		(net "JTAG_RST#")
	)
	(via
		(at 167.740838 -48.5394)
		(size 0.7112)
		(drill 0.3556)
		(layers "F.Cu" "B.Cu")
		(net "JTAG_RST#")
	)
	(segment
		(start 167.740838 -48.5394)
		(end 167.740838 -48.54575)
		(width 0.1143)
		(layer "B.Cu")
		(net "JTAG_RST#")
	)
	(segment
		(start 167.740838 -48.54575)
		(end 167.061388 -49.2252)
		(width 0.1143)
		(layer "B.Cu")
		(net "JTAG_RST#")
	)
	(segment
		(start 167.061388 -49.2252)
		(end 167.061388 -48.822864)
		(width 0.0889)
		(layer "In9.Cu")
		(net "JTAG_RST#")
	)
	(segment
		(start 203.342748 -19.2278)
		(end 205.157578 -17.41297)
		(width 0.0889)
		(layer "In9.Cu")
		(net "JTAG_RST#")
	)
	(segment
		(start 205.157578 -17.41297)
		(end 205.157578 -10.339578)
		(width 0.0889)
		(layer "In9.Cu")
		(net "JTAG_RST#")
	)
	(segment
		(start 173.091602 -42.79265)
		(end 181.241192 -42.79265)
		(width 0.0889)
		(layer "In9.Cu")
		(net "JTAG_RST#")
	)
	(segment
		(start 186.563 -28.212542)
		(end 195.547742 -19.2278)
		(width 0.0889)
		(layer "In9.Cu")
		(net "JTAG_RST#")
	)
	(segment
		(start 181.241192 -42.79265)
		(end 185.61685 -38.416992)
		(width 0.0889)
		(layer "In9.Cu")
		(net "JTAG_RST#")
	)
	(segment
		(start 195.547742 -19.2278)
		(end 203.342748 -19.2278)
		(width 0.0889)
		(layer "In9.Cu")
		(net "JTAG_RST#")
	)
	(segment
		(start 205.157578 -10.339578)
		(end 204.224128 -9.406128)
		(width 0.0889)
		(layer "In9.Cu")
		(net "JTAG_RST#")
	)
	(segment
		(start 185.61685 -38.416992)
		(end 185.61685 -32.49295)
		(width 0.0889)
		(layer "In9.Cu")
		(net "JTAG_RST#")
	)
	(segment
		(start 186.563 -31.5468)
		(end 186.563 -28.212542)
		(width 0.0889)
		(layer "In9.Cu")
		(net "JTAG_RST#")
	)
	(segment
		(start 185.61685 -32.49295)
		(end 186.563 -31.5468)
		(width 0.0889)
		(layer "In9.Cu")
		(net "JTAG_RST#")
	)
	(segment
		(start 167.061388 -48.822864)
		(end 173.091602 -42.79265)
		(width 0.0889)
		(layer "In9.Cu")
		(net "JTAG_RST#")
	)
	(segment
		(start 201.684128 -14.486128)
		(end 202.630278 -15.432278)
		(width 0.1143)
		(layer "F.Cu")
		(net "JTAG_CPU_PLD_TDO")
	)
	(segment
		(start 155.858464 -46.99)
		(end 155.858464 -47.917354)
		(width 0.1143)
		(layer "F.Cu")
		(net "JTAG_CPU_PLD_TDO")
	)
	(segment
		(start 156.3243 -45.4279)
		(end 156.315918 -45.4279)
		(width 0.1143)
		(layer "F.Cu")
		(net "JTAG_CPU_PLD_TDO")
	)
	(segment
		(start 205.74 -23.6728)
		(end 204.7748 -24.638)
		(width 0.1143)
		(layer "F.Cu")
		(net "JTAG_CPU_PLD_TDO")
	)
	(segment
		(start 156.05125 -49.742344)
		(end 156.05125 -50.32121)
		(width 0.1143)
		(layer "F.Cu")
		(net "JTAG_CPU_PLD_TDO")
	)
	(segment
		(start 155.858464 -47.917354)
		(end 156.464 -48.52289)
		(width 0.1143)
		(layer "F.Cu")
		(net "JTAG_CPU_PLD_TDO")
	)
	(segment
		(start 156.315918 -45.4279)
		(end 155.64485 -46.098968)
		(width 0.1143)
		(layer "F.Cu")
		(net "JTAG_CPU_PLD_TDO")
	)
	(segment
		(start 156.4132 -45.339)
		(end 156.3243 -45.4279)
		(width 0.1143)
		(layer "F.Cu")
		(net "JTAG_CPU_PLD_TDO")
	)
	(segment
		(start 205.105 -21.8948)
		(end 205.74 -22.5298)
		(width 0.1143)
		(layer "F.Cu")
		(net "JTAG_CPU_PLD_TDO")
	)
	(segment
		(start 203.91755 -23.78075)
		(end 204.7748 -24.638)
		(width 0.1143)
		(layer "F.Cu")
		(net "JTAG_CPU_PLD_TDO")
	)
	(segment
		(start 202.630278 -17.52219)
		(end 203.91755 -18.809462)
		(width 0.1143)
		(layer "F.Cu")
		(net "JTAG_CPU_PLD_TDO")
	)
	(segment
		(start 156.05125 -50.32121)
		(end 156.44749 -50.71745)
		(width 0.1143)
		(layer "F.Cu")
		(net "JTAG_CPU_PLD_TDO")
	)
	(segment
		(start 201.684128 -13.284454)
		(end 201.684128 -14.486128)
		(width 0.1143)
		(layer "F.Cu")
		(net "JTAG_CPU_PLD_TDO")
	)
	(segment
		(start 156.464 -49.329594)
		(end 156.05125 -49.742344)
		(width 0.1143)
		(layer "F.Cu")
		(net "JTAG_CPU_PLD_TDO")
	)
	(segment
		(start 158.66745 -50.71745)
		(end 158.78175 -50.83175)
		(width 0.1143)
		(layer "F.Cu")
		(net "JTAG_CPU_PLD_TDO")
	)
	(segment
		(start 155.64485 -46.776386)
		(end 155.858464 -46.99)
		(width 0.1143)
		(layer "F.Cu")
		(net "JTAG_CPU_PLD_TDO")
	)
	(segment
		(start 155.64485 -46.098968)
		(end 155.64485 -46.776386)
		(width 0.1143)
		(layer "F.Cu")
		(net "JTAG_CPU_PLD_TDO")
	)
	(segment
		(start 163.8808 -50.3682)
		(end 161.671 -50.3682)
		(width 0.1143)
		(layer "F.Cu")
		(net "JTAG_CPU_PLD_TDO")
	)
	(segment
		(start 199.016874 -10.6172)
		(end 201.684128 -13.284454)
		(width 0.1143)
		(layer "F.Cu")
		(net "JTAG_CPU_PLD_TDO")
	)
	(segment
		(start 203.91755 -18.809462)
		(end 203.91755 -23.78075)
		(width 0.1143)
		(layer "F.Cu")
		(net "JTAG_CPU_PLD_TDO")
	)
	(segment
		(start 161.20745 -50.83175)
		(end 161.671 -50.3682)
		(width 0.1143)
		(layer "F.Cu")
		(net "JTAG_CPU_PLD_TDO")
	)
	(segment
		(start 205.74 -22.5298)
		(end 205.74 -23.6728)
		(width 0.1143)
		(layer "F.Cu")
		(net "JTAG_CPU_PLD_TDO")
	)
	(segment
		(start 164.211 -50.038)
		(end 163.8808 -50.3682)
		(width 0.1143)
		(layer "F.Cu")
		(net "JTAG_CPU_PLD_TDO")
	)
	(segment
		(start 158.78175 -50.83175)
		(end 161.20745 -50.83175)
		(width 0.1143)
		(layer "F.Cu")
		(net "JTAG_CPU_PLD_TDO")
	)
	(segment
		(start 156.44749 -50.71745)
		(end 158.66745 -50.71745)
		(width 0.1143)
		(layer "F.Cu")
		(net "JTAG_CPU_PLD_TDO")
	)
	(segment
		(start 156.464 -48.52289)
		(end 156.464 -49.329594)
		(width 0.1143)
		(layer "F.Cu")
		(net "JTAG_CPU_PLD_TDO")
	)
	(segment
		(start 202.630278 -15.432278)
		(end 202.630278 -17.52219)
		(width 0.1143)
		(layer "F.Cu")
		(net "JTAG_CPU_PLD_TDO")
	)
	(segment
		(start 164.211 -48.895)
		(end 164.211 -50.038)
		(width 0.1143)
		(layer "F.Cu")
		(net "JTAG_CPU_PLD_TDO")
	)
	(segment
		(start 198.755 -10.6172)
		(end 199.016874 -10.6172)
		(width 0.1143)
		(layer "F.Cu")
		(net "JTAG_CPU_PLD_TDO")
	)
	(via
		(at 161.671 -50.3682)
		(size 0.508)
		(drill 0.254)
		(layers "F.Cu" "B.Cu")
		(net "JTAG_CPU_PLD_TDO")
	)
	(segment
		(start 202.617578 -17.41297)
		(end 202.617578 -15.419578)
		(width 0.0889)
		(layer "In9.Cu")
		(net "JTAG_CPU_PLD_TDO")
	)
	(segment
		(start 168.228518 -44.6786)
		(end 171.054268 -41.85285)
		(width 0.0889)
		(layer "In9.Cu")
		(net "JTAG_CPU_PLD_TDO")
	)
	(segment
		(start 202.002898 -18.02765)
		(end 202.617578 -17.41297)
		(width 0.0889)
		(layer "In9.Cu")
		(net "JTAG_CPU_PLD_TDO")
	)
	(segment
		(start 183.7055 -38.998906)
		(end 183.7055 -29.740606)
		(width 0.0889)
		(layer "In9.Cu")
		(net "JTAG_CPU_PLD_TDO")
	)
	(segment
		(start 161.671 -48.231806)
		(end 165.224206 -44.6786)
		(width 0.0889)
		(layer "In9.Cu")
		(net "JTAG_CPU_PLD_TDO")
	)
	(segment
		(start 171.054268 -41.85285)
		(end 180.851556 -41.85285)
		(width 0.0889)
		(layer "In9.Cu")
		(net "JTAG_CPU_PLD_TDO")
	)
	(segment
		(start 165.224206 -44.6786)
		(end 168.228518 -44.6786)
		(width 0.0889)
		(layer "In9.Cu")
		(net "JTAG_CPU_PLD_TDO")
	)
	(segment
		(start 195.418456 -18.02765)
		(end 202.002898 -18.02765)
		(width 0.0889)
		(layer "In9.Cu")
		(net "JTAG_CPU_PLD_TDO")
	)
	(segment
		(start 180.851556 -41.85285)
		(end 183.7055 -38.998906)
		(width 0.0889)
		(layer "In9.Cu")
		(net "JTAG_CPU_PLD_TDO")
	)
	(segment
		(start 161.671 -50.3682)
		(end 161.671 -48.231806)
		(width 0.0889)
		(layer "In9.Cu")
		(net "JTAG_CPU_PLD_TDO")
	)
	(segment
		(start 183.7055 -29.740606)
		(end 195.418456 -18.02765)
		(width 0.0889)
		(layer "In9.Cu")
		(net "JTAG_CPU_PLD_TDO")
	)
	(segment
		(start 202.617578 -15.419578)
		(end 201.684128 -14.486128)
		(width 0.0889)
		(layer "In9.Cu")
		(net "JTAG_CPU_PLD_TDO")
	)
	(segment
		(start 156.21 -46.23435)
		(end 156.21 -46.355)
		(width 0.1143)
		(layer "F.Cu")
		(net "JTAG_CPU_PLD_TDO_D")
	)
	(segment
		(start 156.6926 -45.9232)
		(end 156.52115 -45.9232)
		(width 0.1143)
		(layer "F.Cu")
		(net "JTAG_CPU_PLD_TDO_D")
	)
	(segment
		(start 157.2768 -45.339)
		(end 156.6926 -45.9232)
		(width 0.1143)
		(layer "F.Cu")
		(net "JTAG_CPU_PLD_TDO_D")
	)
	(segment
		(start 156.21 -46.57725)
		(end 156.410914 -46.778164)
		(width 0.1143)
		(layer "F.Cu")
		(net "JTAG_CPU_PLD_TDO_D")
	)
	(segment
		(start 156.21 -46.355)
		(end 156.21 -46.57725)
		(width 0.1143)
		(layer "F.Cu")
		(net "JTAG_CPU_PLD_TDO_D")
	)
	(segment
		(start 156.410914 -46.778164)
		(end 156.410914 -47.498)
		(width 0.1143)
		(layer "F.Cu")
		(net "JTAG_CPU_PLD_TDO_D")
	)
	(segment
		(start 156.52115 -45.9232)
		(end 156.21 -46.23435)
		(width 0.1143)
		(layer "F.Cu")
		(net "JTAG_CPU_PLD_TDO_D")
	)
	(via
		(at 156.21 -46.355)
		(size 0.7112)
		(drill 0.3556)
		(layers "F.Cu" "B.Cu")
		(net "JTAG_CPU_PLD_TDO_D")
	)
	(segment
		(start 55.42534 -9.263888)
		(end 55.42534 -9.78662)
		(width 0.1143)
		(layer "F.Cu")
		(net "GBE_R_SMBALRT#")
	)
	(segment
		(start 55.349902 -6.195568)
		(end 55.349902 -9.18845)
		(width 0.1143)
		(layer "F.Cu")
		(net "GBE_R_SMBALRT#")
	)
	(segment
		(start 53.848 -11.36396)
		(end 53.899054 -11.312906)
		(width 0.1143)
		(layer "F.Cu")
		(net "GBE_R_SMBALRT#")
	)
	(segment
		(start 55.349902 -9.18845)
		(end 55.42534 -9.263888)
		(width 0.1143)
		(layer "F.Cu")
		(net "GBE_R_SMBALRT#")
	)
	(segment
		(start 53.848 -12.3952)
		(end 53.848 -11.36396)
		(width 0.1143)
		(layer "F.Cu")
		(net "GBE_R_SMBALRT#")
	)
	(segment
		(start 55.42534 -9.78662)
		(end 53.899054 -11.312906)
		(width 0.1143)
		(layer "F.Cu")
		(net "GBE_R_SMBALRT#")
	)
	(via
		(at 53.899054 -11.312906)
		(size 0.7112)
		(drill 0.3556)
		(layers "F.Cu" "B.Cu")
		(net "GBE_R_SMBALRT#")
	)
	(via
		(at 53.086 -11.303)
		(size 0.7112)
		(drill 0.3556)
		(layers "F.Cu" "B.Cu")
		(net "GBE_R_SMDATA")
	)
	(segment
		(start 53.349906 -9.896094)
		(end 53.086 -10.16)
		(width 0.1143)
		(layer "B.Cu")
		(net "GBE_R_SMDATA")
	)
	(segment
		(start 53.349906 -5.814568)
		(end 53.349906 -9.896094)
		(width 0.1143)
		(layer "B.Cu")
		(net "GBE_R_SMDATA")
	)
	(segment
		(start 53.086 -12.2682)
		(end 53.086 -11.303)
		(width 0.1143)
		(layer "B.Cu")
		(net "GBE_R_SMDATA")
	)
	(segment
		(start 53.086 -10.16)
		(end 53.086 -11.303)
		(width 0.1143)
		(layer "B.Cu")
		(net "GBE_R_SMDATA")
	)
	(via
		(at 54.61 -11.303)
		(size 0.7112)
		(drill 0.3556)
		(layers "F.Cu" "B.Cu")
		(net "GBE_R_SMBCLK")
	)
	(segment
		(start 54.349904 -5.814568)
		(end 54.349904 -9.066022)
		(width 0.1143)
		(layer "B.Cu")
		(net "GBE_R_SMBCLK")
	)
	(segment
		(start 53.8988 -12.2682)
		(end 54.61 -11.557)
		(width 0.1143)
		(layer "B.Cu")
		(net "GBE_R_SMBCLK")
	)
	(segment
		(start 54.349904 -9.066022)
		(end 54.229 -9.186926)
		(width 0.1143)
		(layer "B.Cu")
		(net "GBE_R_SMBCLK")
	)
	(segment
		(start 54.61 -11.557)
		(end 54.61 -11.303)
		(width 0.1143)
		(layer "B.Cu")
		(net "GBE_R_SMBCLK")
	)
	(segment
		(start 53.848 -12.2682)
		(end 53.8988 -12.2682)
		(width 0.1143)
		(layer "B.Cu")
		(net "GBE_R_SMBCLK")
	)
	(segment
		(start 54.229 -10.922)
		(end 54.61 -11.303)
		(width 0.1143)
		(layer "B.Cu")
		(net "GBE_R_SMBCLK")
	)
	(segment
		(start 54.229 -9.186926)
		(end 54.229 -10.922)
		(width 0.1143)
		(layer "B.Cu")
		(net "GBE_R_SMBCLK")
	)
	(segment
		(start 85.552788 -35.458654)
		(end 85.552788 -35.440112)
		(width 0.1143)
		(layer "F.Cu")
		(net "REV_CPU_FPGA_IO0")
	)
	(segment
		(start 85.552788 -35.440112)
		(end 85.220556 -35.10788)
		(width 0.1143)
		(layer "F.Cu")
		(net "REV_CPU_FPGA_IO0")
	)
	(via
		(at 109.22 -7.812532)
		(size 0.508)
		(drill 0.254)
		(layers "F.Cu" "B.Cu")
		(net "REV_CPU_FPGA_IO0")
	)
	(via
		(at 85.220556 -35.10788)
		(size 0.4318)
		(drill 0.2032)
		(layers "F.Cu" "B.Cu")
		(net "REV_CPU_FPGA_IO0")
	)
	(via
		(at 111.506 -13.716)
		(size 0.7112)
		(drill 0.3556)
		(layers "F.Cu" "B.Cu")
		(net "REV_CPU_FPGA_IO0")
	)
	(via
		(at 83.6422 -22.1742)
		(size 0.4318)
		(drill 0.2032)
		(layers "F.Cu" "B.Cu")
		(net "REV_CPU_FPGA_IO0")
	)
	(segment
		(start 82.58429 -34.334958)
		(end 82.208624 -33.959292)
		(width 0.1143)
		(layer "B.Cu")
		(net "REV_CPU_FPGA_IO0")
	)
	(segment
		(start 108.75645 -8.868156)
		(end 108.75645 -8.276082)
		(width 0.1143)
		(layer "B.Cu")
		(net "REV_CPU_FPGA_IO0")
	)
	(segment
		(start 84.99602 -35.10788)
		(end 84.407502 -34.519362)
		(width 0.1143)
		(layer "B.Cu")
		(net "REV_CPU_FPGA_IO0")
	)
	(segment
		(start 77.098652 -32.975296)
		(end 76.835 -32.711644)
		(width 0.1143)
		(layer "B.Cu")
		(net "REV_CPU_FPGA_IO0")
	)
	(segment
		(start 114.935 -23.5204)
		(end 123.13285 -31.71825)
		(width 0.1143)
		(layer "B.Cu")
		(net "REV_CPU_FPGA_IO0")
	)
	(segment
		(start 80.137 -33.960562)
		(end 79.666338 -33.4899)
		(width 0.1143)
		(layer "B.Cu")
		(net "REV_CPU_FPGA_IO0")
	)
	(segment
		(start 109.39145 -9.503156)
		(end 108.75645 -8.868156)
		(width 0.1143)
		(layer "B.Cu")
		(net "REV_CPU_FPGA_IO0")
	)
	(segment
		(start 76.835 -31.75127)
		(end 76.2254 -31.14167)
		(width 0.1143)
		(layer "B.Cu")
		(net "REV_CPU_FPGA_IO0")
	)
	(segment
		(start 123.13285 -31.71825)
		(end 123.13285 -35.75685)
		(width 0.1143)
		(layer "B.Cu")
		(net "REV_CPU_FPGA_IO0")
	)
	(segment
		(start 76.2254 -31.14167)
		(end 76.2254 -30.093158)
		(width 0.1143)
		(layer "B.Cu")
		(net "REV_CPU_FPGA_IO0")
	)
	(segment
		(start 109.39145 -11.22045)
		(end 109.39145 -9.503156)
		(width 0.1143)
		(layer "B.Cu")
		(net "REV_CPU_FPGA_IO0")
	)
	(segment
		(start 77.642974 -32.975296)
		(end 77.098652 -32.975296)
		(width 0.1143)
		(layer "B.Cu")
		(net "REV_CPU_FPGA_IO0")
	)
	(segment
		(start 84.407502 -34.519362)
		(end 83.465924 -34.519362)
		(width 0.1143)
		(layer "B.Cu")
		(net "REV_CPU_FPGA_IO0")
	)
	(segment
		(start 79.1337 -33.4899)
		(end 78.426056 -32.782256)
		(width 0.1143)
		(layer "B.Cu")
		(net "REV_CPU_FPGA_IO0")
	)
	(segment
		(start 111.506 -13.716)
		(end 111.506 -13.335)
		(width 0.1143)
		(layer "B.Cu")
		(net "REV_CPU_FPGA_IO0")
	)
	(segment
		(start 85.220556 -35.10788)
		(end 84.99602 -35.10788)
		(width 0.1143)
		(layer "B.Cu")
		(net "REV_CPU_FPGA_IO0")
	)
	(segment
		(start 108.75645 -8.276082)
		(end 109.22 -7.812532)
		(width 0.1143)
		(layer "B.Cu")
		(net "REV_CPU_FPGA_IO0")
	)
	(segment
		(start 76.835 -32.711644)
		(end 76.835 -31.75127)
		(width 0.1143)
		(layer "B.Cu")
		(net "REV_CPU_FPGA_IO0")
	)
	(segment
		(start 76.2254 -30.093158)
		(end 75.596242 -29.464)
		(width 0.1143)
		(layer "B.Cu")
		(net "REV_CPU_FPGA_IO0")
	)
	(segment
		(start 82.208624 -33.959292)
		(end 81.718404 -33.959292)
		(width 0.1143)
		(layer "B.Cu")
		(net "REV_CPU_FPGA_IO0")
	)
	(segment
		(start 79.666338 -33.4899)
		(end 79.1337 -33.4899)
		(width 0.1143)
		(layer "B.Cu")
		(net "REV_CPU_FPGA_IO0")
	)
	(segment
		(start 128.443736 -49.1744)
		(end 133.4008 -49.1744)
		(width 0.1143)
		(layer "B.Cu")
		(net "REV_CPU_FPGA_IO0")
	)
	(segment
		(start 126.34595 -47.076614)
		(end 128.443736 -49.1744)
		(width 0.1143)
		(layer "B.Cu")
		(net "REV_CPU_FPGA_IO0")
	)
	(segment
		(start 83.465924 -34.519362)
		(end 83.28152 -34.334958)
		(width 0.1143)
		(layer "B.Cu")
		(net "REV_CPU_FPGA_IO0")
	)
	(segment
		(start 133.4008 -49.1744)
		(end 133.9342 -48.641)
		(width 0.1143)
		(layer "B.Cu")
		(net "REV_CPU_FPGA_IO0")
	)
	(segment
		(start 78.426056 -32.782256)
		(end 77.836014 -32.782256)
		(width 0.1143)
		(layer "B.Cu")
		(net "REV_CPU_FPGA_IO0")
	)
	(segment
		(start 126.34595 -38.96995)
		(end 126.34595 -47.076614)
		(width 0.1143)
		(layer "B.Cu")
		(net "REV_CPU_FPGA_IO0")
	)
	(segment
		(start 77.836014 -32.782256)
		(end 77.642974 -32.975296)
		(width 0.1143)
		(layer "B.Cu")
		(net "REV_CPU_FPGA_IO0")
	)
	(segment
		(start 81.717134 -33.960562)
		(end 80.137 -33.960562)
		(width 0.1143)
		(layer "B.Cu")
		(net "REV_CPU_FPGA_IO0")
	)
	(segment
		(start 111.506 -13.335)
		(end 109.39145 -11.22045)
		(width 0.1143)
		(layer "B.Cu")
		(net "REV_CPU_FPGA_IO0")
	)
	(segment
		(start 114.935 -17.696688)
		(end 114.935 -23.5204)
		(width 0.1143)
		(layer "B.Cu")
		(net "REV_CPU_FPGA_IO0")
	)
	(segment
		(start 81.718404 -33.959292)
		(end 81.717134 -33.960562)
		(width 0.1143)
		(layer "B.Cu")
		(net "REV_CPU_FPGA_IO0")
	)
	(segment
		(start 111.506 -14.267688)
		(end 114.935 -17.696688)
		(width 0.1143)
		(layer "B.Cu")
		(net "REV_CPU_FPGA_IO0")
	)
	(segment
		(start 83.28152 -34.334958)
		(end 82.58429 -34.334958)
		(width 0.1143)
		(layer "B.Cu")
		(net "REV_CPU_FPGA_IO0")
	)
	(segment
		(start 123.13285 -35.75685)
		(end 126.34595 -38.96995)
		(width 0.1143)
		(layer "B.Cu")
		(net "REV_CPU_FPGA_IO0")
	)
	(segment
		(start 75.596242 -29.464)
		(end 74.4728 -29.464)
		(width 0.1143)
		(layer "B.Cu")
		(net "REV_CPU_FPGA_IO0")
	)
	(segment
		(start 111.506 -13.716)
		(end 111.506 -14.267688)
		(width 0.1143)
		(layer "B.Cu")
		(net "REV_CPU_FPGA_IO0")
	)
	(segment
		(start 99.778566 -12.582906)
		(end 90.168222 -22.19325)
		(width 0.0889)
		(layer "In4.Cu")
		(net "REV_CPU_FPGA_IO0")
	)
	(segment
		(start 108.712 -8.320532)
		(end 108.712 -10.999978)
		(width 0.0889)
		(layer "In4.Cu")
		(net "REV_CPU_FPGA_IO0")
	)
	(segment
		(start 107.129072 -12.582906)
		(end 99.778566 -12.582906)
		(width 0.0889)
		(layer "In4.Cu")
		(net "REV_CPU_FPGA_IO0")
	)
	(segment
		(start 85.285834 -22.14245)
		(end 83.67395 -22.14245)
		(width 0.0889)
		(layer "In4.Cu")
		(net "REV_CPU_FPGA_IO0")
	)
	(segment
		(start 85.336634 -22.19325)
		(end 85.285834 -22.14245)
		(width 0.0889)
		(layer "In4.Cu")
		(net "REV_CPU_FPGA_IO0")
	)
	(segment
		(start 108.712 -10.999978)
		(end 107.129072 -12.582906)
		(width 0.0889)
		(layer "In4.Cu")
		(net "REV_CPU_FPGA_IO0")
	)
	(segment
		(start 90.168222 -22.19325)
		(end 85.336634 -22.19325)
		(width 0.0889)
		(layer "In4.Cu")
		(net "REV_CPU_FPGA_IO0")
	)
	(segment
		(start 109.22 -7.812532)
		(end 108.712 -8.320532)
		(width 0.0889)
		(layer "In4.Cu")
		(net "REV_CPU_FPGA_IO0")
	)
	(segment
		(start 83.67395 -22.14245)
		(end 83.6422 -22.1742)
		(width 0.0889)
		(layer "In4.Cu")
		(net "REV_CPU_FPGA_IO0")
	)
	(segment
		(start 82.423 -24.887936)
		(end 82.932524 -25.39746)
		(width 0.0889)
		(layer "In9.Cu")
		(net "REV_CPU_FPGA_IO0")
	)
	(segment
		(start 82.521552 -31.234634)
		(end 83.018122 -31.731204)
		(width 0.0889)
		(layer "In9.Cu")
		(net "REV_CPU_FPGA_IO0")
	)
	(segment
		(start 83.00085 -28.932886)
		(end 83.00085 -29.233114)
		(width 0.0889)
		(layer "In9.Cu")
		(net "REV_CPU_FPGA_IO0")
	)
	(segment
		(start 82.43443 -23.619714)
		(end 82.423 -23.631144)
		(width 0.0889)
		(layer "In9.Cu")
		(net "REV_CPU_FPGA_IO0")
	)
	(segment
		(start 83.6422 -22.1742)
		(end 83.370674 -22.1742)
		(width 0.0889)
		(layer "In9.Cu")
		(net "REV_CPU_FPGA_IO0")
	)
	(segment
		(start 82.804 -32.710882)
		(end 82.804 -33.31464)
		(width 0.0889)
		(layer "In9.Cu")
		(net "REV_CPU_FPGA_IO0")
	)
	(segment
		(start 82.804 -33.31464)
		(end 83.04276 -33.5534)
		(width 0.0889)
		(layer "In9.Cu")
		(net "REV_CPU_FPGA_IO0")
	)
	(segment
		(start 82.98815 -28.374086)
		(end 82.98815 -28.920186)
		(width 0.0889)
		(layer "In9.Cu")
		(net "REV_CPU_FPGA_IO0")
	)
	(segment
		(start 83.662774 -33.5534)
		(end 85.217254 -35.10788)
		(width 0.0889)
		(layer "In9.Cu")
		(net "REV_CPU_FPGA_IO0")
	)
	(segment
		(start 83.370674 -22.1742)
		(end 82.43443 -23.110444)
		(width 0.0889)
		(layer "In9.Cu")
		(net "REV_CPU_FPGA_IO0")
	)
	(segment
		(start 82.677 -25.965912)
		(end 82.677 -28.062936)
		(width 0.0889)
		(layer "In9.Cu")
		(net "REV_CPU_FPGA_IO0")
	)
	(segment
		(start 82.98815 -28.920186)
		(end 83.00085 -28.932886)
		(width 0.0889)
		(layer "In9.Cu")
		(net "REV_CPU_FPGA_IO0")
	)
	(segment
		(start 85.217254 -35.10788)
		(end 85.220556 -35.10788)
		(width 0.0889)
		(layer "In9.Cu")
		(net "REV_CPU_FPGA_IO0")
	)
	(segment
		(start 82.43443 -23.110444)
		(end 82.43443 -23.619714)
		(width 0.0889)
		(layer "In9.Cu")
		(net "REV_CPU_FPGA_IO0")
	)
	(segment
		(start 82.423 -23.631144)
		(end 82.423 -24.887936)
		(width 0.0889)
		(layer "In9.Cu")
		(net "REV_CPU_FPGA_IO0")
	)
	(segment
		(start 82.677 -28.062936)
		(end 82.98815 -28.374086)
		(width 0.0889)
		(layer "In9.Cu")
		(net "REV_CPU_FPGA_IO0")
	)
	(segment
		(start 82.521552 -29.712412)
		(end 82.521552 -31.234634)
		(width 0.0889)
		(layer "In9.Cu")
		(net "REV_CPU_FPGA_IO0")
	)
	(segment
		(start 83.00085 -29.233114)
		(end 82.521552 -29.712412)
		(width 0.0889)
		(layer "In9.Cu")
		(net "REV_CPU_FPGA_IO0")
	)
	(segment
		(start 83.018122 -32.49676)
		(end 82.804 -32.710882)
		(width 0.0889)
		(layer "In9.Cu")
		(net "REV_CPU_FPGA_IO0")
	)
	(segment
		(start 82.932524 -25.39746)
		(end 82.932524 -25.710388)
		(width 0.0889)
		(layer "In9.Cu")
		(net "REV_CPU_FPGA_IO0")
	)
	(segment
		(start 83.018122 -31.731204)
		(end 83.018122 -32.49676)
		(width 0.0889)
		(layer "In9.Cu")
		(net "REV_CPU_FPGA_IO0")
	)
	(segment
		(start 82.932524 -25.710388)
		(end 82.677 -25.965912)
		(width 0.0889)
		(layer "In9.Cu")
		(net "REV_CPU_FPGA_IO0")
	)
	(segment
		(start 83.04276 -33.5534)
		(end 83.662774 -33.5534)
		(width 0.0889)
		(layer "In9.Cu")
		(net "REV_CPU_FPGA_IO0")
	)
	(segment
		(start 86.314788 -35.518852)
		(end 86.314788 -35.458654)
		(width 0.1143)
		(layer "F.Cu")
		(net "REV_CPU_FPGA_IO1")
	)
	(segment
		(start 85.96884 -35.8648)
		(end 86.314788 -35.518852)
		(width 0.1143)
		(layer "F.Cu")
		(net "REV_CPU_FPGA_IO1")
	)
	(segment
		(start 85.93328 -35.8902)
		(end 85.95868 -35.8648)
		(width 0.1143)
		(layer "F.Cu")
		(net "REV_CPU_FPGA_IO1")
	)
	(segment
		(start 85.95868 -35.8648)
		(end 85.96884 -35.8648)
		(width 0.1143)
		(layer "F.Cu")
		(net "REV_CPU_FPGA_IO1")
	)
	(via
		(at 109.22 -6.948932)
		(size 0.508)
		(drill 0.254)
		(layers "F.Cu" "B.Cu")
		(net "REV_CPU_FPGA_IO1")
	)
	(via
		(at 84.1248 -22.5044)
		(size 0.4318)
		(drill 0.2032)
		(layers "F.Cu" "B.Cu")
		(net "REV_CPU_FPGA_IO1")
	)
	(via
		(at 85.93328 -35.8902)
		(size 0.4318)
		(drill 0.2032)
		(layers "F.Cu" "B.Cu")
		(net "REV_CPU_FPGA_IO1")
	)
	(via
		(at 123.698 -35.1536)
		(size 0.7112)
		(drill 0.3556)
		(layers "F.Cu" "B.Cu")
		(net "REV_CPU_FPGA_IO1")
	)
	(segment
		(start 75.0189 -29.2481)
		(end 74.4728 -28.702)
		(width 0.1143)
		(layer "B.Cu")
		(net "REV_CPU_FPGA_IO1")
	)
	(segment
		(start 85.59546 -35.30854)
		(end 85.59546 -34.94024)
		(width 0.1143)
		(layer "B.Cu")
		(net "REV_CPU_FPGA_IO1")
	)
	(segment
		(start 77.799692 -32.4104)
		(end 76.4413 -31.052008)
		(width 0.1143)
		(layer "B.Cu")
		(net "REV_CPU_FPGA_IO1")
	)
	(segment
		(start 85.365082 -34.709862)
		(end 84.903564 -34.709862)
		(width 0.1143)
		(layer "B.Cu")
		(net "REV_CPU_FPGA_IO1")
	)
	(segment
		(start 78.667864 -32.4104)
		(end 77.799692 -32.4104)
		(width 0.1143)
		(layer "B.Cu")
		(net "REV_CPU_FPGA_IO1")
	)
	(segment
		(start 85.93328 -35.8902)
		(end 85.93328 -35.64636)
		(width 0.1143)
		(layer "B.Cu")
		(net "REV_CPU_FPGA_IO1")
	)
	(segment
		(start 133.63575 -47.879)
		(end 132.842 -48.67275)
		(width 0.1143)
		(layer "B.Cu")
		(net "REV_CPU_FPGA_IO1")
	)
	(segment
		(start 123.698 -31.6484)
		(end 115.3541 -23.3045)
		(width 0.1143)
		(layer "B.Cu")
		(net "REV_CPU_FPGA_IO1")
	)
	(segment
		(start 85.93328 -35.64636)
		(end 85.59546 -35.30854)
		(width 0.1143)
		(layer "B.Cu")
		(net "REV_CPU_FPGA_IO1")
	)
	(segment
		(start 83.957922 -33.76422)
		(end 83.073494 -33.76422)
		(width 0.1143)
		(layer "B.Cu")
		(net "REV_CPU_FPGA_IO1")
	)
	(segment
		(start 76.4413 -30.003496)
		(end 75.685904 -29.2481)
		(width 0.1143)
		(layer "B.Cu")
		(net "REV_CPU_FPGA_IO1")
	)
	(segment
		(start 115.3541 -16.5481)
		(end 109.81055 -11.00455)
		(width 0.1143)
		(layer "B.Cu")
		(net "REV_CPU_FPGA_IO1")
	)
	(segment
		(start 109.81055 -7.539482)
		(end 109.22 -6.948932)
		(width 0.1143)
		(layer "B.Cu")
		(net "REV_CPU_FPGA_IO1")
	)
	(segment
		(start 109.81055 -11.00455)
		(end 109.81055 -7.539482)
		(width 0.1143)
		(layer "B.Cu")
		(net "REV_CPU_FPGA_IO1")
	)
	(segment
		(start 84.903564 -34.709862)
		(end 83.957922 -33.76422)
		(width 0.1143)
		(layer "B.Cu")
		(net "REV_CPU_FPGA_IO1")
	)
	(segment
		(start 83.073494 -33.76422)
		(end 82.894932 -33.585658)
		(width 0.1143)
		(layer "B.Cu")
		(net "REV_CPU_FPGA_IO1")
	)
	(segment
		(start 126.76505 -38.75405)
		(end 123.698 -35.687)
		(width 0.1143)
		(layer "B.Cu")
		(net "REV_CPU_FPGA_IO1")
	)
	(segment
		(start 76.4413 -31.052008)
		(end 76.4413 -30.003496)
		(width 0.1143)
		(layer "B.Cu")
		(net "REV_CPU_FPGA_IO1")
	)
	(segment
		(start 123.698 -35.1536)
		(end 123.698 -31.6484)
		(width 0.1143)
		(layer "B.Cu")
		(net "REV_CPU_FPGA_IO1")
	)
	(segment
		(start 133.9342 -47.879)
		(end 133.63575 -47.879)
		(width 0.1143)
		(layer "B.Cu")
		(net "REV_CPU_FPGA_IO1")
	)
	(segment
		(start 123.698 -35.687)
		(end 123.698 -35.1536)
		(width 0.1143)
		(layer "B.Cu")
		(net "REV_CPU_FPGA_IO1")
	)
	(segment
		(start 79.487014 -33.22955)
		(end 78.667864 -32.4104)
		(width 0.1143)
		(layer "B.Cu")
		(net "REV_CPU_FPGA_IO1")
	)
	(segment
		(start 128.534922 -48.67275)
		(end 126.76505 -46.902878)
		(width 0.1143)
		(layer "B.Cu")
		(net "REV_CPU_FPGA_IO1")
	)
	(segment
		(start 126.76505 -46.902878)
		(end 126.76505 -38.75405)
		(width 0.1143)
		(layer "B.Cu")
		(net "REV_CPU_FPGA_IO1")
	)
	(segment
		(start 80.226662 -33.744662)
		(end 79.71155 -33.22955)
		(width 0.1143)
		(layer "B.Cu")
		(net "REV_CPU_FPGA_IO1")
	)
	(segment
		(start 132.842 -48.67275)
		(end 128.534922 -48.67275)
		(width 0.1143)
		(layer "B.Cu")
		(net "REV_CPU_FPGA_IO1")
	)
	(segment
		(start 81.765648 -33.585658)
		(end 81.606644 -33.744662)
		(width 0.1143)
		(layer "B.Cu")
		(net "REV_CPU_FPGA_IO1")
	)
	(segment
		(start 79.71155 -33.22955)
		(end 79.487014 -33.22955)
		(width 0.1143)
		(layer "B.Cu")
		(net "REV_CPU_FPGA_IO1")
	)
	(segment
		(start 81.606644 -33.744662)
		(end 80.226662 -33.744662)
		(width 0.1143)
		(layer "B.Cu")
		(net "REV_CPU_FPGA_IO1")
	)
	(segment
		(start 75.685904 -29.2481)
		(end 75.0189 -29.2481)
		(width 0.1143)
		(layer "B.Cu")
		(net "REV_CPU_FPGA_IO1")
	)
	(segment
		(start 82.894932 -33.585658)
		(end 81.765648 -33.585658)
		(width 0.1143)
		(layer "B.Cu")
		(net "REV_CPU_FPGA_IO1")
	)
	(segment
		(start 85.59546 -34.94024)
		(end 85.365082 -34.709862)
		(width 0.1143)
		(layer "B.Cu")
		(net "REV_CPU_FPGA_IO1")
	)
	(segment
		(start 115.3541 -23.3045)
		(end 115.3541 -16.5481)
		(width 0.1143)
		(layer "B.Cu")
		(net "REV_CPU_FPGA_IO1")
	)
	(segment
		(start 107.292394 -12.976606)
		(end 109.67085 -10.59815)
		(width 0.0889)
		(layer "In4.Cu")
		(net "REV_CPU_FPGA_IO1")
	)
	(segment
		(start 100.071682 -12.976606)
		(end 107.292394 -12.976606)
		(width 0.0889)
		(layer "In4.Cu")
		(net "REV_CPU_FPGA_IO1")
	)
	(segment
		(start 90.543888 -22.5044)
		(end 100.071682 -12.976606)
		(width 0.0889)
		(layer "In4.Cu")
		(net "REV_CPU_FPGA_IO1")
	)
	(segment
		(start 84.1248 -22.5044)
		(end 90.543888 -22.5044)
		(width 0.0889)
		(layer "In4.Cu")
		(net "REV_CPU_FPGA_IO1")
	)
	(segment
		(start 109.67085 -10.59815)
		(end 109.67085 -7.399782)
		(width 0.0889)
		(layer "In4.Cu")
		(net "REV_CPU_FPGA_IO1")
	)
	(segment
		(start 109.67085 -7.399782)
		(end 109.22 -6.948932)
		(width 0.0889)
		(layer "In4.Cu")
		(net "REV_CPU_FPGA_IO1")
	)
	(segment
		(start 83.209638 -31.270448)
		(end 83.209638 -32.032702)
		(width 0.0889)
		(layer "In9.Cu")
		(net "REV_CPU_FPGA_IO1")
	)
	(segment
		(start 82.677 -24.257)
		(end 82.677 -24.872442)
		(width 0.0889)
		(layer "In9.Cu")
		(net "REV_CPU_FPGA_IO1")
	)
	(segment
		(start 83.67395 -22.95525)
		(end 83.67395 -23.695914)
		(width 0.0889)
		(layer "In9.Cu")
		(net "REV_CPU_FPGA_IO1")
	)
	(segment
		(start 83.30946 -30.610556)
		(end 83.312 -30.613096)
		(width 0.0889)
		(layer "In9.Cu")
		(net "REV_CPU_FPGA_IO1")
	)
	(segment
		(start 85.5726 -34.94786)
		(end 85.582506 -34.957766)
		(width 0.0889)
		(layer "In9.Cu")
		(net "REV_CPU_FPGA_IO1")
	)
	(segment
		(start 83.462114 -23.90775)
		(end 83.02625 -23.90775)
		(width 0.0889)
		(layer "In9.Cu")
		(net "REV_CPU_FPGA_IO1")
	)
	(segment
		(start 83.209638 -32.032702)
		(end 83.421474 -32.244538)
		(width 0.0889)
		(layer "In9.Cu")
		(net "REV_CPU_FPGA_IO1")
	)
	(segment
		(start 85.582506 -34.957766)
		(end 85.582506 -35.315906)
		(width 0.0889)
		(layer "In9.Cu")
		(net "REV_CPU_FPGA_IO1")
	)
	(segment
		(start 85.5726 -33.9852)
		(end 85.5726 -34.94786)
		(width 0.0889)
		(layer "In9.Cu")
		(net "REV_CPU_FPGA_IO1")
	)
	(segment
		(start 83.24215 -25.679908)
		(end 83.30946 -25.747218)
		(width 0.0889)
		(layer "In9.Cu")
		(net "REV_CPU_FPGA_IO1")
	)
	(segment
		(start 83.24215 -25.437592)
		(end 83.24215 -25.679908)
		(width 0.0889)
		(layer "In9.Cu")
		(net "REV_CPU_FPGA_IO1")
	)
	(segment
		(start 85.93328 -35.66668)
		(end 85.93328 -35.8902)
		(width 0.0889)
		(layer "In9.Cu")
		(net "REV_CPU_FPGA_IO1")
	)
	(segment
		(start 83.67395 -23.695914)
		(end 83.462114 -23.90775)
		(width 0.0889)
		(layer "In9.Cu")
		(net "REV_CPU_FPGA_IO1")
	)
	(segment
		(start 83.421474 -32.244538)
		(end 83.831938 -32.244538)
		(width 0.0889)
		(layer "In9.Cu")
		(net "REV_CPU_FPGA_IO1")
	)
	(segment
		(start 85.582506 -35.315906)
		(end 85.93328 -35.66668)
		(width 0.0889)
		(layer "In9.Cu")
		(net "REV_CPU_FPGA_IO1")
	)
	(segment
		(start 83.282282 -30.93593)
		(end 83.282282 -31.197804)
		(width 0.0889)
		(layer "In9.Cu")
		(net "REV_CPU_FPGA_IO1")
	)
	(segment
		(start 83.312 -30.613096)
		(end 83.312 -30.906212)
		(width 0.0889)
		(layer "In9.Cu")
		(net "REV_CPU_FPGA_IO1")
	)
	(segment
		(start 83.831938 -32.244538)
		(end 85.5726 -33.9852)
		(width 0.0889)
		(layer "In9.Cu")
		(net "REV_CPU_FPGA_IO1")
	)
	(segment
		(start 83.02625 -23.90775)
		(end 82.677 -24.257)
		(width 0.0889)
		(layer "In9.Cu")
		(net "REV_CPU_FPGA_IO1")
	)
	(segment
		(start 84.1248 -22.5044)
		(end 83.67395 -22.95525)
		(width 0.0889)
		(layer "In9.Cu")
		(net "REV_CPU_FPGA_IO1")
	)
	(segment
		(start 83.312 -30.906212)
		(end 83.282282 -30.93593)
		(width 0.0889)
		(layer "In9.Cu")
		(net "REV_CPU_FPGA_IO1")
	)
	(segment
		(start 82.677 -24.872442)
		(end 83.24215 -25.437592)
		(width 0.0889)
		(layer "In9.Cu")
		(net "REV_CPU_FPGA_IO1")
	)
	(segment
		(start 83.282282 -31.197804)
		(end 83.209638 -31.270448)
		(width 0.0889)
		(layer "In9.Cu")
		(net "REV_CPU_FPGA_IO1")
	)
	(segment
		(start 83.30946 -25.747218)
		(end 83.30946 -30.610556)
		(width 0.0889)
		(layer "In9.Cu")
		(net "REV_CPU_FPGA_IO1")
	)
	(segment
		(start 169.037 -45.593)
		(end 169.291 -45.847)
		(width 0.1143)
		(layer "F.Cu")
		(net "XDP_SOC_CPU_TDI_S")
	)
	(segment
		(start 168.3512 -45.593)
		(end 169.037 -45.593)
		(width 0.1143)
		(layer "F.Cu")
		(net "XDP_SOC_CPU_TDI_S")
	)
	(segment
		(start 168.21404 -45.70476)
		(end 167.1955 -45.70476)
		(width 0.1143)
		(layer "F.Cu")
		(net "XDP_SOC_CPU_TDI_S")
	)
	(segment
		(start 168.3512 -45.593)
		(end 168.3258 -45.593)
		(width 0.1143)
		(layer "F.Cu")
		(net "XDP_SOC_CPU_TDI_S")
	)
	(segment
		(start 168.3258 -45.593)
		(end 168.21404 -45.70476)
		(width 0.1143)
		(layer "F.Cu")
		(net "XDP_SOC_CPU_TDI_S")
	)
	(via
		(at 168.3512 -45.593)
		(size 0.7112)
		(drill 0.3556)
		(layers "F.Cu" "B.Cu")
		(net "XDP_SOC_CPU_TDI_S")
	)
	(segment
		(start 67.564 -46.863)
		(end 68.007484 -47.306484)
		(width 0.1143)
		(layer "F.Cu")
		(net "SMBUS_PECI_SW_EN")
	)
	(segment
		(start 66.7512 -45.72)
		(end 67.6275 -45.72)
		(width 0.1143)
		(layer "F.Cu")
		(net "SMBUS_PECI_SW_EN")
	)
	(segment
		(start 68.5038 -49.4284)
		(end 68.453 -49.3776)
		(width 0.1143)
		(layer "F.Cu")
		(net "SMBUS_PECI_SW_EN")
	)
	(segment
		(start 68.007484 -47.306484)
		(end 68.007484 -48.034448)
		(width 0.1143)
		(layer "F.Cu")
		(net "SMBUS_PECI_SW_EN")
	)
	(segment
		(start 68.007484 -48.034448)
		(end 68.1101 -48.137064)
		(width 0.1143)
		(layer "F.Cu")
		(net "SMBUS_PECI_SW_EN")
	)
	(segment
		(start 68.1101 -48.137064)
		(end 68.1101 -49.0347)
		(width 0.1143)
		(layer "F.Cu")
		(net "SMBUS_PECI_SW_EN")
	)
	(segment
		(start 68.5038 -50.292)
		(end 68.5038 -49.4284)
		(width 0.1143)
		(layer "F.Cu")
		(net "SMBUS_PECI_SW_EN")
	)
	(segment
		(start 68.1101 -49.0347)
		(end 68.453 -49.3776)
		(width 0.1143)
		(layer "F.Cu")
		(net "SMBUS_PECI_SW_EN")
	)
	(segment
		(start 67.183 -46.863)
		(end 67.564 -46.863)
		(width 0.1143)
		(layer "F.Cu")
		(net "SMBUS_PECI_SW_EN")
	)
	(segment
		(start 66.7512 -46.4312)
		(end 67.183 -46.863)
		(width 0.1143)
		(layer "F.Cu")
		(net "SMBUS_PECI_SW_EN")
	)
	(segment
		(start 66.7512 -45.72)
		(end 66.7512 -46.4312)
		(width 0.1143)
		(layer "F.Cu")
		(net "SMBUS_PECI_SW_EN")
	)
	(segment
		(start 65.9765 -45.72)
		(end 66.7512 -45.72)
		(width 0.1143)
		(layer "F.Cu")
		(net "SMBUS_PECI_SW_EN")
	)
	(via
		(at 68.453 -49.3776)
		(size 0.7112)
		(drill 0.3556)
		(layers "F.Cu" "B.Cu")
		(net "SMBUS_PECI_SW_EN")
	)
	(via
		(at 35.1536 -17.9578)
		(size 0.7112)
		(drill 0.3556)
		(layers "F.Cu" "B.Cu")
		(net "SMB_CLKBUFF_R_CLK")
	)
	(segment
		(start 37.92982 -20.389088)
		(end 36.920932 -19.3802)
		(width 0.1143)
		(layer "B.Cu")
		(net "SMB_CLKBUFF_R_CLK")
	)
	(segment
		(start 39.654988 -20.389088)
		(end 37.92982 -20.389088)
		(width 0.1143)
		(layer "B.Cu")
		(net "SMB_CLKBUFF_R_CLK")
	)
	(segment
		(start 35.1028 -17.907)
		(end 35.1536 -17.9578)
		(width 0.1143)
		(layer "B.Cu")
		(net "SMB_CLKBUFF_R_CLK")
	)
	(segment
		(start 40.51681 -18.6563)
		(end 40.51681 -19.527266)
		(width 0.1143)
		(layer "B.Cu")
		(net "SMB_CLKBUFF_R_CLK")
	)
	(segment
		(start 36.576 -19.3802)
		(end 35.1536 -17.9578)
		(width 0.1143)
		(layer "B.Cu")
		(net "SMB_CLKBUFF_R_CLK")
	)
	(segment
		(start 36.920932 -19.3802)
		(end 36.576 -19.3802)
		(width 0.1143)
		(layer "B.Cu")
		(net "SMB_CLKBUFF_R_CLK")
	)
	(segment
		(start 35.1028 -17.018)
		(end 35.1028 -17.907)
		(width 0.1143)
		(layer "B.Cu")
		(net "SMB_CLKBUFF_R_CLK")
	)
	(segment
		(start 40.51681 -19.527266)
		(end 39.654988 -20.389088)
		(width 0.1143)
		(layer "B.Cu")
		(net "SMB_CLKBUFF_R_CLK")
	)
	(segment
		(start 52.6796 -23.1394)
		(end 52.13604 -23.1394)
		(width 0.1143)
		(layer "B.Cu")
		(net "CLKBUFF_IREF")
	)
	(segment
		(start 52.13604 -23.1394)
		(end 50.52441 -24.75103)
		(width 0.1143)
		(layer "B.Cu")
		(net "CLKBUFF_IREF")
	)
	(segment
		(start 50.52441 -24.75103)
		(end 50.52441 -25.8445)
		(width 0.1143)
		(layer "B.Cu")
		(net "CLKBUFF_IREF")
	)
	(via
		(at 51.338988 -27.286966)
		(size 0.7112)
		(drill 0.3556)
		(layers "F.Cu" "B.Cu")
		(net "P3V3_VDDA_CLKBUFF")
	)
	(segment
		(start 52.32273 -24.6126)
		(end 51.52517 -25.41016)
		(width 0.3048)
		(layer "B.Cu")
		(net "P3V3_VDDA_CLKBUFF")
	)
	(segment
		(start 52.1208 -20.000468)
		(end 53.2638 -21.143468)
		(width 0.3048)
		(layer "B.Cu")
		(net "P3V3_VDDA_CLKBUFF")
	)
	(segment
		(start 52.1208 -17.653)
		(end 52.1208 -20.000468)
		(width 0.3048)
		(layer "B.Cu")
		(net "P3V3_VDDA_CLKBUFF")
	)
	(segment
		(start 53.2638 -21.143468)
		(end 53.2638 -23.72487)
		(width 0.3048)
		(layer "B.Cu")
		(net "P3V3_VDDA_CLKBUFF")
	)
	(segment
		(start 50.3174 -27.9908)
		(end 51.02098 -27.28722)
		(width 0.3048)
		(layer "B.Cu")
		(net "P3V3_VDDA_CLKBUFF")
	)
	(segment
		(start 51.52517 -27.100784)
		(end 51.338988 -27.286966)
		(width 0.3048)
		(layer "B.Cu")
		(net "P3V3_VDDA_CLKBUFF")
	)
	(segment
		(start 52.998624 -24.6126)
		(end 52.32273 -24.6126)
		(width 0.3048)
		(layer "B.Cu")
		(net "P3V3_VDDA_CLKBUFF")
	)
	(segment
		(start 51.52517 -25.8445)
		(end 51.52517 -27.100784)
		(width 0.3048)
		(layer "B.Cu")
		(net "P3V3_VDDA_CLKBUFF")
	)
	(segment
		(start 51.181 -17.4752)
		(end 51.943 -17.4752)
		(width 0.3048)
		(layer "B.Cu")
		(net "P3V3_VDDA_CLKBUFF")
	)
	(segment
		(start 53.2892 -24.322024)
		(end 52.998624 -24.6126)
		(width 0.3048)
		(layer "B.Cu")
		(net "P3V3_VDDA_CLKBUFF")
	)
	(segment
		(start 51.02479 -17.63141)
		(end 51.181 -17.4752)
		(width 0.3048)
		(layer "B.Cu")
		(net "P3V3_VDDA_CLKBUFF")
	)
	(segment
		(start 50.3174 -29.2608)
		(end 50.3174 -27.9908)
		(width 0.508)
		(layer "B.Cu")
		(net "P3V3_VDDA_CLKBUFF")
	)
	(segment
		(start 53.2892 -23.75027)
		(end 53.2892 -24.322024)
		(width 0.3048)
		(layer "B.Cu")
		(net "P3V3_VDDA_CLKBUFF")
	)
	(segment
		(start 51.02098 -27.28722)
		(end 51.29022 -27.28722)
		(width 0.3048)
		(layer "B.Cu")
		(net "P3V3_VDDA_CLKBUFF")
	)
	(segment
		(start 53.2638 -23.72487)
		(end 53.2892 -23.75027)
		(width 0.3048)
		(layer "B.Cu")
		(net "P3V3_VDDA_CLKBUFF")
	)
	(segment
		(start 51.943 -17.4752)
		(end 52.1208 -17.653)
		(width 0.3048)
		(layer "B.Cu")
		(net "P3V3_VDDA_CLKBUFF")
	)
	(segment
		(start 51.02479 -18.6563)
		(end 51.02479 -17.63141)
		(width 0.3048)
		(layer "B.Cu")
		(net "P3V3_VDDA_CLKBUFF")
	)
	(segment
		(start 51.29022 -27.28722)
		(end 51.290474 -27.286966)
		(width 0.3048)
		(layer "B.Cu")
		(net "P3V3_VDDA_CLKBUFF")
	)
	(segment
		(start 51.52517 -25.41016)
		(end 51.52517 -25.8445)
		(width 0.3048)
		(layer "B.Cu")
		(net "P3V3_VDDA_CLKBUFF")
	)
	(segment
		(start 51.290474 -27.286966)
		(end 51.338988 -27.286966)
		(width 0.3048)
		(layer "B.Cu")
		(net "P3V3_VDDA_CLKBUFF")
	)
	(segment
		(start 44.323 -25.019)
		(end 43.942 -24.638)
		(width 0.3048)
		(layer "F.Cu")
		(net "P3V3_VDD_CLKBUFF")
	)
	(segment
		(start 42.1386 -15.494)
		(end 42.1386 -16.0274)
		(width 0.508)
		(layer "F.Cu")
		(net "P3V3_VDD_CLKBUFF")
	)
	(segment
		(start 46.355 -23.675848)
		(end 46.355 -23.1902)
		(width 0.3048)
		(layer "F.Cu")
		(net "P3V3_VDD_CLKBUFF")
	)
	(segment
		(start 45.974 -20.0152)
		(end 45.8978 -19.939)
		(width 0.3048)
		(layer "F.Cu")
		(net "P3V3_VDD_CLKBUFF")
	)
	(segment
		(start 46.569376 -23.890224)
		(end 46.355 -23.675848)
		(width 0.3048)
		(layer "F.Cu")
		(net "P3V3_VDD_CLKBUFF")
	)
	(segment
		(start 45.6438 -19.177)
		(end 45.6438 -19.685)
		(width 0.3048)
		(layer "F.Cu")
		(net "P3V3_VDD_CLKBUFF")
	)
	(segment
		(start 40.5892 -15.494)
		(end 42.1386 -15.494)
		(width 0.508)
		(layer "F.Cu")
		(net "P3V3_VDD_CLKBUFF")
	)
	(segment
		(start 42.1386 -16.0274)
		(end 41.656 -16.51)
		(width 0.508)
		(layer "F.Cu")
		(net "P3V3_VDD_CLKBUFF")
	)
	(segment
		(start 45.974 -20.6248)
		(end 45.974 -20.0152)
		(width 0.3048)
		(layer "F.Cu")
		(net "P3V3_VDD_CLKBUFF")
	)
	(segment
		(start 44.323 -25.273)
		(end 44.323 -25.019)
		(width 0.3048)
		(layer "F.Cu")
		(net "P3V3_VDD_CLKBUFF")
	)
	(segment
		(start 45.6438 -19.685)
		(end 45.8978 -19.939)
		(width 0.3048)
		(layer "F.Cu")
		(net "P3V3_VDD_CLKBUFF")
	)
	(via
		(at 45.8978 -19.939)
		(size 0.508)
		(drill 0.254)
		(layers "F.Cu" "B.Cu")
		(net "P3V3_VDD_CLKBUFF")
	)
	(via
		(at 41.656 -16.51)
		(size 0.508)
		(drill 0.254)
		(layers "F.Cu" "B.Cu")
		(net "P3V3_VDD_CLKBUFF")
	)
	(via
		(at 38.2778 -27.1272)
		(size 0.7112)
		(drill 0.3556)
		(layers "F.Cu" "B.Cu")
		(net "P3V3_VDD_CLKBUFF")
	)
	(via
		(at 43.942 -24.638)
		(size 0.508)
		(drill 0.254)
		(layers "F.Cu" "B.Cu")
		(net "P3V3_VDD_CLKBUFF")
	)
	(via
		(at 46.569376 -23.890224)
		(size 0.508)
		(drill 0.254)
		(layers "F.Cu" "B.Cu")
		(net "P3V3_VDD_CLKBUFF")
	)
	(segment
		(start 46.0248 -19.939)
		(end 45.8978 -19.939)
		(width 0.3048)
		(layer "B.Cu")
		(net "P3V3_VDD_CLKBUFF")
	)
	(segment
		(start 43.942 -24.638)
		(end 43.479466 -24.638)
		(width 0.3048)
		(layer "B.Cu")
		(net "P3V3_VDD_CLKBUFF")
	)
	(segment
		(start 43.01871 -25.098756)
		(end 42.659554 -24.7396)
		(width 0.3048)
		(layer "B.Cu")
		(net "P3V3_VDD_CLKBUFF")
	)
	(segment
		(start 38.5826 -27.1272)
		(end 38.2778 -27.1272)
		(width 0.3048)
		(layer "B.Cu")
		(net "P3V3_VDD_CLKBUFF")
	)
	(segment
		(start 38.989 -27.5336)
		(end 38.5826 -27.1272)
		(width 0.3048)
		(layer "B.Cu")
		(net "P3V3_VDD_CLKBUFF")
	)
	(segment
		(start 46.52137 -19.44243)
		(end 46.0248 -19.939)
		(width 0.3048)
		(layer "B.Cu")
		(net "P3V3_VDD_CLKBUFF")
	)
	(segment
		(start 43.01871 -25.098756)
		(end 43.01871 -25.8445)
		(width 0.3048)
		(layer "B.Cu")
		(net "P3V3_VDD_CLKBUFF")
	)
	(segment
		(start 41.01719 -25.098756)
		(end 41.01719 -25.8445)
		(width 0.3048)
		(layer "B.Cu")
		(net "P3V3_VDD_CLKBUFF")
	)
	(segment
		(start 43.479466 -24.638)
		(end 43.01871 -25.098756)
		(width 0.3048)
		(layer "B.Cu")
		(net "P3V3_VDD_CLKBUFF")
	)
	(segment
		(start 37.6174 -27.1272)
		(end 38.2778 -27.1272)
		(width 0.3048)
		(layer "B.Cu")
		(net "P3V3_VDD_CLKBUFF")
	)
	(segment
		(start 45.212 -23.368)
		(end 43.942 -24.638)
		(width 0.3048)
		(layer "B.Cu")
		(net "P3V3_VDD_CLKBUFF")
	)
	(segment
		(start 45.3644 -20.4724)
		(end 45.8978 -19.939)
		(width 0.3048)
		(layer "B.Cu")
		(net "P3V3_VDD_CLKBUFF")
	)
	(segment
		(start 37.4142 -26.924)
		(end 37.6174 -27.1272)
		(width 0.3048)
		(layer "B.Cu")
		(net "P3V3_VDD_CLKBUFF")
	)
	(segment
		(start 42.92473 -20.4724)
		(end 45.3644 -20.4724)
		(width 0.3048)
		(layer "B.Cu")
		(net "P3V3_VDD_CLKBUFF")
	)
	(segment
		(start 40.6654 -26.9494)
		(end 40.2336 -26.9494)
		(width 0.3048)
		(layer "B.Cu")
		(net "P3V3_VDD_CLKBUFF")
	)
	(segment
		(start 41.376346 -24.7396)
		(end 41.01719 -25.098756)
		(width 0.3048)
		(layer "B.Cu")
		(net "P3V3_VDD_CLKBUFF")
	)
	(segment
		(start 46.52137 -18.6563)
		(end 46.52137 -19.44243)
		(width 0.3048)
		(layer "B.Cu")
		(net "P3V3_VDD_CLKBUFF")
	)
	(segment
		(start 47.02175 -24.342598)
		(end 46.569376 -23.890224)
		(width 0.3048)
		(layer "B.Cu")
		(net "P3V3_VDD_CLKBUFF")
	)
	(segment
		(start 42.51833 -18.6563)
		(end 42.51833 -20.066)
		(width 0.3048)
		(layer "B.Cu")
		(net "P3V3_VDD_CLKBUFF")
	)
	(segment
		(start 42.51833 -20.066)
		(end 42.92473 -20.4724)
		(width 0.3048)
		(layer "B.Cu")
		(net "P3V3_VDD_CLKBUFF")
	)
	(segment
		(start 46.569376 -23.890224)
		(end 46.047152 -23.368)
		(width 0.3048)
		(layer "B.Cu")
		(net "P3V3_VDD_CLKBUFF")
	)
	(segment
		(start 41.01719 -26.59761)
		(end 40.6654 -26.9494)
		(width 0.3048)
		(layer "B.Cu")
		(net "P3V3_VDD_CLKBUFF")
	)
	(segment
		(start 41.01719 -25.8445)
		(end 41.01719 -26.59761)
		(width 0.3048)
		(layer "B.Cu")
		(net "P3V3_VDD_CLKBUFF")
	)
	(segment
		(start 39.6494 -27.5336)
		(end 38.989 -27.5336)
		(width 0.3048)
		(layer "B.Cu")
		(net "P3V3_VDD_CLKBUFF")
	)
	(segment
		(start 46.047152 -23.368)
		(end 45.212 -23.368)
		(width 0.3048)
		(layer "B.Cu")
		(net "P3V3_VDD_CLKBUFF")
	)
	(segment
		(start 42.659554 -24.7396)
		(end 41.376346 -24.7396)
		(width 0.3048)
		(layer "B.Cu")
		(net "P3V3_VDD_CLKBUFF")
	)
	(segment
		(start 40.2336 -26.9494)
		(end 39.6494 -27.5336)
		(width 0.3048)
		(layer "B.Cu")
		(net "P3V3_VDD_CLKBUFF")
	)
	(segment
		(start 47.02175 -25.8445)
		(end 47.02175 -24.342598)
		(width 0.3048)
		(layer "B.Cu")
		(net "P3V3_VDD_CLKBUFF")
	)
	(segment
		(start 46.569376 -22.007576)
		(end 45.8978 -21.336)
		(width 0.508)
		(layer "In2.Cu")
		(net "P3V3_VDD_CLKBUFF")
	)
	(segment
		(start 45.8978 -21.336)
		(end 45.8978 -19.939)
		(width 0.508)
		(layer "In2.Cu")
		(net "P3V3_VDD_CLKBUFF")
	)
	(segment
		(start 46.569376 -23.890224)
		(end 46.569376 -22.007576)
		(width 0.508)
		(layer "In2.Cu")
		(net "P3V3_VDD_CLKBUFF")
	)
	(segment
		(start 45.8978 -19.690842)
		(end 42.716958 -16.51)
		(width 0.508)
		(layer "In7.Cu")
		(net "P3V3_VDD_CLKBUFF")
	)
	(segment
		(start 45.8978 -19.939)
		(end 45.8978 -19.690842)
		(width 0.508)
		(layer "In7.Cu")
		(net "P3V3_VDD_CLKBUFF")
	)
	(segment
		(start 42.716958 -16.51)
		(end 41.656 -16.51)
		(width 0.508)
		(layer "In7.Cu")
		(net "P3V3_VDD_CLKBUFF")
	)
	(via
		(at 39.2684 -28.2448)
		(size 0.7112)
		(drill 0.3556)
		(layers "F.Cu" "B.Cu")
		(net "CLKCUFF_SMB_ADDR")
	)
	(segment
		(start 39.802562 -28.2448)
		(end 39.2684 -28.2448)
		(width 0.1143)
		(layer "B.Cu")
		(net "CLKCUFF_SMB_ADDR")
	)
	(segment
		(start 40.851328 -27.310842)
		(end 40.73652 -27.310842)
		(width 0.1143)
		(layer "B.Cu")
		(net "CLKCUFF_SMB_ADDR")
	)
	(segment
		(start 41.51757 -26.6446)
		(end 40.851328 -27.310842)
		(width 0.1143)
		(layer "B.Cu")
		(net "CLKCUFF_SMB_ADDR")
	)
	(segment
		(start 37.3888 -27.686)
		(end 37.3888 -28.448)
		(width 0.1143)
		(layer "B.Cu")
		(net "CLKCUFF_SMB_ADDR")
	)
	(segment
		(start 39.2684 -28.2448)
		(end 38.697408 -28.2448)
		(width 0.1143)
		(layer "B.Cu")
		(net "CLKCUFF_SMB_ADDR")
	)
	(segment
		(start 38.697408 -28.2448)
		(end 38.138608 -27.686)
		(width 0.1143)
		(layer "B.Cu")
		(net "CLKCUFF_SMB_ADDR")
	)
	(segment
		(start 40.73652 -27.310842)
		(end 39.802562 -28.2448)
		(width 0.1143)
		(layer "B.Cu")
		(net "CLKCUFF_SMB_ADDR")
	)
	(segment
		(start 41.51757 -25.8445)
		(end 41.51757 -26.6446)
		(width 0.1143)
		(layer "B.Cu")
		(net "CLKCUFF_SMB_ADDR")
	)
	(segment
		(start 38.138608 -27.686)
		(end 37.3888 -27.686)
		(width 0.1143)
		(layer "B.Cu")
		(net "CLKCUFF_SMB_ADDR")
	)
	(segment
		(start 51.52517 -21.24837)
		(end 51.52517 -18.6563)
		(width 0.1143)
		(layer "B.Cu")
		(net "CLKBUFF_SRC_DIV#")
	)
	(segment
		(start 52.6796 -21.463)
		(end 51.7398 -21.463)
		(width 0.1143)
		(layer "B.Cu")
		(net "CLKBUFF_SRC_DIV#")
	)
	(segment
		(start 51.7398 -21.463)
		(end 51.52517 -21.24837)
		(width 0.1143)
		(layer "B.Cu")
		(net "CLKBUFF_SRC_DIV#")
	)
	(via
		(at 34.79927 -20.55622)
		(size 0.7112)
		(drill 0.3556)
		(layers "F.Cu" "B.Cu")
		(net "CLKBUFF_BYPASS_OR_PLL")
	)
	(segment
		(start 36.449 -20.0152)
		(end 37.318188 -20.884388)
		(width 0.1143)
		(layer "B.Cu")
		(net "CLKBUFF_BYPASS_OR_PLL")
	)
	(segment
		(start 37.318188 -20.884388)
		(end 40.075612 -20.884388)
		(width 0.1143)
		(layer "B.Cu")
		(net "CLKBUFF_BYPASS_OR_PLL")
	)
	(segment
		(start 36.449 -20.0152)
		(end 35.687 -20.0152)
		(width 0.1143)
		(layer "B.Cu")
		(net "CLKBUFF_BYPASS_OR_PLL")
	)
	(segment
		(start 41.01719 -19.94281)
		(end 41.01719 -18.6563)
		(width 0.1143)
		(layer "B.Cu")
		(net "CLKBUFF_BYPASS_OR_PLL")
	)
	(segment
		(start 34.79927 -20.55622)
		(end 35.34029 -20.0152)
		(width 0.1143)
		(layer "B.Cu")
		(net "CLKBUFF_BYPASS_OR_PLL")
	)
	(segment
		(start 35.34029 -20.0152)
		(end 35.687 -20.0152)
		(width 0.1143)
		(layer "B.Cu")
		(net "CLKBUFF_BYPASS_OR_PLL")
	)
	(segment
		(start 40.075612 -20.884388)
		(end 41.01719 -19.94281)
		(width 0.1143)
		(layer "B.Cu")
		(net "CLKBUFF_BYPASS_OR_PLL")
	)
	(segment
		(start 88.501728 -41.699434)
		(end 88.501728 -41.870376)
		(width 0.1143)
		(layer "F.Cu")
		(net "LPC_CPU_R_CLKOUT1")
	)
	(segment
		(start 88.219788 -41.417494)
		(end 88.501728 -41.699434)
		(width 0.1143)
		(layer "F.Cu")
		(net "LPC_CPU_R_CLKOUT1")
	)
	(via
		(at 88.501728 -41.870376)
		(size 0.4318)
		(drill 0.2032)
		(layers "F.Cu" "B.Cu")
		(net "LPC_CPU_R_CLKOUT1")
	)
	(segment
		(start 87.757 -42.291)
		(end 88.081104 -42.291)
		(width 0.1143)
		(layer "B.Cu")
		(net "LPC_CPU_R_CLKOUT1")
	)
	(segment
		(start 88.081104 -42.291)
		(end 88.501728 -41.870376)
		(width 0.1143)
		(layer "B.Cu")
		(net "LPC_CPU_R_CLKOUT1")
	)
	(via
		(at 37.5666 -18.6182)
		(size 0.7112)
		(drill 0.3556)
		(layers "F.Cu" "B.Cu")
		(net "SMB_CLKBUFF_R_DATA")
	)
	(segment
		(start 38.135052 -19.893788)
		(end 37.5666 -19.325336)
		(width 0.1143)
		(layer "B.Cu")
		(net "SMB_CLKBUFF_R_DATA")
	)
	(segment
		(start 35.1028 -16.256)
		(end 36.822126 -16.256)
		(width 0.1143)
		(layer "B.Cu")
		(net "SMB_CLKBUFF_R_DATA")
	)
	(segment
		(start 39.628826 -19.614134)
		(end 39.349172 -19.893788)
		(width 0.1143)
		(layer "B.Cu")
		(net "SMB_CLKBUFF_R_DATA")
	)
	(segment
		(start 39.349172 -19.893788)
		(end 38.135052 -19.893788)
		(width 0.1143)
		(layer "B.Cu")
		(net "SMB_CLKBUFF_R_DATA")
	)
	(segment
		(start 36.822126 -16.256)
		(end 37.5666 -17.000474)
		(width 0.1143)
		(layer "B.Cu")
		(net "SMB_CLKBUFF_R_DATA")
	)
	(segment
		(start 37.5666 -19.325336)
		(end 37.5666 -18.6182)
		(width 0.1143)
		(layer "B.Cu")
		(net "SMB_CLKBUFF_R_DATA")
	)
	(segment
		(start 40.01643 -19.226784)
		(end 39.628826 -19.614134)
		(width 0.1143)
		(layer "B.Cu")
		(net "SMB_CLKBUFF_R_DATA")
	)
	(segment
		(start 37.5666 -17.000474)
		(end 37.5666 -18.6182)
		(width 0.1143)
		(layer "B.Cu")
		(net "SMB_CLKBUFF_R_DATA")
	)
	(segment
		(start 40.01643 -18.6563)
		(end 40.01643 -19.226784)
		(width 0.1143)
		(layer "B.Cu")
		(net "SMB_CLKBUFF_R_DATA")
	)
	(segment
		(start 43.942 -14.331442)
		(end 43.4594 -14.814042)
		(width 0.508)
		(layer "F.Cu")
		(net "P3V3_VDD_CLKBUFF_R")
	)
	(segment
		(start 43.967654 -14.357096)
		(end 43.942 -14.331442)
		(width 0.508)
		(layer "F.Cu")
		(net "P3V3_VDD_CLKBUFF_R")
	)
	(segment
		(start 43.4594 -14.814042)
		(end 43.4594 -15.494)
		(width 0.508)
		(layer "F.Cu")
		(net "P3V3_VDD_CLKBUFF_R")
	)
	(segment
		(start 44.5516 -14.6812)
		(end 44.227496 -14.357096)
		(width 0.508)
		(layer "F.Cu")
		(net "P3V3_VDD_CLKBUFF_R")
	)
	(segment
		(start 44.227496 -14.357096)
		(end 43.967654 -14.357096)
		(width 0.508)
		(layer "F.Cu")
		(net "P3V3_VDD_CLKBUFF_R")
	)
	(segment
		(start 44.5516 -15.494)
		(end 44.5516 -14.6812)
		(width 0.508)
		(layer "F.Cu")
		(net "P3V3_VDD_CLKBUFF_R")
	)
	(via
		(at 43.942 -14.331442)
		(size 0.7112)
		(drill 0.3556)
		(layers "F.Cu" "B.Cu")
		(net "P3V3_VDD_CLKBUFF_R")
	)
	(segment
		(start 137.5664 -46.593506)
		(end 137.9982 -46.161706)
		(width 0.1143)
		(layer "F.Cu")
		(net "REV_CPU_FPGA_R_IO0")
	)
	(segment
		(start 137.5537 -46.6217)
		(end 137.5664 -46.609)
		(width 0.1143)
		(layer "F.Cu")
		(net "REV_CPU_FPGA_R_IO0")
	)
	(segment
		(start 137.5664 -46.609)
		(end 137.5664 -46.593506)
		(width 0.1143)
		(layer "F.Cu")
		(net "REV_CPU_FPGA_R_IO0")
	)
	(segment
		(start 137.9982 -46.161706)
		(end 137.9982 -45.1612)
		(width 0.1143)
		(layer "F.Cu")
		(net "REV_CPU_FPGA_R_IO0")
	)
	(via
		(at 137.5537 -46.6217)
		(size 0.508)
		(drill 0.254)
		(layers "F.Cu" "B.Cu")
		(net "REV_CPU_FPGA_R_IO0")
	)
	(via
		(at 137.4394 -47.625)
		(size 0.7112)
		(drill 0.3556)
		(layers "F.Cu" "B.Cu")
		(net "REV_CPU_FPGA_R_IO0")
	)
	(segment
		(start 137.5537 -46.6217)
		(end 137.5537 -46.6598)
		(width 0.1143)
		(layer "B.Cu")
		(net "REV_CPU_FPGA_R_IO0")
	)
	(segment
		(start 136.4234 -48.641)
		(end 137.4394 -47.625)
		(width 0.1143)
		(layer "B.Cu")
		(net "REV_CPU_FPGA_R_IO0")
	)
	(segment
		(start 137.541 -46.6725)
		(end 137.541 -47.5234)
		(width 0.1143)
		(layer "B.Cu")
		(net "REV_CPU_FPGA_R_IO0")
	)
	(segment
		(start 137.5537 -46.6598)
		(end 137.541 -46.6725)
		(width 0.1143)
		(layer "B.Cu")
		(net "REV_CPU_FPGA_R_IO0")
	)
	(segment
		(start 137.541 -47.5234)
		(end 137.4394 -47.625)
		(width 0.1143)
		(layer "B.Cu")
		(net "REV_CPU_FPGA_R_IO0")
	)
	(segment
		(start 134.7978 -48.641)
		(end 136.4234 -48.641)
		(width 0.1143)
		(layer "B.Cu")
		(net "REV_CPU_FPGA_R_IO0")
	)
	(segment
		(start 135.8519 -46.609)
		(end 135.8519 -46.5201)
		(width 0.1143)
		(layer "F.Cu")
		(net "REV_CPU_FPGA_R_IO1")
	)
	(segment
		(start 135.8265 -46.6344)
		(end 135.8519 -46.609)
		(width 0.1143)
		(layer "F.Cu")
		(net "REV_CPU_FPGA_R_IO1")
	)
	(segment
		(start 135.8519 -46.5201)
		(end 136.39165 -45.98035)
		(width 0.1143)
		(layer "F.Cu")
		(net "REV_CPU_FPGA_R_IO1")
	)
	(segment
		(start 136.99744 -45.710094)
		(end 136.99744 -45.1612)
		(width 0.1143)
		(layer "F.Cu")
		(net "REV_CPU_FPGA_R_IO1")
	)
	(segment
		(start 136.727184 -45.98035)
		(end 136.99744 -45.710094)
		(width 0.1143)
		(layer "F.Cu")
		(net "REV_CPU_FPGA_R_IO1")
	)
	(segment
		(start 136.39165 -45.98035)
		(end 136.727184 -45.98035)
		(width 0.1143)
		(layer "F.Cu")
		(net "REV_CPU_FPGA_R_IO1")
	)
	(via
		(at 135.8138 -47.6123)
		(size 0.7112)
		(drill 0.3556)
		(layers "F.Cu" "B.Cu")
		(net "REV_CPU_FPGA_R_IO1")
	)
	(via
		(at 135.8265 -46.6344)
		(size 0.508)
		(drill 0.254)
		(layers "F.Cu" "B.Cu")
		(net "REV_CPU_FPGA_R_IO1")
	)
	(segment
		(start 134.7978 -47.879)
		(end 135.5471 -47.879)
		(width 0.1143)
		(layer "B.Cu")
		(net "REV_CPU_FPGA_R_IO1")
	)
	(segment
		(start 135.8265 -46.6598)
		(end 135.8138 -46.6725)
		(width 0.1143)
		(layer "B.Cu")
		(net "REV_CPU_FPGA_R_IO1")
	)
	(segment
		(start 135.8138 -46.6725)
		(end 135.8138 -47.6123)
		(width 0.1143)
		(layer "B.Cu")
		(net "REV_CPU_FPGA_R_IO1")
	)
	(segment
		(start 135.5471 -47.879)
		(end 135.8138 -47.6123)
		(width 0.1143)
		(layer "B.Cu")
		(net "REV_CPU_FPGA_R_IO1")
	)
	(segment
		(start 135.8265 -46.6344)
		(end 135.8265 -46.6598)
		(width 0.1143)
		(layer "B.Cu")
		(net "REV_CPU_FPGA_R_IO1")
	)
	(segment
		(start 84.021168 -8.7757)
		(end 84.021168 -10.123424)
		(width 0.1397)
		(layer "F.Cu")
		(net "CLK_100M_PCIE_SAS_DP")
	)
	(segment
		(start 84.349844 -8.447024)
		(end 84.021168 -8.7757)
		(width 0.1397)
		(layer "F.Cu")
		(net "CLK_100M_PCIE_SAS_DP")
	)
	(segment
		(start 84.021168 -10.123424)
		(end 84.310474 -10.41273)
		(width 0.1397)
		(layer "F.Cu")
		(net "CLK_100M_PCIE_SAS_DP")
	)
	(segment
		(start 84.349844 -6.195568)
		(end 84.349844 -8.447024)
		(width 0.1397)
		(layer "F.Cu")
		(net "CLK_100M_PCIE_SAS_DP")
	)
	(via
		(at 84.310474 -10.41273)
		(size 0.508)
		(drill 0.254)
		(layers "F.Cu" "B.Cu")
		(net "CLK_100M_PCIE_SAS_DP")
	)
	(via
		(at 40.40124 -12.34694)
		(size 0.508)
		(drill 0.254)
		(layers "F.Cu" "B.Cu")
		(net "CLK_100M_PCIE_SAS_DP")
	)
	(segment
		(start 40.43045 -14.31925)
		(end 40.7162 -14.605)
		(width 0.1397)
		(layer "B.Cu")
		(net "CLK_100M_PCIE_SAS_DP")
	)
	(segment
		(start 40.0939 -12.65428)
		(end 40.0939 -13.4239)
		(width 0.1397)
		(layer "B.Cu")
		(net "CLK_100M_PCIE_SAS_DP")
	)
	(segment
		(start 40.64 -14.6812)
		(end 40.7162 -14.605)
		(width 0.1397)
		(layer "B.Cu")
		(net "CLK_100M_PCIE_SAS_DP")
	)
	(segment
		(start 40.43045 -13.76045)
		(end 40.43045 -14.31925)
		(width 0.1397)
		(layer "B.Cu")
		(net "CLK_100M_PCIE_SAS_DP")
	)
	(segment
		(start 40.40124 -12.34694)
		(end 40.0939 -12.65428)
		(width 0.1397)
		(layer "B.Cu")
		(net "CLK_100M_PCIE_SAS_DP")
	)
	(segment
		(start 40.0939 -13.4239)
		(end 40.43045 -13.76045)
		(width 0.1397)
		(layer "B.Cu")
		(net "CLK_100M_PCIE_SAS_DP")
	)
	(segment
		(start 40.64 -15.4686)
		(end 40.64 -14.6812)
		(width 0.1397)
		(layer "B.Cu")
		(net "CLK_100M_PCIE_SAS_DP")
	)
	(segment
		(start 83.872324 -10.85088)
		(end 84.310474 -10.41273)
		(width 0.1143)
		(layer "In2.Cu")
		(net "CLK_100M_PCIE_SAS_DP")
	)
	(segment
		(start 81.1657 -9.0297)
		(end 81.8134 -9.6774)
		(width 0.1143)
		(layer "In2.Cu")
		(net "CLK_100M_PCIE_SAS_DP")
	)
	(segment
		(start 42.037 -9.890506)
		(end 42.037 -9.525)
		(width 0.1143)
		(layer "In2.Cu")
		(net "CLK_100M_PCIE_SAS_DP")
	)
	(segment
		(start 42.037 -9.525)
		(end 42.5323 -9.0297)
		(width 0.1143)
		(layer "In2.Cu")
		(net "CLK_100M_PCIE_SAS_DP")
	)
	(segment
		(start 81.8134 -9.6774)
		(end 81.8134 -10.033)
		(width 0.1143)
		(layer "In2.Cu")
		(net "CLK_100M_PCIE_SAS_DP")
	)
	(segment
		(start 40.08755 -12.03325)
		(end 40.08755 -11.839956)
		(width 0.1143)
		(layer "In2.Cu")
		(net "CLK_100M_PCIE_SAS_DP")
	)
	(segment
		(start 81.8134 -10.033)
		(end 82.63128 -10.85088)
		(width 0.1143)
		(layer "In2.Cu")
		(net "CLK_100M_PCIE_SAS_DP")
	)
	(segment
		(start 42.5323 -9.0297)
		(end 81.1657 -9.0297)
		(width 0.1143)
		(layer "In2.Cu")
		(net "CLK_100M_PCIE_SAS_DP")
	)
	(segment
		(start 82.63128 -10.85088)
		(end 83.872324 -10.85088)
		(width 0.1143)
		(layer "In2.Cu")
		(net "CLK_100M_PCIE_SAS_DP")
	)
	(segment
		(start 40.08755 -11.839956)
		(end 42.037 -9.890506)
		(width 0.1143)
		(layer "In2.Cu")
		(net "CLK_100M_PCIE_SAS_DP")
	)
	(segment
		(start 40.40124 -12.34694)
		(end 40.08755 -12.03325)
		(width 0.1143)
		(layer "In2.Cu")
		(net "CLK_100M_PCIE_SAS_DP")
	)
	(segment
		(start 83.678268 -10.123424)
		(end 83.388962 -10.41273)
		(width 0.1397)
		(layer "F.Cu")
		(net "CLK_100M_PCIE_SAS_DN")
	)
	(segment
		(start 83.678268 -8.7757)
		(end 83.678268 -10.123424)
		(width 0.1397)
		(layer "F.Cu")
		(net "CLK_100M_PCIE_SAS_DN")
	)
	(segment
		(start 83.349846 -6.195568)
		(end 83.349846 -8.447278)
		(width 0.1397)
		(layer "F.Cu")
		(net "CLK_100M_PCIE_SAS_DN")
	)
	(segment
		(start 83.349846 -8.447278)
		(end 83.678268 -8.7757)
		(width 0.1397)
		(layer "F.Cu")
		(net "CLK_100M_PCIE_SAS_DN")
	)
	(via
		(at 83.388962 -10.41273)
		(size 0.508)
		(drill 0.254)
		(layers "F.Cu" "B.Cu")
		(net "CLK_100M_PCIE_SAS_DN")
	)
	(via
		(at 39.44366 -12.34694)
		(size 0.508)
		(drill 0.254)
		(layers "F.Cu" "B.Cu")
		(net "CLK_100M_PCIE_SAS_DN")
	)
	(segment
		(start 39.44366 -12.34694)
		(end 39.751 -12.65428)
		(width 0.1397)
		(layer "B.Cu")
		(net "CLK_100M_PCIE_SAS_DN")
	)
	(segment
		(start 40.08755 -14.31925)
		(end 39.8018 -14.605)
		(width 0.1397)
		(layer "B.Cu")
		(net "CLK_100M_PCIE_SAS_DN")
	)
	(segment
		(start 39.751 -12.65428)
		(end 39.751 -13.56614)
		(width 0.1397)
		(layer "B.Cu")
		(net "CLK_100M_PCIE_SAS_DN")
	)
	(segment
		(start 40.08755 -13.90269)
		(end 40.08755 -14.31925)
		(width 0.1397)
		(layer "B.Cu")
		(net "CLK_100M_PCIE_SAS_DN")
	)
	(segment
		(start 39.878 -15.4686)
		(end 39.878 -14.6812)
		(width 0.1397)
		(layer "B.Cu")
		(net "CLK_100M_PCIE_SAS_DN")
	)
	(segment
		(start 39.878 -14.6812)
		(end 39.8018 -14.605)
		(width 0.1397)
		(layer "B.Cu")
		(net "CLK_100M_PCIE_SAS_DN")
	)
	(segment
		(start 39.751 -13.56614)
		(end 40.08755 -13.90269)
		(width 0.1397)
		(layer "B.Cu")
		(net "CLK_100M_PCIE_SAS_DN")
	)
	(segment
		(start 54.77891 -8.6995)
		(end 54.56555 -8.48614)
		(width 0.1143)
		(layer "In2.Cu")
		(net "CLK_100M_PCIE_SAS_DN")
	)
	(segment
		(start 56.79059 -8.48614)
		(end 56.44769 -8.48614)
		(width 0.1143)
		(layer "In2.Cu")
		(net "CLK_100M_PCIE_SAS_DN")
	)
	(segment
		(start 55.12181 -8.6995)
		(end 54.77891 -8.6995)
		(width 0.1143)
		(layer "In2.Cu")
		(net "CLK_100M_PCIE_SAS_DN")
	)
	(segment
		(start 39.75735 -12.03325)
		(end 39.44366 -12.34694)
		(width 0.1143)
		(layer "In2.Cu")
		(net "CLK_100M_PCIE_SAS_DN")
	)
	(segment
		(start 82.1436 -9.896094)
		(end 82.1436 -9.540494)
		(width 0.1143)
		(layer "In2.Cu")
		(net "CLK_100M_PCIE_SAS_DN")
	)
	(segment
		(start 42.395394 -8.6995)
		(end 41.7068 -9.388094)
		(width 0.1143)
		(layer "In2.Cu")
		(net "CLK_100M_PCIE_SAS_DN")
	)
	(segment
		(start 55.89143 -8.6995)
		(end 55.67807 -8.48614)
		(width 0.1143)
		(layer "In2.Cu")
		(net "CLK_100M_PCIE_SAS_DN")
	)
	(segment
		(start 83.281012 -10.52068)
		(end 82.768186 -10.52068)
		(width 0.1143)
		(layer "In2.Cu")
		(net "CLK_100M_PCIE_SAS_DN")
	)
	(segment
		(start 81.302606 -8.6995)
		(end 57.00395 -8.6995)
		(width 0.1143)
		(layer "In2.Cu")
		(net "CLK_100M_PCIE_SAS_DN")
	)
	(segment
		(start 55.33517 -8.48614)
		(end 55.12181 -8.6995)
		(width 0.1143)
		(layer "In2.Cu")
		(net "CLK_100M_PCIE_SAS_DN")
	)
	(segment
		(start 55.67807 -8.48614)
		(end 55.33517 -8.48614)
		(width 0.1143)
		(layer "In2.Cu")
		(net "CLK_100M_PCIE_SAS_DN")
	)
	(segment
		(start 82.1436 -9.540494)
		(end 81.302606 -8.6995)
		(width 0.1143)
		(layer "In2.Cu")
		(net "CLK_100M_PCIE_SAS_DN")
	)
	(segment
		(start 56.44769 -8.48614)
		(end 56.23433 -8.6995)
		(width 0.1143)
		(layer "In2.Cu")
		(net "CLK_100M_PCIE_SAS_DN")
	)
	(segment
		(start 54.56555 -8.48614)
		(end 54.22265 -8.48614)
		(width 0.1143)
		(layer "In2.Cu")
		(net "CLK_100M_PCIE_SAS_DN")
	)
	(segment
		(start 41.7068 -9.7536)
		(end 39.75735 -11.70305)
		(width 0.1143)
		(layer "In2.Cu")
		(net "CLK_100M_PCIE_SAS_DN")
	)
	(segment
		(start 57.00395 -8.6995)
		(end 56.79059 -8.48614)
		(width 0.1143)
		(layer "In2.Cu")
		(net "CLK_100M_PCIE_SAS_DN")
	)
	(segment
		(start 39.75735 -11.70305)
		(end 39.75735 -12.03325)
		(width 0.1143)
		(layer "In2.Cu")
		(net "CLK_100M_PCIE_SAS_DN")
	)
	(segment
		(start 83.388962 -10.41273)
		(end 83.281012 -10.52068)
		(width 0.1143)
		(layer "In2.Cu")
		(net "CLK_100M_PCIE_SAS_DN")
	)
	(segment
		(start 41.7068 -9.388094)
		(end 41.7068 -9.7536)
		(width 0.1143)
		(layer "In2.Cu")
		(net "CLK_100M_PCIE_SAS_DN")
	)
	(segment
		(start 54.22265 -8.48614)
		(end 54.00929 -8.6995)
		(width 0.1143)
		(layer "In2.Cu")
		(net "CLK_100M_PCIE_SAS_DN")
	)
	(segment
		(start 56.23433 -8.6995)
		(end 55.89143 -8.6995)
		(width 0.1143)
		(layer "In2.Cu")
		(net "CLK_100M_PCIE_SAS_DN")
	)
	(segment
		(start 54.00929 -8.6995)
		(end 42.395394 -8.6995)
		(width 0.1143)
		(layer "In2.Cu")
		(net "CLK_100M_PCIE_SAS_DN")
	)
	(segment
		(start 82.768186 -10.52068)
		(end 82.1436 -9.896094)
		(width 0.1143)
		(layer "In2.Cu")
		(net "CLK_100M_PCIE_SAS_DN")
	)
	(via
		(at 59.69 -11.938)
		(size 0.7112)
		(drill 0.3556)
		(layers "F.Cu" "B.Cu")
		(net "PCIE2_RESET#")
	)
	(segment
		(start 57.402476 -9.348724)
		(end 57.349898 -9.296146)
		(width 0.1143)
		(layer "B.Cu")
		(net "PCIE2_RESET#")
	)
	(segment
		(start 60.071 -12.9032)
		(end 60.071 -12.319)
		(width 0.1143)
		(layer "B.Cu")
		(net "PCIE2_RESET#")
	)
	(segment
		(start 59.182 -11.43)
		(end 58.0644 -11.43)
		(width 0.1143)
		(layer "B.Cu")
		(net "PCIE2_RESET#")
	)
	(segment
		(start 59.69 -11.938)
		(end 59.182 -11.43)
		(width 0.1143)
		(layer "B.Cu")
		(net "PCIE2_RESET#")
	)
	(segment
		(start 57.349898 -9.296146)
		(end 57.349898 -5.814568)
		(width 0.1143)
		(layer "B.Cu")
		(net "PCIE2_RESET#")
	)
	(segment
		(start 57.402476 -10.768076)
		(end 57.402476 -9.348724)
		(width 0.1143)
		(layer "B.Cu")
		(net "PCIE2_RESET#")
	)
	(segment
		(start 60.071 -12.319)
		(end 59.69 -11.938)
		(width 0.1143)
		(layer "B.Cu")
		(net "PCIE2_RESET#")
	)
	(segment
		(start 58.0644 -11.43)
		(end 57.402476 -10.768076)
		(width 0.1143)
		(layer "B.Cu")
		(net "PCIE2_RESET#")
	)
	(via
		(at 47.9425 -30.463998)
		(size 0.7112)
		(drill 0.3556)
		(layers "F.Cu" "B.Cu")
		(net "P3V3_VDDA_CLKBUFF_R")
	)
	(segment
		(start 48.9966 -30.5308)
		(end 48.9966 -29.2608)
		(width 0.508)
		(layer "B.Cu")
		(net "P3V3_VDDA_CLKBUFF_R")
	)
	(segment
		(start 48.9966 -30.5308)
		(end 48.009302 -30.5308)
		(width 0.508)
		(layer "B.Cu")
		(net "P3V3_VDDA_CLKBUFF_R")
	)
	(segment
		(start 48.009302 -30.5308)
		(end 47.9425 -30.463998)
		(width 0.508)
		(layer "B.Cu")
		(net "P3V3_VDDA_CLKBUFF_R")
	)
	(segment
		(start 45.3644 -27.4828)
		(end 45.02023 -27.13863)
		(width 0.1143)
		(layer "B.Cu")
		(net "CLKBUFF_OE5#")
	)
	(segment
		(start 44.6024 -27.8892)
		(end 45.3644 -27.8892)
		(width 0.1143)
		(layer "B.Cu")
		(net "CLKBUFF_OE5#")
	)
	(segment
		(start 45.3644 -27.8892)
		(end 45.3644 -27.4828)
		(width 0.1143)
		(layer "B.Cu")
		(net "CLKBUFF_OE5#")
	)
	(segment
		(start 45.02023 -27.13863)
		(end 45.02023 -25.8445)
		(width 0.1143)
		(layer "B.Cu")
		(net "CLKBUFF_OE5#")
	)
	(segment
		(start 50.6476 -24.4094)
		(end 49.984406 -24.4094)
		(width 0.1143)
		(layer "F.Cu")
		(net "CLKBUFF_OE7#")
	)
	(segment
		(start 50.1904 -23.4188)
		(end 50.1904 -23.495)
		(width 0.1143)
		(layer "F.Cu")
		(net "CLKBUFF_OE7#")
	)
	(segment
		(start 50.1904 -23.495)
		(end 49.781206 -23.904194)
		(width 0.1143)
		(layer "F.Cu")
		(net "CLKBUFF_OE7#")
	)
	(segment
		(start 49.781206 -23.904194)
		(end 49.781206 -24.2062)
		(width 0.1143)
		(layer "F.Cu")
		(net "CLKBUFF_OE7#")
	)
	(segment
		(start 51.0032 -23.495)
		(end 51.0032 -24.0538)
		(width 0.1143)
		(layer "F.Cu")
		(net "CLKBUFF_OE7#")
	)
	(segment
		(start 49.984406 -24.4094)
		(end 49.781206 -24.2062)
		(width 0.1143)
		(layer "F.Cu")
		(net "CLKBUFF_OE7#")
	)
	(segment
		(start 51.0032 -24.0538)
		(end 50.6476 -24.4094)
		(width 0.1143)
		(layer "F.Cu")
		(net "CLKBUFF_OE7#")
	)
	(via
		(at 49.781206 -24.2062)
		(size 0.508)
		(drill 0.254)
		(layers "F.Cu" "B.Cu")
		(net "CLKBUFF_OE7#")
	)
	(segment
		(start 49.52365 -25.22855)
		(end 49.911 -24.8412)
		(width 0.1143)
		(layer "B.Cu")
		(net "CLKBUFF_OE7#")
	)
	(segment
		(start 49.911 -24.335994)
		(end 49.781206 -24.2062)
		(width 0.1143)
		(layer "B.Cu")
		(net "CLKBUFF_OE7#")
	)
	(segment
		(start 49.52365 -25.8445)
		(end 49.52365 -25.22855)
		(width 0.1143)
		(layer "B.Cu")
		(net "CLKBUFF_OE7#")
	)
	(segment
		(start 49.911 -24.8412)
		(end 49.911 -24.335994)
		(width 0.1143)
		(layer "B.Cu")
		(net "CLKBUFF_OE7#")
	)
	(segment
		(start 49.276 -24.426164)
		(end 49.276 -23.9268)
		(width 0.1143)
		(layer "F.Cu")
		(net "CLKBUFF_OE4#")
	)
	(segment
		(start 49.4284 -23.7744)
		(end 49.4284 -23.4188)
		(width 0.1143)
		(layer "F.Cu")
		(net "CLKBUFF_OE4#")
	)
	(segment
		(start 52.7812 -24.56815)
		(end 52.7812 -23.495)
		(width 0.1143)
		(layer "F.Cu")
		(net "CLKBUFF_OE4#")
	)
	(segment
		(start 49.276 -23.9268)
		(end 49.4284 -23.7744)
		(width 0.1143)
		(layer "F.Cu")
		(net "CLKBUFF_OE4#")
	)
	(segment
		(start 52.197 -25.15235)
		(end 52.7812 -24.56815)
		(width 0.1143)
		(layer "F.Cu")
		(net "CLKBUFF_OE4#")
	)
	(segment
		(start 49.024794 -24.67737)
		(end 49.276 -24.426164)
		(width 0.1143)
		(layer "F.Cu")
		(net "CLKBUFF_OE4#")
	)
	(segment
		(start 49.024794 -24.67737)
		(end 49.499774 -25.15235)
		(width 0.1143)
		(layer "F.Cu")
		(net "CLKBUFF_OE4#")
	)
	(segment
		(start 49.499774 -25.15235)
		(end 52.197 -25.15235)
		(width 0.1143)
		(layer "F.Cu")
		(net "CLKBUFF_OE4#")
	)
	(segment
		(start 49.02327 -24.67737)
		(end 49.024794 -24.67737)
		(width 0.1143)
		(layer "F.Cu")
		(net "CLKBUFF_OE4#")
	)
	(via
		(at 49.02327 -24.67737)
		(size 0.508)
		(drill 0.254)
		(layers "F.Cu" "B.Cu")
		(net "CLKBUFF_OE4#")
	)
	(segment
		(start 49.02327 -24.67737)
		(end 49.02327 -25.8445)
		(width 0.1143)
		(layer "B.Cu")
		(net "CLKBUFF_OE4#")
	)
	(segment
		(start 46.1264 -27.8892)
		(end 46.1264 -27.857196)
		(width 0.1143)
		(layer "B.Cu")
		(net "CLKBUFF_OE6#")
	)
	(segment
		(start 45.52061 -27.251406)
		(end 45.52061 -25.8445)
		(width 0.1143)
		(layer "B.Cu")
		(net "CLKBUFF_OE6#")
	)
	(segment
		(start 46.8884 -27.8892)
		(end 46.1264 -27.8892)
		(width 0.1143)
		(layer "B.Cu")
		(net "CLKBUFF_OE6#")
	)
	(segment
		(start 46.1264 -27.857196)
		(end 45.52061 -27.251406)
		(width 0.1143)
		(layer "B.Cu")
		(net "CLKBUFF_OE6#")
	)
	(segment
		(start 60.349892 -8.447278)
		(end 60.02147 -8.7757)
		(width 0.1397)
		(layer "F.Cu")
		(net "CLK_100M_PCIE2_REFCLK_DP")
	)
	(segment
		(start 59.69127 -10.18413)
		(end 59.69127 -10.630154)
		(width 0.1397)
		(layer "F.Cu")
		(net "CLK_100M_PCIE2_REFCLK_DP")
	)
	(segment
		(start 59.69127 -10.630154)
		(end 59.997594 -10.936478)
		(width 0.1397)
		(layer "F.Cu")
		(net "CLK_100M_PCIE2_REFCLK_DP")
	)
	(segment
		(start 60.349892 -6.195568)
		(end 60.349892 -8.447278)
		(width 0.1397)
		(layer "F.Cu")
		(net "CLK_100M_PCIE2_REFCLK_DP")
	)
	(segment
		(start 60.02147 -8.7757)
		(end 60.02147 -9.85393)
		(width 0.1397)
		(layer "F.Cu")
		(net "CLK_100M_PCIE2_REFCLK_DP")
	)
	(segment
		(start 60.02147 -9.85393)
		(end 59.69127 -10.18413)
		(width 0.1397)
		(layer "F.Cu")
		(net "CLK_100M_PCIE2_REFCLK_DP")
	)
	(via
		(at 59.997594 -10.936478)
		(size 0.508)
		(drill 0.254)
		(layers "F.Cu" "B.Cu")
		(net "CLK_100M_PCIE2_REFCLK_DP")
	)
	(via
		(at 48.1838 -13.7922)
		(size 0.508)
		(drill 0.254)
		(layers "F.Cu" "B.Cu")
		(net "CLK_100M_PCIE2_REFCLK_DP")
	)
	(segment
		(start 48.2092 -14.605)
		(end 47.93615 -14.33195)
		(width 0.1397)
		(layer "B.Cu")
		(net "CLK_100M_PCIE2_REFCLK_DP")
	)
	(segment
		(start 48.133 -14.6812)
		(end 48.2092 -14.605)
		(width 0.1397)
		(layer "B.Cu")
		(net "CLK_100M_PCIE2_REFCLK_DP")
	)
	(segment
		(start 47.93615 -14.03985)
		(end 48.1838 -13.7922)
		(width 0.1397)
		(layer "B.Cu")
		(net "CLK_100M_PCIE2_REFCLK_DP")
	)
	(segment
		(start 48.133 -15.4686)
		(end 48.133 -14.6812)
		(width 0.1397)
		(layer "B.Cu")
		(net "CLK_100M_PCIE2_REFCLK_DP")
	)
	(segment
		(start 47.93615 -14.33195)
		(end 47.93615 -14.03985)
		(width 0.1397)
		(layer "B.Cu")
		(net "CLK_100M_PCIE2_REFCLK_DP")
	)
	(segment
		(start 48.0314 -12.7762)
		(end 48.0314 -13.6398)
		(width 0.1143)
		(layer "In2.Cu")
		(net "CLK_100M_PCIE2_REFCLK_DP")
	)
	(segment
		(start 48.0314 -13.6398)
		(end 48.1838 -13.7922)
		(width 0.1143)
		(layer "In2.Cu")
		(net "CLK_100M_PCIE2_REFCLK_DP")
	)
	(segment
		(start 59.702954 -11.630152)
		(end 59.369706 -11.9634)
		(width 0.1143)
		(layer "In2.Cu")
		(net "CLK_100M_PCIE2_REFCLK_DP")
	)
	(segment
		(start 59.369706 -11.9634)
		(end 48.8442 -11.9634)
		(width 0.1143)
		(layer "In2.Cu")
		(net "CLK_100M_PCIE2_REFCLK_DP")
	)
	(segment
		(start 59.702954 -11.231118)
		(end 59.702954 -11.630152)
		(width 0.1143)
		(layer "In2.Cu")
		(net "CLK_100M_PCIE2_REFCLK_DP")
	)
	(segment
		(start 59.997594 -10.936478)
		(end 59.702954 -11.231118)
		(width 0.1143)
		(layer "In2.Cu")
		(net "CLK_100M_PCIE2_REFCLK_DP")
	)
	(segment
		(start 48.8442 -11.9634)
		(end 48.0314 -12.7762)
		(width 0.1143)
		(layer "In2.Cu")
		(net "CLK_100M_PCIE2_REFCLK_DP")
	)
	(segment
		(start 46.063408 -17.046702)
		(end 45.59935 -17.51076)
		(width 0.1397)
		(layer "B.Cu")
		(net "CLK_100M_PCIE2_REFCLK_R_DN")
	)
	(segment
		(start 47.399448 -17.046702)
		(end 46.063408 -17.046702)
		(width 0.1397)
		(layer "B.Cu")
		(net "CLK_100M_PCIE2_REFCLK_R_DN")
	)
	(segment
		(start 47.58055 -16.8656)
		(end 47.399448 -17.046702)
		(width 0.1397)
		(layer "B.Cu")
		(net "CLK_100M_PCIE2_REFCLK_R_DN")
	)
	(segment
		(start 45.59935 -17.51076)
		(end 45.59935 -17.97685)
		(width 0.1397)
		(layer "B.Cu")
		(net "CLK_100M_PCIE2_REFCLK_R_DN")
	)
	(segment
		(start 45.59935 -17.97685)
		(end 45.52061 -18.05559)
		(width 0.1397)
		(layer "B.Cu")
		(net "CLK_100M_PCIE2_REFCLK_R_DN")
	)
	(segment
		(start 47.58055 -16.54175)
		(end 47.58055 -16.8656)
		(width 0.1397)
		(layer "B.Cu")
		(net "CLK_100M_PCIE2_REFCLK_R_DN")
	)
	(segment
		(start 45.52061 -18.05559)
		(end 45.52061 -18.6563)
		(width 0.1397)
		(layer "B.Cu")
		(net "CLK_100M_PCIE2_REFCLK_R_DN")
	)
	(segment
		(start 47.371 -16.3322)
		(end 47.58055 -16.54175)
		(width 0.1397)
		(layer "B.Cu")
		(net "CLK_100M_PCIE2_REFCLK_R_DN")
	)
	(segment
		(start 45.94225 -17.653)
		(end 45.94225 -18.0086)
		(width 0.1397)
		(layer "B.Cu")
		(net "CLK_100M_PCIE2_REFCLK_R_DP")
	)
	(segment
		(start 47.92345 -16.54175)
		(end 47.92345 -17.00784)
		(width 0.1397)
		(layer "B.Cu")
		(net "CLK_100M_PCIE2_REFCLK_R_DP")
	)
	(segment
		(start 46.02099 -18.08734)
		(end 46.02099 -18.6563)
		(width 0.1397)
		(layer "B.Cu")
		(net "CLK_100M_PCIE2_REFCLK_R_DP")
	)
	(segment
		(start 48.133 -16.3322)
		(end 47.92345 -16.54175)
		(width 0.1397)
		(layer "B.Cu")
		(net "CLK_100M_PCIE2_REFCLK_R_DP")
	)
	(segment
		(start 47.92345 -17.00784)
		(end 47.541688 -17.389602)
		(width 0.1397)
		(layer "B.Cu")
		(net "CLK_100M_PCIE2_REFCLK_R_DP")
	)
	(segment
		(start 46.205648 -17.389602)
		(end 45.94225 -17.653)
		(width 0.1397)
		(layer "B.Cu")
		(net "CLK_100M_PCIE2_REFCLK_R_DP")
	)
	(segment
		(start 45.94225 -18.0086)
		(end 46.02099 -18.08734)
		(width 0.1397)
		(layer "B.Cu")
		(net "CLK_100M_PCIE2_REFCLK_R_DP")
	)
	(segment
		(start 47.541688 -17.389602)
		(end 46.205648 -17.389602)
		(width 0.1397)
		(layer "B.Cu")
		(net "CLK_100M_PCIE2_REFCLK_R_DP")
	)
	(segment
		(start 59.349894 -8.447024)
		(end 59.67857 -8.7757)
		(width 0.1397)
		(layer "F.Cu")
		(net "CLK_100M_PCIE2_REFCLK_DN")
	)
	(segment
		(start 59.34837 -10.04189)
		(end 59.34837 -10.666222)
		(width 0.1397)
		(layer "F.Cu")
		(net "CLK_100M_PCIE2_REFCLK_DN")
	)
	(segment
		(start 59.34837 -10.666222)
		(end 59.078114 -10.936478)
		(width 0.1397)
		(layer "F.Cu")
		(net "CLK_100M_PCIE2_REFCLK_DN")
	)
	(segment
		(start 59.67857 -8.7757)
		(end 59.67857 -9.71169)
		(width 0.1397)
		(layer "F.Cu")
		(net "CLK_100M_PCIE2_REFCLK_DN")
	)
	(segment
		(start 59.349894 -6.195568)
		(end 59.349894 -8.447024)
		(width 0.1397)
		(layer "F.Cu")
		(net "CLK_100M_PCIE2_REFCLK_DN")
	)
	(segment
		(start 59.67857 -9.71169)
		(end 59.34837 -10.04189)
		(width 0.1397)
		(layer "F.Cu")
		(net "CLK_100M_PCIE2_REFCLK_DN")
	)
	(via
		(at 59.078114 -10.936478)
		(size 0.508)
		(drill 0.254)
		(layers "F.Cu" "B.Cu")
		(net "CLK_100M_PCIE2_REFCLK_DN")
	)
	(via
		(at 47.46371 -13.7922)
		(size 0.508)
		(drill 0.254)
		(layers "F.Cu" "B.Cu")
		(net "CLK_100M_PCIE2_REFCLK_DN")
	)
	(segment
		(start 47.59325 -14.30655)
		(end 47.59325 -13.92174)
		(width 0.1397)
		(layer "B.Cu")
		(net "CLK_100M_PCIE2_REFCLK_DN")
	)
	(segment
		(start 47.2948 -14.605)
		(end 47.59325 -14.30655)
		(width 0.1397)
		(layer "B.Cu")
		(net "CLK_100M_PCIE2_REFCLK_DN")
	)
	(segment
		(start 47.371 -14.6812)
		(end 47.2948 -14.605)
		(width 0.1397)
		(layer "B.Cu")
		(net "CLK_100M_PCIE2_REFCLK_DN")
	)
	(segment
		(start 47.371 -15.4686)
		(end 47.371 -14.6812)
		(width 0.1397)
		(layer "B.Cu")
		(net "CLK_100M_PCIE2_REFCLK_DN")
	)
	(segment
		(start 47.59325 -13.92174)
		(end 47.46371 -13.7922)
		(width 0.1397)
		(layer "B.Cu")
		(net "CLK_100M_PCIE2_REFCLK_DN")
	)
	(segment
		(start 47.46371 -13.7922)
		(end 47.7012 -13.55471)
		(width 0.1143)
		(layer "In2.Cu")
		(net "CLK_100M_PCIE2_REFCLK_DN")
	)
	(segment
		(start 48.707294 -11.6332)
		(end 59.2328 -11.6332)
		(width 0.1143)
		(layer "In2.Cu")
		(net "CLK_100M_PCIE2_REFCLK_DN")
	)
	(segment
		(start 59.372754 -11.493246)
		(end 59.372754 -11.231118)
		(width 0.1143)
		(layer "In2.Cu")
		(net "CLK_100M_PCIE2_REFCLK_DN")
	)
	(segment
		(start 59.372754 -11.231118)
		(end 59.078114 -10.936478)
		(width 0.1143)
		(layer "In2.Cu")
		(net "CLK_100M_PCIE2_REFCLK_DN")
	)
	(segment
		(start 59.2328 -11.6332)
		(end 59.372754 -11.493246)
		(width 0.1143)
		(layer "In2.Cu")
		(net "CLK_100M_PCIE2_REFCLK_DN")
	)
	(segment
		(start 47.7012 -13.55471)
		(end 47.7012 -12.639294)
		(width 0.1143)
		(layer "In2.Cu")
		(net "CLK_100M_PCIE2_REFCLK_DN")
	)
	(segment
		(start 47.7012 -12.639294)
		(end 48.707294 -11.6332)
		(width 0.1143)
		(layer "In2.Cu")
		(net "CLK_100M_PCIE2_REFCLK_DN")
	)
	(segment
		(start 63.11265 -18.937224)
		(end 63.911226 -19.7358)
		(width 0.1143)
		(layer "F.Cu")
		(net "PMU_BUF_PLTRST#")
	)
	(segment
		(start 61.48705 -15.64005)
		(end 59.584082 -15.64005)
		(width 0.1143)
		(layer "F.Cu")
		(net "PMU_BUF_PLTRST#")
	)
	(segment
		(start 63.11265 -18.19275)
		(end 63.11265 -18.937224)
		(width 0.1143)
		(layer "F.Cu")
		(net "PMU_BUF_PLTRST#")
	)
	(segment
		(start 74.69251 -16.32585)
		(end 67.764406 -16.32585)
		(width 0.1143)
		(layer "F.Cu")
		(net "PMU_BUF_PLTRST#")
	)
	(segment
		(start 71.0565 -19.939)
		(end 70.505828 -19.939)
		(width 0.1143)
		(layer "F.Cu")
		(net "PMU_BUF_PLTRST#")
	)
	(segment
		(start 72.7075 -19.939)
		(end 71.0565 -19.939)
		(width 0.1143)
		(layer "F.Cu")
		(net "PMU_BUF_PLTRST#")
	)
	(segment
		(start 58.42 -16.804132)
		(end 58.42 -16.8656)
		(width 0.1143)
		(layer "F.Cu")
		(net "PMU_BUF_PLTRST#")
	)
	(segment
		(start 77.1652 -14.097)
		(end 76.92136 -14.097)
		(width 0.1143)
		(layer "F.Cu")
		(net "PMU_BUF_PLTRST#")
	)
	(segment
		(start 59.584082 -15.64005)
		(end 58.42 -16.804132)
		(width 0.1143)
		(layer "F.Cu")
		(net "PMU_BUF_PLTRST#")
	)
	(segment
		(start 77.5462 -13.716)
		(end 77.1652 -14.097)
		(width 0.1143)
		(layer "F.Cu")
		(net "PMU_BUF_PLTRST#")
	)
	(segment
		(start 76.92136 -14.097)
		(end 74.69251 -16.32585)
		(width 0.1143)
		(layer "F.Cu")
		(net "PMU_BUF_PLTRST#")
	)
	(segment
		(start 63.23965 -18.06575)
		(end 63.11265 -18.19275)
		(width 0.1143)
		(layer "F.Cu")
		(net "PMU_BUF_PLTRST#")
	)
	(segment
		(start 70.023228 -19.4564)
		(end 68.7197 -19.4564)
		(width 0.1143)
		(layer "F.Cu")
		(net "PMU_BUF_PLTRST#")
	)
	(segment
		(start 66.024506 -18.06575)
		(end 63.23965 -18.06575)
		(width 0.1143)
		(layer "F.Cu")
		(net "PMU_BUF_PLTRST#")
	)
	(segment
		(start 63.911226 -19.7358)
		(end 65.202562 -19.7358)
		(width 0.1143)
		(layer "F.Cu")
		(net "PMU_BUF_PLTRST#")
	)
	(segment
		(start 70.505828 -19.939)
		(end 70.023228 -19.4564)
		(width 0.1143)
		(layer "F.Cu")
		(net "PMU_BUF_PLTRST#")
	)
	(segment
		(start 68.54825 -19.62785)
		(end 68.6181 -19.558)
		(width 0.1143)
		(layer "F.Cu")
		(net "PMU_BUF_PLTRST#")
	)
	(segment
		(start 65.202562 -19.7358)
		(end 65.310512 -19.62785)
		(width 0.1143)
		(layer "F.Cu")
		(net "PMU_BUF_PLTRST#")
	)
	(segment
		(start 68.7197 -19.4564)
		(end 68.6181 -19.558)
		(width 0.1143)
		(layer "F.Cu")
		(net "PMU_BUF_PLTRST#")
	)
	(segment
		(start 63.23965 -17.39265)
		(end 61.48705 -15.64005)
		(width 0.1143)
		(layer "F.Cu")
		(net "PMU_BUF_PLTRST#")
	)
	(segment
		(start 65.310512 -19.62785)
		(end 68.54825 -19.62785)
		(width 0.1143)
		(layer "F.Cu")
		(net "PMU_BUF_PLTRST#")
	)
	(segment
		(start 63.23965 -18.06575)
		(end 63.23965 -17.39265)
		(width 0.1143)
		(layer "F.Cu")
		(net "PMU_BUF_PLTRST#")
	)
	(segment
		(start 67.764406 -16.32585)
		(end 66.024506 -18.06575)
		(width 0.1143)
		(layer "F.Cu")
		(net "PMU_BUF_PLTRST#")
	)
	(via
		(at 58.42 -16.8656)
		(size 0.508)
		(drill 0.254)
		(layers "F.Cu" "B.Cu")
		(net "PMU_BUF_PLTRST#")
	)
	(via
		(at 68.6181 -19.558)
		(size 0.7112)
		(drill 0.3556)
		(layers "F.Cu" "B.Cu")
		(net "PMU_BUF_PLTRST#")
	)
	(segment
		(start 57.56656 -15.19936)
		(end 57.6072 -15.24)
		(width 0.1143)
		(layer "B.Cu")
		(net "PMU_BUF_PLTRST#")
	)
	(segment
		(start 59.8678 -13.5636)
		(end 60.071 -13.7668)
		(width 0.1143)
		(layer "B.Cu")
		(net "PMU_BUF_PLTRST#")
	)
	(segment
		(start 60.833 -13.7668)
		(end 60.071 -13.7668)
		(width 0.1143)
		(layer "B.Cu")
		(net "PMU_BUF_PLTRST#")
	)
	(segment
		(start 57.56656 -14.26972)
		(end 57.56656 -15.19936)
		(width 0.1143)
		(layer "B.Cu")
		(net "PMU_BUF_PLTRST#")
	)
	(segment
		(start 57.912 -16.3576)
		(end 58.42 -16.8656)
		(width 0.1143)
		(layer "B.Cu")
		(net "PMU_BUF_PLTRST#")
	)
	(segment
		(start 58.0644 -13.5636)
		(end 59.8678 -13.5636)
		(width 0.1143)
		(layer "B.Cu")
		(net "PMU_BUF_PLTRST#")
	)
	(segment
		(start 57.56656 -14.26972)
		(end 57.56656 -14.06144)
		(width 0.1143)
		(layer "B.Cu")
		(net "PMU_BUF_PLTRST#")
	)
	(segment
		(start 57.6072 -15.24)
		(end 57.912 -15.5448)
		(width 0.1143)
		(layer "B.Cu")
		(net "PMU_BUF_PLTRST#")
	)
	(segment
		(start 57.912 -15.5448)
		(end 57.912 -16.3576)
		(width 0.1143)
		(layer "B.Cu")
		(net "PMU_BUF_PLTRST#")
	)
	(segment
		(start 57.56656 -14.06144)
		(end 58.0644 -13.5636)
		(width 0.1143)
		(layer "B.Cu")
		(net "PMU_BUF_PLTRST#")
	)
	(segment
		(start 71.4502 -18.288)
		(end 71.4502 -18.0848)
		(width 0.1143)
		(layer "F.Cu")
		(net "GF_CPU_TXD")
	)
	(segment
		(start 92.355416 -10.424668)
		(end 91.911932 -9.981184)
		(width 0.1143)
		(layer "F.Cu")
		(net "GF_CPU_TXD")
	)
	(segment
		(start 72.639936 -17.84985)
		(end 72.77735 -17.987264)
		(width 0.1143)
		(layer "F.Cu")
		(net "GF_CPU_TXD")
	)
	(segment
		(start 77.0636 -18.7198)
		(end 77.8256 -18.7198)
		(width 0.1143)
		(layer "F.Cu")
		(net "GF_CPU_TXD")
	)
	(segment
		(start 71.0565 -19.28876)
		(end 71.0565 -18.6817)
		(width 0.1143)
		(layer "F.Cu")
		(net "GF_CPU_TXD")
	)
	(segment
		(start 91.911932 -9.981184)
		(end 91.911932 -9.069578)
		(width 0.1143)
		(layer "F.Cu")
		(net "GF_CPU_TXD")
	)
	(segment
		(start 92.350082 -8.631428)
		(end 92.350082 -6.195568)
		(width 0.1143)
		(layer "F.Cu")
		(net "GF_CPU_TXD")
	)
	(segment
		(start 72.77735 -18.162524)
		(end 73.334626 -18.7198)
		(width 0.1143)
		(layer "F.Cu")
		(net "GF_CPU_TXD")
	)
	(segment
		(start 71.4502 -18.0848)
		(end 71.68515 -17.84985)
		(width 0.1143)
		(layer "F.Cu")
		(net "GF_CPU_TXD")
	)
	(segment
		(start 71.0565 -18.6817)
		(end 71.4502 -18.288)
		(width 0.1143)
		(layer "F.Cu")
		(net "GF_CPU_TXD")
	)
	(segment
		(start 91.911932 -9.069578)
		(end 92.350082 -8.631428)
		(width 0.1143)
		(layer "F.Cu")
		(net "GF_CPU_TXD")
	)
	(segment
		(start 71.68515 -17.84985)
		(end 72.639936 -17.84985)
		(width 0.1143)
		(layer "F.Cu")
		(net "GF_CPU_TXD")
	)
	(segment
		(start 73.334626 -18.7198)
		(end 77.0636 -18.7198)
		(width 0.1143)
		(layer "F.Cu")
		(net "GF_CPU_TXD")
	)
	(segment
		(start 77.8256 -18.7198)
		(end 79.3496 -20.2438)
		(width 0.1143)
		(layer "F.Cu")
		(net "GF_CPU_TXD")
	)
	(segment
		(start 72.77735 -17.987264)
		(end 72.77735 -18.162524)
		(width 0.1143)
		(layer "F.Cu")
		(net "GF_CPU_TXD")
	)
	(via
		(at 77.0636 -18.7198)
		(size 0.7112)
		(drill 0.3556)
		(layers "F.Cu" "B.Cu")
		(net "GF_CPU_TXD")
	)
	(via
		(at 92.355416 -10.424668)
		(size 0.508)
		(drill 0.254)
		(layers "F.Cu" "B.Cu")
		(net "GF_CPU_TXD")
	)
	(via
		(at 79.3496 -20.2438)
		(size 0.508)
		(drill 0.254)
		(layers "F.Cu" "B.Cu")
		(net "GF_CPU_TXD")
	)
	(segment
		(start 84.963 -14.732)
		(end 83.2231 -16.4719)
		(width 0.0889)
		(layer "In2.Cu")
		(net "GF_CPU_TXD")
	)
	(segment
		(start 79.5401 -20.0533)
		(end 79.3496 -20.2438)
		(width 0.0889)
		(layer "In2.Cu")
		(net "GF_CPU_TXD")
	)
	(segment
		(start 79.5401 -19.015456)
		(end 79.5401 -20.0533)
		(width 0.0889)
		(layer "In2.Cu")
		(net "GF_CPU_TXD")
	)
	(segment
		(start 90.235278 -12.331446)
		(end 87.83447 -14.732)
		(width 0.0889)
		(layer "In2.Cu")
		(net "GF_CPU_TXD")
	)
	(segment
		(start 82.083656 -16.4719)
		(end 79.5401 -19.015456)
		(width 0.0889)
		(layer "In2.Cu")
		(net "GF_CPU_TXD")
	)
	(segment
		(start 90.959178 -11.6078)
		(end 90.235278 -12.331446)
		(width 0.0889)
		(layer "In2.Cu")
		(net "GF_CPU_TXD")
	)
	(segment
		(start 87.83447 -14.732)
		(end 84.963 -14.732)
		(width 0.0889)
		(layer "In2.Cu")
		(net "GF_CPU_TXD")
	)
	(segment
		(start 92.355416 -10.424668)
		(end 92.14231 -10.424668)
		(width 0.0889)
		(layer "In2.Cu")
		(net "GF_CPU_TXD")
	)
	(segment
		(start 83.2231 -16.4719)
		(end 82.083656 -16.4719)
		(width 0.0889)
		(layer "In2.Cu")
		(net "GF_CPU_TXD")
	)
	(segment
		(start 92.14231 -10.424668)
		(end 90.959178 -11.6078)
		(width 0.0889)
		(layer "In2.Cu")
		(net "GF_CPU_TXD")
	)
	(segment
		(start 92.6084 -11.251692)
		(end 92.455492 -11.251692)
		(width 0.1143)
		(layer "F.Cu")
		(net "GF_CPU_RXD")
	)
	(segment
		(start 91.350084 -8.901684)
		(end 91.350084 -6.195568)
		(width 0.1143)
		(layer "F.Cu")
		(net "GF_CPU_RXD")
	)
	(segment
		(start 91.670632 -10.466832)
		(end 91.670632 -9.222232)
		(width 0.1143)
		(layer "F.Cu")
		(net "GF_CPU_RXD")
	)
	(segment
		(start 72.7075 -20.58924)
		(end 73.08596 -20.58924)
		(width 0.1143)
		(layer "F.Cu")
		(net "GF_CPU_RXD")
	)
	(segment
		(start 75.17765 -20.44065)
		(end 77.1906 -20.44065)
		(width 0.1143)
		(layer "F.Cu")
		(net "GF_CPU_RXD")
	)
	(segment
		(start 74.6252 -19.8882)
		(end 75.17765 -20.44065)
		(width 0.1143)
		(layer "F.Cu")
		(net "GF_CPU_RXD")
	)
	(segment
		(start 73.08596 -20.58924)
		(end 73.787 -19.8882)
		(width 0.1143)
		(layer "F.Cu")
		(net "GF_CPU_RXD")
	)
	(segment
		(start 78.17485 -20.44065)
		(end 77.1906 -20.44065)
		(width 0.1143)
		(layer "F.Cu")
		(net "GF_CPU_RXD")
	)
	(segment
		(start 73.787 -19.8882)
		(end 74.6252 -19.8882)
		(width 0.1143)
		(layer "F.Cu")
		(net "GF_CPU_RXD")
	)
	(segment
		(start 78.5876 -20.8534)
		(end 78.17485 -20.44065)
		(width 0.1143)
		(layer "F.Cu")
		(net "GF_CPU_RXD")
	)
	(segment
		(start 92.455492 -11.251692)
		(end 91.670632 -10.466832)
		(width 0.1143)
		(layer "F.Cu")
		(net "GF_CPU_RXD")
	)
	(segment
		(start 91.670632 -9.222232)
		(end 91.350084 -8.901684)
		(width 0.1143)
		(layer "F.Cu")
		(net "GF_CPU_RXD")
	)
	(via
		(at 92.6084 -11.251692)
		(size 0.508)
		(drill 0.254)
		(layers "F.Cu" "B.Cu")
		(net "GF_CPU_RXD")
	)
	(via
		(at 78.5876 -20.8534)
		(size 0.508)
		(drill 0.254)
		(layers "F.Cu" "B.Cu")
		(net "GF_CPU_RXD")
	)
	(via
		(at 77.1906 -20.44065)
		(size 0.7112)
		(drill 0.3556)
		(layers "F.Cu" "B.Cu")
		(net "GF_CPU_RXD")
	)
	(segment
		(start 83.386422 -16.8656)
		(end 85.113622 -15.1384)
		(width 0.0889)
		(layer "In2.Cu")
		(net "GF_CPU_RXD")
	)
	(segment
		(start 82.959956 -16.8656)
		(end 83.386422 -16.8656)
		(width 0.0889)
		(layer "In2.Cu")
		(net "GF_CPU_RXD")
	)
	(segment
		(start 81.689956 -18.566638)
		(end 81.689956 -18.1356)
		(width 0.0889)
		(layer "In2.Cu")
		(net "GF_CPU_RXD")
	)
	(segment
		(start 78.5876 -20.8534)
		(end 78.6384 -20.9042)
		(width 0.0889)
		(layer "In2.Cu")
		(net "GF_CPU_RXD")
	)
	(segment
		(start 81.689956 -18.1356)
		(end 82.959956 -16.8656)
		(width 0.0889)
		(layer "In2.Cu")
		(net "GF_CPU_RXD")
	)
	(segment
		(start 87.9856 -15.1384)
		(end 91.872308 -11.251692)
		(width 0.0889)
		(layer "In2.Cu")
		(net "GF_CPU_RXD")
	)
	(segment
		(start 78.6384 -20.9042)
		(end 79.352394 -20.9042)
		(width 0.0889)
		(layer "In2.Cu")
		(net "GF_CPU_RXD")
	)
	(segment
		(start 91.872308 -11.251692)
		(end 92.6084 -11.251692)
		(width 0.0889)
		(layer "In2.Cu")
		(net "GF_CPU_RXD")
	)
	(segment
		(start 79.352394 -20.9042)
		(end 81.689956 -18.566638)
		(width 0.0889)
		(layer "In2.Cu")
		(net "GF_CPU_RXD")
	)
	(segment
		(start 85.113622 -15.1384)
		(end 87.9856 -15.1384)
		(width 0.0889)
		(layer "In2.Cu")
		(net "GF_CPU_RXD")
	)
	(segment
		(start 153.3652 -27.29357)
		(end 154.146504 -27.29357)
		(width 0.1143)
		(layer "F.Cu")
		(net "TP_FPGA_P112")
	)
	(segment
		(start 154.146504 -27.29357)
		(end 157.48 -23.960074)
		(width 0.1143)
		(layer "F.Cu")
		(net "TP_FPGA_P112")
	)
	(segment
		(start 157.48 -23.960074)
		(end 157.48 -23.876)
		(width 0.1143)
		(layer "F.Cu")
		(net "TP_FPGA_P112")
	)
	(segment
		(start 153.3652 -27.79395)
		(end 153.9875 -27.79395)
		(width 0.1143)
		(layer "F.Cu")
		(net "TP_FPGA_P113")
	)
	(segment
		(start 156.00045 -25.781)
		(end 157.48 -25.781)
		(width 0.1143)
		(layer "F.Cu")
		(net "TP_FPGA_P113")
	)
	(segment
		(start 153.9875 -27.79395)
		(end 156.00045 -25.781)
		(width 0.1143)
		(layer "F.Cu")
		(net "TP_FPGA_P113")
	)
	(segment
		(start 155.963112 -24.735536)
		(end 155.963112 -20.947888)
		(width 0.1143)
		(layer "F.Cu")
		(net "TP_FPGA_P110")
	)
	(segment
		(start 154.404568 -26.29408)
		(end 155.963112 -24.735536)
		(width 0.1143)
		(layer "F.Cu")
		(net "TP_FPGA_P110")
	)
	(segment
		(start 155.963112 -20.947888)
		(end 156.718 -20.193)
		(width 0.1143)
		(layer "F.Cu")
		(net "TP_FPGA_P110")
	)
	(segment
		(start 153.3652 -26.29408)
		(end 154.404568 -26.29408)
		(width 0.1143)
		(layer "F.Cu")
		(net "TP_FPGA_P110")
	)
	(segment
		(start 153.3652 -26.79446)
		(end 154.245564 -26.79446)
		(width 0.1143)
		(layer "F.Cu")
		(net "TP_FPGA_P111")
	)
	(segment
		(start 154.245564 -26.79446)
		(end 156.718 -24.322024)
		(width 0.1143)
		(layer "F.Cu")
		(net "TP_FPGA_P111")
	)
	(segment
		(start 156.718 -24.322024)
		(end 156.718 -22.098)
		(width 0.1143)
		(layer "F.Cu")
		(net "TP_FPGA_P111")
	)
	(segment
		(start 139.7 -23.0632)
		(end 139.7 -21.717)
		(width 0.1143)
		(layer "F.Cu")
		(net "TP_FPGA_P85")
	)
	(segment
		(start 139.49807 -23.9268)
		(end 139.49807 -23.26513)
		(width 0.1143)
		(layer "F.Cu")
		(net "TP_FPGA_P85")
	)
	(segment
		(start 139.49807 -23.26513)
		(end 139.7 -23.0632)
		(width 0.1143)
		(layer "F.Cu")
		(net "TP_FPGA_P85")
	)
	(segment
		(start 138.99769 -23.9268)
		(end 138.99769 -23.379176)
		(width 0.1143)
		(layer "F.Cu")
		(net "TP_FPGA_P84")
	)
	(segment
		(start 138.176 -21.116544)
		(end 138.176 -20.574)
		(width 0.1143)
		(layer "F.Cu")
		(net "TP_FPGA_P84")
	)
	(segment
		(start 138.99769 -23.379176)
		(end 139.210796 -23.16607)
		(width 0.1143)
		(layer "F.Cu")
		(net "TP_FPGA_P84")
	)
	(segment
		(start 139.210796 -23.16607)
		(end 139.210796 -22.15134)
		(width 0.1143)
		(layer "F.Cu")
		(net "TP_FPGA_P84")
	)
	(segment
		(start 139.210796 -22.15134)
		(end 138.176 -21.116544)
		(width 0.1143)
		(layer "F.Cu")
		(net "TP_FPGA_P84")
	)
	(segment
		(start 146.05 -18.796)
		(end 145.923 -18.796)
		(width 0.1143)
		(layer "F.Cu")
		(net "TP_FPGA_P100")
	)
	(segment
		(start 147.4978 -20.2438)
		(end 146.05 -18.796)
		(width 0.1143)
		(layer "F.Cu")
		(net "TP_FPGA_P100")
	)
	(segment
		(start 147.4978 -23.9268)
		(end 147.4978 -20.2438)
		(width 0.1143)
		(layer "F.Cu")
		(net "TP_FPGA_P100")
	)
	(segment
		(start 78.867 -11.6078)
		(end 80.645 -11.6078)
		(width 0.1143)
		(layer "F.Cu")
		(net "PCIE_GF_I2C_R_ALERT#")
	)
	(segment
		(start 81.3816 -12.3444)
		(end 80.645 -11.6078)
		(width 0.1143)
		(layer "F.Cu")
		(net "PCIE_GF_I2C_R_ALERT#")
	)
	(segment
		(start 78.4098 -12.065)
		(end 78.867 -11.6078)
		(width 0.1143)
		(layer "F.Cu")
		(net "PCIE_GF_I2C_R_ALERT#")
	)
	(via
		(at 81.3816 -12.3444)
		(size 0.508)
		(drill 0.254)
		(layers "F.Cu" "B.Cu")
		(net "PCIE_GF_I2C_R_ALERT#")
	)
	(via
		(at 80.645 -11.6078)
		(size 0.7112)
		(drill 0.3556)
		(layers "F.Cu" "B.Cu")
		(net "PCIE_GF_I2C_R_ALERT#")
	)
	(segment
		(start 85.349842 -5.814568)
		(end 85.349842 -10.033)
		(width 0.1143)
		(layer "B.Cu")
		(net "PCIE_GF_I2C_R_ALERT#")
	)
	(segment
		(start 85.05825 -10.67435)
		(end 84.8106 -10.922)
		(width 0.1143)
		(layer "B.Cu")
		(net "PCIE_GF_I2C_R_ALERT#")
	)
	(segment
		(start 85.349842 -10.033)
		(end 85.05825 -10.324592)
		(width 0.1143)
		(layer "B.Cu")
		(net "PCIE_GF_I2C_R_ALERT#")
	)
	(segment
		(start 85.05825 -10.324592)
		(end 85.05825 -10.67435)
		(width 0.1143)
		(layer "B.Cu")
		(net "PCIE_GF_I2C_R_ALERT#")
	)
	(segment
		(start 82.804 -10.922)
		(end 81.3816 -12.3444)
		(width 0.1143)
		(layer "B.Cu")
		(net "PCIE_GF_I2C_R_ALERT#")
	)
	(segment
		(start 84.8106 -10.922)
		(end 82.804 -10.922)
		(width 0.1143)
		(layer "B.Cu")
		(net "PCIE_GF_I2C_R_ALERT#")
	)
	(segment
		(start 36.048188 -11.832336)
		(end 36.496752 -12.2809)
		(width 0.1143)
		(layer "F.Cu")
		(net "PICE_GF_I2C_SW_EN")
	)
	(segment
		(start 75.364086 -12.51204)
		(end 75.82916 -12.51204)
		(width 0.1143)
		(layer "F.Cu")
		(net "PICE_GF_I2C_SW_EN")
	)
	(segment
		(start 31.75 -12.5095)
		(end 31.75 -12.192)
		(width 0.1143)
		(layer "F.Cu")
		(net "PICE_GF_I2C_SW_EN")
	)
	(segment
		(start 75.82916 -12.51204)
		(end 76.4286 -11.9126)
		(width 0.1143)
		(layer "F.Cu")
		(net "PICE_GF_I2C_SW_EN")
	)
	(segment
		(start 31.75 -15.3162)
		(end 31.75 -14.1605)
		(width 0.1143)
		(layer "F.Cu")
		(net "PICE_GF_I2C_SW_EN")
	)
	(segment
		(start 35.566604 -11.832336)
		(end 36.048188 -11.832336)
		(width 0.1143)
		(layer "F.Cu")
		(net "PICE_GF_I2C_SW_EN")
	)
	(segment
		(start 31.75 -12.192)
		(end 32.09925 -11.84275)
		(width 0.1143)
		(layer "F.Cu")
		(net "PICE_GF_I2C_SW_EN")
	)
	(segment
		(start 35.55619 -11.84275)
		(end 35.566604 -11.832336)
		(width 0.1143)
		(layer "F.Cu")
		(net "PICE_GF_I2C_SW_EN")
	)
	(segment
		(start 31.75 -14.1605)
		(end 31.75 -12.5095)
		(width 0.1143)
		(layer "F.Cu")
		(net "PICE_GF_I2C_SW_EN")
	)
	(segment
		(start 32.09925 -11.84275)
		(end 35.55619 -11.84275)
		(width 0.1143)
		(layer "F.Cu")
		(net "PICE_GF_I2C_SW_EN")
	)
	(via
		(at 76.4286 -11.9126)
		(size 0.508)
		(drill 0.254)
		(layers "F.Cu" "B.Cu")
		(net "PICE_GF_I2C_SW_EN")
	)
	(via
		(at 36.496752 -12.2809)
		(size 0.508)
		(drill 0.254)
		(layers "F.Cu" "B.Cu")
		(net "PICE_GF_I2C_SW_EN")
	)
	(via
		(at 35.566604 -11.832336)
		(size 0.7112)
		(drill 0.3556)
		(layers "F.Cu" "B.Cu")
		(net "PICE_GF_I2C_SW_EN")
	)
	(segment
		(start 56.266842 -10.7696)
		(end 55.499 -10.7696)
		(width 0.0889)
		(layer "In7.Cu")
		(net "PICE_GF_I2C_SW_EN")
	)
	(segment
		(start 76.4286 -11.9126)
		(end 75.653646 -11.137646)
		(width 0.0889)
		(layer "In7.Cu")
		(net "PICE_GF_I2C_SW_EN")
	)
	(segment
		(start 55.118 -11.1506)
		(end 37.627052 -11.1506)
		(width 0.0889)
		(layer "In7.Cu")
		(net "PICE_GF_I2C_SW_EN")
	)
	(segment
		(start 37.627052 -11.1506)
		(end 36.496752 -12.2809)
		(width 0.0889)
		(layer "In7.Cu")
		(net "PICE_GF_I2C_SW_EN")
	)
	(segment
		(start 75.501246 -11.137646)
		(end 72.8726 -8.509)
		(width 0.0889)
		(layer "In7.Cu")
		(net "PICE_GF_I2C_SW_EN")
	)
	(segment
		(start 72.8726 -8.509)
		(end 58.527442 -8.509)
		(width 0.0889)
		(layer "In7.Cu")
		(net "PICE_GF_I2C_SW_EN")
	)
	(segment
		(start 75.653646 -11.137646)
		(end 75.501246 -11.137646)
		(width 0.0889)
		(layer "In7.Cu")
		(net "PICE_GF_I2C_SW_EN")
	)
	(segment
		(start 55.499 -10.7696)
		(end 55.118 -11.1506)
		(width 0.0889)
		(layer "In7.Cu")
		(net "PICE_GF_I2C_SW_EN")
	)
	(segment
		(start 58.527442 -8.509)
		(end 56.266842 -10.7696)
		(width 0.0889)
		(layer "In7.Cu")
		(net "PICE_GF_I2C_SW_EN")
	)
	(segment
		(start 77.5462 -12.827)
		(end 77.5462 -12.065)
		(width 0.1143)
		(layer "F.Cu")
		(net "PCIE_GF_I2C_ALERT#")
	)
	(segment
		(start 71.67245 -14.284198)
		(end 71.67245 -13.724636)
		(width 0.1143)
		(layer "F.Cu")
		(net "PCIE_GF_I2C_ALERT#")
	)
	(segment
		(start 72.971914 -13.208)
		(end 72.4154 -13.208)
		(width 0.1143)
		(layer "F.Cu")
		(net "PCIE_GF_I2C_ALERT#")
	)
	(segment
		(start 72.413114 -13.210286)
		(end 72.202548 -13.210286)
		(width 0.1143)
		(layer "F.Cu")
		(net "PCIE_GF_I2C_ALERT#")
	)
	(segment
		(start 77.052932 -12.065)
		(end 75.655932 -13.462)
		(width 0.1143)
		(layer "F.Cu")
		(net "PCIE_GF_I2C_ALERT#")
	)
	(segment
		(start 71.6788 -14.986)
		(end 71.6788 -14.290548)
		(width 0.1143)
		(layer "F.Cu")
		(net "PCIE_GF_I2C_ALERT#")
	)
	(segment
		(start 72.1868 -13.210286)
		(end 72.202548 -13.210286)
		(width 0.1143)
		(layer "F.Cu")
		(net "PCIE_GF_I2C_ALERT#")
	)
	(segment
		(start 73.225914 -13.462)
		(end 72.971914 -13.208)
		(width 0.1143)
		(layer "F.Cu")
		(net "PCIE_GF_I2C_ALERT#")
	)
	(segment
		(start 71.67245 -13.724636)
		(end 72.1868 -13.210286)
		(width 0.1143)
		(layer "F.Cu")
		(net "PCIE_GF_I2C_ALERT#")
	)
	(segment
		(start 77.5462 -12.065)
		(end 77.052932 -12.065)
		(width 0.1143)
		(layer "F.Cu")
		(net "PCIE_GF_I2C_ALERT#")
	)
	(segment
		(start 71.6788 -14.290548)
		(end 71.67245 -14.284198)
		(width 0.1143)
		(layer "F.Cu")
		(net "PCIE_GF_I2C_ALERT#")
	)
	(segment
		(start 75.655932 -13.462)
		(end 73.225914 -13.462)
		(width 0.1143)
		(layer "F.Cu")
		(net "PCIE_GF_I2C_ALERT#")
	)
	(segment
		(start 72.4154 -13.208)
		(end 72.413114 -13.210286)
		(width 0.1143)
		(layer "F.Cu")
		(net "PCIE_GF_I2C_ALERT#")
	)
	(via
		(at 72.202548 -13.210286)
		(size 0.7112)
		(drill 0.3556)
		(layers "F.Cu" "B.Cu")
		(net "PCIE_GF_I2C_ALERT#")
	)
	(segment
		(start 33.2613 -12.5095)
		(end 32.40024 -12.5095)
		(width 0.1143)
		(layer "F.Cu")
		(net "PCIE_GF_I2C_DATA")
	)
	(segment
		(start 33.401 -12.6492)
		(end 33.2613 -12.5095)
		(width 0.1143)
		(layer "F.Cu")
		(net "PCIE_GF_I2C_DATA")
	)
	(segment
		(start 34.29 -12.6492)
		(end 33.401 -12.6492)
		(width 0.1143)
		(layer "F.Cu")
		(net "PCIE_GF_I2C_DATA")
	)
	(segment
		(start 34.29 -12.6492)
		(end 35.052 -12.6492)
		(width 0.1143)
		(layer "F.Cu")
		(net "PCIE_GF_I2C_DATA")
	)
	(via
		(at 35.567874 -12.018518)
		(size 0.7112)
		(drill 0.3556)
		(layers "F.Cu" "B.Cu")
		(net "PCIE_GF_I2C_DATA")
	)
	(via
		(at 93.35008 -9.561068)
		(size 0.508)
		(drill 0.254)
		(layers "F.Cu" "B.Cu")
		(net "PCIE_GF_I2C_DATA")
	)
	(via
		(at 35.052 -12.6492)
		(size 0.508)
		(drill 0.254)
		(layers "F.Cu" "B.Cu")
		(net "PCIE_GF_I2C_DATA")
	)
	(segment
		(start 35.567874 -12.133326)
		(end 35.052 -12.6492)
		(width 0.1143)
		(layer "B.Cu")
		(net "PCIE_GF_I2C_DATA")
	)
	(segment
		(start 93.35008 -5.814568)
		(end 93.35008 -9.561068)
		(width 0.1143)
		(layer "B.Cu")
		(net "PCIE_GF_I2C_DATA")
	)
	(segment
		(start 35.567874 -12.018518)
		(end 35.567874 -12.133326)
		(width 0.1143)
		(layer "B.Cu")
		(net "PCIE_GF_I2C_DATA")
	)
	(segment
		(start 90.245184 -9.90346)
		(end 90.245184 -9.399524)
		(width 0.0889)
		(layer "In7.Cu")
		(net "PCIE_GF_I2C_DATA")
	)
	(segment
		(start 81.5086 -11.60145)
		(end 84.22005 -11.60145)
		(width 0.0889)
		(layer "In7.Cu")
		(net "PCIE_GF_I2C_DATA")
	)
	(segment
		(start 90.50909 -9.135618)
		(end 92.92463 -9.135618)
		(width 0.0889)
		(layer "In7.Cu")
		(net "PCIE_GF_I2C_DATA")
	)
	(segment
		(start 77.8637 -9.765538)
		(end 78.981554 -10.883392)
		(width 0.0889)
		(layer "In7.Cu")
		(net "PCIE_GF_I2C_DATA")
	)
	(segment
		(start 87.77224 -12.376404)
		(end 90.245184 -9.90346)
		(width 0.0889)
		(layer "In7.Cu")
		(net "PCIE_GF_I2C_DATA")
	)
	(segment
		(start 78.981554 -10.883392)
		(end 80.790542 -10.883392)
		(width 0.0889)
		(layer "In7.Cu")
		(net "PCIE_GF_I2C_DATA")
	)
	(segment
		(start 84.995004 -12.376404)
		(end 87.77224 -12.376404)
		(width 0.0889)
		(layer "In7.Cu")
		(net "PCIE_GF_I2C_DATA")
	)
	(segment
		(start 84.22005 -11.60145)
		(end 84.995004 -12.376404)
		(width 0.0889)
		(layer "In7.Cu")
		(net "PCIE_GF_I2C_DATA")
	)
	(segment
		(start 77.8637 -9.045956)
		(end 77.8637 -9.765538)
		(width 0.0889)
		(layer "In7.Cu")
		(net "PCIE_GF_I2C_DATA")
	)
	(segment
		(start 92.92463 -9.135618)
		(end 93.35008 -9.561068)
		(width 0.0889)
		(layer "In7.Cu")
		(net "PCIE_GF_I2C_DATA")
	)
	(segment
		(start 80.790542 -10.883392)
		(end 81.5086 -11.60145)
		(width 0.0889)
		(layer "In7.Cu")
		(net "PCIE_GF_I2C_DATA")
	)
	(segment
		(start 35.052 -12.42314)
		(end 39.47414 -8.001)
		(width 0.0889)
		(layer "In7.Cu")
		(net "PCIE_GF_I2C_DATA")
	)
	(segment
		(start 39.47414 -8.001)
		(end 76.818744 -8.001)
		(width 0.0889)
		(layer "In7.Cu")
		(net "PCIE_GF_I2C_DATA")
	)
	(segment
		(start 90.245184 -9.399524)
		(end 90.50909 -9.135618)
		(width 0.0889)
		(layer "In7.Cu")
		(net "PCIE_GF_I2C_DATA")
	)
	(segment
		(start 76.818744 -8.001)
		(end 77.8637 -9.045956)
		(width 0.0889)
		(layer "In7.Cu")
		(net "PCIE_GF_I2C_DATA")
	)
	(segment
		(start 35.052 -12.6492)
		(end 35.052 -12.42314)
		(width 0.0889)
		(layer "In7.Cu")
		(net "PCIE_GF_I2C_DATA")
	)
	(segment
		(start 29.862272 -11.58494)
		(end 29.486606 -11.960606)
		(width 0.1143)
		(layer "F.Cu")
		(net "PCIE_GF_I2C_CLK")
	)
	(segment
		(start 30.513528 -14.1605)
		(end 31.09976 -14.1605)
		(width 0.1143)
		(layer "F.Cu")
		(net "PCIE_GF_I2C_CLK")
	)
	(segment
		(start 28.829 -12.618212)
		(end 29.486606 -11.960606)
		(width 0.1143)
		(layer "F.Cu")
		(net "PCIE_GF_I2C_CLK")
	)
	(segment
		(start 29.6926 -13.7668)
		(end 29.972 -13.7668)
		(width 0.1143)
		(layer "F.Cu")
		(net "PCIE_GF_I2C_CLK")
	)
	(segment
		(start 28.829 -12.9032)
		(end 29.6926 -13.7668)
		(width 0.1143)
		(layer "F.Cu")
		(net "PCIE_GF_I2C_CLK")
	)
	(segment
		(start 30.5308 -11.58494)
		(end 29.862272 -11.58494)
		(width 0.1143)
		(layer "F.Cu")
		(net "PCIE_GF_I2C_CLK")
	)
	(segment
		(start 28.829 -12.9032)
		(end 28.829 -12.618212)
		(width 0.1143)
		(layer "F.Cu")
		(net "PCIE_GF_I2C_CLK")
	)
	(segment
		(start 29.972 -13.7668)
		(end 30.119828 -13.7668)
		(width 0.1143)
		(layer "F.Cu")
		(net "PCIE_GF_I2C_CLK")
	)
	(segment
		(start 30.119828 -13.7668)
		(end 30.513528 -14.1605)
		(width 0.1143)
		(layer "F.Cu")
		(net "PCIE_GF_I2C_CLK")
	)
	(via
		(at 30.5308 -11.58494)
		(size 0.508)
		(drill 0.254)
		(layers "F.Cu" "B.Cu")
		(net "PCIE_GF_I2C_CLK")
	)
	(via
		(at 29.486606 -11.960606)
		(size 0.7112)
		(drill 0.3556)
		(layers "F.Cu" "B.Cu")
		(net "PCIE_GF_I2C_CLK")
	)
	(via
		(at 94.350078 -9.561068)
		(size 0.508)
		(drill 0.254)
		(layers "F.Cu" "B.Cu")
		(net "PCIE_GF_I2C_CLK")
	)
	(segment
		(start 94.350078 -5.814568)
		(end 94.350078 -9.561068)
		(width 0.1143)
		(layer "B.Cu")
		(net "PCIE_GF_I2C_CLK")
	)
	(segment
		(start 32.681418 -10.7696)
		(end 35.704018 -7.747)
		(width 0.0889)
		(layer "In7.Cu")
		(net "PCIE_GF_I2C_CLK")
	)
	(segment
		(start 83.274408 -11.137646)
		(end 84.420964 -11.137646)
		(width 0.0889)
		(layer "In7.Cu")
		(net "PCIE_GF_I2C_CLK")
	)
	(segment
		(start 30.5308 -11.58494)
		(end 31.34614 -10.7696)
		(width 0.0889)
		(layer "In7.Cu")
		(net "PCIE_GF_I2C_CLK")
	)
	(segment
		(start 85.189822 -11.906504)
		(end 87.022686 -11.906504)
		(width 0.0889)
		(layer "In7.Cu")
		(net "PCIE_GF_I2C_CLK")
	)
	(segment
		(start 31.34614 -10.7696)
		(end 32.681418 -10.7696)
		(width 0.0889)
		(layer "In7.Cu")
		(net "PCIE_GF_I2C_CLK")
	)
	(segment
		(start 93.17101 -8.382)
		(end 94.350078 -9.561068)
		(width 0.0889)
		(layer "In7.Cu")
		(net "PCIE_GF_I2C_CLK")
	)
	(segment
		(start 90.424 -8.382)
		(end 93.17101 -8.382)
		(width 0.0889)
		(layer "In7.Cu")
		(net "PCIE_GF_I2C_CLK")
	)
	(segment
		(start 87.119714 -11.8872)
		(end 87.596726 -11.8872)
		(width 0.0889)
		(layer "In7.Cu")
		(net "PCIE_GF_I2C_CLK")
	)
	(segment
		(start 79.883762 -7.747)
		(end 83.274408 -11.137646)
		(width 0.0889)
		(layer "In7.Cu")
		(net "PCIE_GF_I2C_CLK")
	)
	(segment
		(start 35.704018 -7.747)
		(end 79.883762 -7.747)
		(width 0.0889)
		(layer "In7.Cu")
		(net "PCIE_GF_I2C_CLK")
	)
	(segment
		(start 89.662 -9.144)
		(end 90.424 -8.382)
		(width 0.0889)
		(layer "In7.Cu")
		(net "PCIE_GF_I2C_CLK")
	)
	(segment
		(start 89.662 -9.821926)
		(end 89.662 -9.144)
		(width 0.0889)
		(layer "In7.Cu")
		(net "PCIE_GF_I2C_CLK")
	)
	(segment
		(start 87.596726 -11.8872)
		(end 89.662 -9.821926)
		(width 0.0889)
		(layer "In7.Cu")
		(net "PCIE_GF_I2C_CLK")
	)
	(segment
		(start 84.420964 -11.137646)
		(end 85.189822 -11.906504)
		(width 0.0889)
		(layer "In7.Cu")
		(net "PCIE_GF_I2C_CLK")
	)
	(segment
		(start 87.022686 -11.906504)
		(end 87.119714 -11.8872)
		(width 0.0889)
		(layer "In7.Cu")
		(net "PCIE_GF_I2C_CLK")
	)
	(segment
		(start 69.0118 -44.958)
		(end 69.0118 -44.4246)
		(width 0.1143)
		(layer "F.Cu")
		(net "SMBUS_PECI_R_CLK")
	)
	(segment
		(start 69.012054 -44.424346)
		(end 69.012054 -44.3992)
		(width 0.1143)
		(layer "F.Cu")
		(net "SMBUS_PECI_R_CLK")
	)
	(segment
		(start 69.0118 -44.4246)
		(end 69.012054 -44.424346)
		(width 0.1143)
		(layer "F.Cu")
		(net "SMBUS_PECI_R_CLK")
	)
	(segment
		(start 68.6562 -45.3136)
		(end 69.0118 -44.958)
		(width 0.1143)
		(layer "F.Cu")
		(net "SMBUS_PECI_R_CLK")
	)
	(segment
		(start 68.1482 -45.3136)
		(end 68.6562 -45.3136)
		(width 0.1143)
		(layer "F.Cu")
		(net "SMBUS_PECI_R_CLK")
	)
	(segment
		(start 67.6275 -45.06976)
		(end 67.90436 -45.06976)
		(width 0.1143)
		(layer "F.Cu")
		(net "SMBUS_PECI_R_CLK")
	)
	(segment
		(start 67.90436 -45.06976)
		(end 68.1482 -45.3136)
		(width 0.1143)
		(layer "F.Cu")
		(net "SMBUS_PECI_R_CLK")
	)
	(via
		(at 69.012054 -44.3992)
		(size 0.7112)
		(drill 0.3556)
		(layers "F.Cu" "B.Cu")
		(net "SMBUS_PECI_R_CLK")
	)
	(segment
		(start 67.4878 -47.7012)
		(end 67.4116 -47.625)
		(width 0.1143)
		(layer "F.Cu")
		(net "SMBUS_PECI_R_DATA")
	)
	(segment
		(start 65.9765 -46.6725)
		(end 66.929 -47.625)
		(width 0.1143)
		(layer "F.Cu")
		(net "SMBUS_PECI_R_DATA")
	)
	(segment
		(start 67.59956 -48.7299)
		(end 67.4878 -48.61814)
		(width 0.1143)
		(layer "F.Cu")
		(net "SMBUS_PECI_R_DATA")
	)
	(segment
		(start 65.9765 -46.37024)
		(end 65.9765 -46.6725)
		(width 0.1143)
		(layer "F.Cu")
		(net "SMBUS_PECI_R_DATA")
	)
	(segment
		(start 66.929 -47.625)
		(end 67.4116 -47.625)
		(width 0.1143)
		(layer "F.Cu")
		(net "SMBUS_PECI_R_DATA")
	)
	(segment
		(start 68.1482 -43.18)
		(end 68.1482 -43.946572)
		(width 0.1143)
		(layer "F.Cu")
		(net "SMBUS_PECI_R_DATA")
	)
	(segment
		(start 68.1482 -43.946572)
		(end 68.143882 -43.95089)
		(width 0.1143)
		(layer "F.Cu")
		(net "SMBUS_PECI_R_DATA")
	)
	(segment
		(start 67.4878 -48.61814)
		(end 67.4878 -47.7012)
		(width 0.1143)
		(layer "F.Cu")
		(net "SMBUS_PECI_R_DATA")
	)
	(via
		(at 68.143882 -43.95089)
		(size 0.508)
		(drill 0.254)
		(layers "F.Cu" "B.Cu")
		(net "SMBUS_PECI_R_DATA")
	)
	(via
		(at 67.59956 -48.7299)
		(size 0.508)
		(drill 0.254)
		(layers "F.Cu" "B.Cu")
		(net "SMBUS_PECI_R_DATA")
	)
	(via
		(at 67.4116 -47.625)
		(size 0.7112)
		(drill 0.3556)
		(layers "F.Cu" "B.Cu")
		(net "SMBUS_PECI_R_DATA")
	)
	(segment
		(start 68.326 -44.629324)
		(end 67.27825 -45.677074)
		(width 0.1143)
		(layer "B.Cu")
		(net "SMBUS_PECI_R_DATA")
	)
	(segment
		(start 68.143882 -43.95089)
		(end 68.1736 -43.95089)
		(width 0.1143)
		(layer "B.Cu")
		(net "SMBUS_PECI_R_DATA")
	)
	(segment
		(start 67.27825 -48.40859)
		(end 67.59956 -48.7299)
		(width 0.1143)
		(layer "B.Cu")
		(net "SMBUS_PECI_R_DATA")
	)
	(segment
		(start 67.27825 -45.677074)
		(end 67.27825 -48.40859)
		(width 0.1143)
		(layer "B.Cu")
		(net "SMBUS_PECI_R_DATA")
	)
	(segment
		(start 68.1736 -43.95089)
		(end 68.326 -44.10329)
		(width 0.1143)
		(layer "B.Cu")
		(net "SMBUS_PECI_R_DATA")
	)
	(segment
		(start 68.326 -44.10329)
		(end 68.326 -44.629324)
		(width 0.1143)
		(layer "B.Cu")
		(net "SMBUS_PECI_R_DATA")
	)
	(via
		(at 161.1884 -48.0822)
		(size 0.7112)
		(drill 0.3556)
		(layers "F.Cu" "B.Cu")
		(net "C_NCE_R#")
	)
	(via
		(at 164.084 -47.3456)
		(size 0.508)
		(drill 0.254)
		(layers "F.Cu" "B.Cu")
		(net "C_NCE_R#")
	)
	(segment
		(start 142.71625 -49.44745)
		(end 140.8938 -47.625)
		(width 0.1143)
		(layer "B.Cu")
		(net "C_NCE_R#")
	)
	(segment
		(start 144.836388 -49.54905)
		(end 144.734788 -49.44745)
		(width 0.1143)
		(layer "B.Cu")
		(net "C_NCE_R#")
	)
	(segment
		(start 144.734788 -49.44745)
		(end 142.71625 -49.44745)
		(width 0.1143)
		(layer "B.Cu")
		(net "C_NCE_R#")
	)
	(segment
		(start 163.3474 -48.0822)
		(end 161.1884 -48.0822)
		(width 0.1143)
		(layer "B.Cu")
		(net "C_NCE_R#")
	)
	(segment
		(start 161.1884 -48.0822)
		(end 156.877512 -48.0822)
		(width 0.1143)
		(layer "B.Cu")
		(net "C_NCE_R#")
	)
	(segment
		(start 164.084 -47.3456)
		(end 163.3474 -48.0822)
		(width 0.1143)
		(layer "B.Cu")
		(net "C_NCE_R#")
	)
	(segment
		(start 156.877512 -48.0822)
		(end 155.410662 -49.54905)
		(width 0.1143)
		(layer "B.Cu")
		(net "C_NCE_R#")
	)
	(segment
		(start 155.410662 -49.54905)
		(end 144.836388 -49.54905)
		(width 0.1143)
		(layer "B.Cu")
		(net "C_NCE_R#")
	)
	(segment
		(start 184.1754 -29.935424)
		(end 195.39331 -18.717514)
		(width 0.0889)
		(layer "In9.Cu")
		(net "C_NCE_R#")
	)
	(segment
		(start 172.40885 -42.32275)
		(end 181.046374 -42.32275)
		(width 0.0889)
		(layer "In9.Cu")
		(net "C_NCE_R#")
	)
	(segment
		(start 203.290678 -14.099286)
		(end 204.224128 -13.165836)
		(width 0.0889)
		(layer "In9.Cu")
		(net "C_NCE_R#")
	)
	(segment
		(start 204.224128 -13.165836)
		(end 204.224128 -11.946128)
		(width 0.0889)
		(layer "In9.Cu")
		(net "C_NCE_R#")
	)
	(segment
		(start 195.39331 -18.717514)
		(end 201.977752 -18.717514)
		(width 0.0889)
		(layer "In9.Cu")
		(net "C_NCE_R#")
	)
	(segment
		(start 203.290678 -17.404588)
		(end 203.290678 -14.099286)
		(width 0.0889)
		(layer "In9.Cu")
		(net "C_NCE_R#")
	)
	(segment
		(start 201.977752 -18.717514)
		(end 203.290678 -17.404588)
		(width 0.0889)
		(layer "In9.Cu")
		(net "C_NCE_R#")
	)
	(segment
		(start 164.084 -47.3456)
		(end 167.386 -47.3456)
		(width 0.0889)
		(layer "In9.Cu")
		(net "C_NCE_R#")
	)
	(segment
		(start 167.386 -47.3456)
		(end 172.40885 -42.32275)
		(width 0.0889)
		(layer "In9.Cu")
		(net "C_NCE_R#")
	)
	(segment
		(start 184.1754 -39.193724)
		(end 184.1754 -29.935424)
		(width 0.0889)
		(layer "In9.Cu")
		(net "C_NCE_R#")
	)
	(segment
		(start 181.046374 -42.32275)
		(end 184.1754 -39.193724)
		(width 0.0889)
		(layer "In9.Cu")
		(net "C_NCE_R#")
	)
	(segment
		(start 74.803 -44.069)
		(end 77.037438 -41.834562)
		(width 0.127)
		(layer "F.Cu")
		(net "SMBUS_SW_R_EN")
	)
	(segment
		(start 80.742028 -41.597834)
		(end 80.742028 -41.58996)
		(width 0.127)
		(layer "F.Cu")
		(net "SMBUS_SW_R_EN")
	)
	(segment
		(start 80.742028 -41.58996)
		(end 80.429862 -41.277794)
		(width 0.127)
		(layer "F.Cu")
		(net "SMBUS_SW_R_EN")
	)
	(segment
		(start 74.0791 -44.5389)
		(end 74.549 -44.069)
		(width 0.127)
		(layer "F.Cu")
		(net "SMBUS_SW_R_EN")
	)
	(segment
		(start 77.862938 -41.251886)
		(end 77.292962 -41.821862)
		(width 0.127)
		(layer "F.Cu")
		(net "SMBUS_SW_R_EN")
	)
	(segment
		(start 77.037438 -41.834562)
		(end 77.292962 -41.834562)
		(width 0.127)
		(layer "F.Cu")
		(net "SMBUS_SW_R_EN")
	)
	(segment
		(start 72.3519 -43.4467)
		(end 72.3519 -44.136818)
		(width 0.127)
		(layer "F.Cu")
		(net "SMBUS_SW_R_EN")
	)
	(segment
		(start 78.21041 -41.251886)
		(end 77.862938 -41.251886)
		(width 0.127)
		(layer "F.Cu")
		(net "SMBUS_SW_R_EN")
	)
	(segment
		(start 74.5998 -44.069)
		(end 74.803 -44.069)
		(width 0.127)
		(layer "F.Cu")
		(net "SMBUS_SW_R_EN")
	)
	(segment
		(start 72.263 -43.3578)
		(end 72.3519 -43.4467)
		(width 0.127)
		(layer "F.Cu")
		(net "SMBUS_SW_R_EN")
	)
	(segment
		(start 80.950308 -41.806114)
		(end 80.742028 -41.597834)
		(width 0.127)
		(layer "F.Cu")
		(net "SMBUS_SW_R_EN")
	)
	(segment
		(start 72.3519 -44.136818)
		(end 72.753982 -44.5389)
		(width 0.127)
		(layer "F.Cu")
		(net "SMBUS_SW_R_EN")
	)
	(segment
		(start 80.429862 -41.277794)
		(end 78.236318 -41.277794)
		(width 0.127)
		(layer "F.Cu")
		(net "SMBUS_SW_R_EN")
	)
	(segment
		(start 72.753982 -44.5389)
		(end 74.0791 -44.5389)
		(width 0.127)
		(layer "F.Cu")
		(net "SMBUS_SW_R_EN")
	)
	(segment
		(start 74.549 -44.069)
		(end 74.5998 -44.069)
		(width 0.127)
		(layer "F.Cu")
		(net "SMBUS_SW_R_EN")
	)
	(segment
		(start 77.292962 -41.821862)
		(end 77.292962 -41.834562)
		(width 0.127)
		(layer "F.Cu")
		(net "SMBUS_SW_R_EN")
	)
	(segment
		(start 78.236318 -41.277794)
		(end 78.21041 -41.251886)
		(width 0.127)
		(layer "F.Cu")
		(net "SMBUS_SW_R_EN")
	)
	(via
		(at 77.292962 -41.834562)
		(size 0.7112)
		(drill 0.3556)
		(layers "F.Cu" "B.Cu")
		(net "SMBUS_SW_R_EN")
	)
	(segment
		(start 128.494028 -10.999978)
		(end 148.540978 -10.999978)
		(width 0.127)
		(layer "F.Cu")
		(net "CPU_FPGA_DISABLE")
	)
	(segment
		(start 157.6578 -19.431)
		(end 156.972 -19.431)
		(width 0.127)
		(layer "F.Cu")
		(net "CPU_FPGA_DISABLE")
	)
	(segment
		(start 112.2934 -1.3716)
		(end 112.649 -1.016)
		(width 0.127)
		(layer "F.Cu")
		(net "CPU_FPGA_DISABLE")
	)
	(segment
		(start 118.745 -2.882646)
		(end 120.807988 -2.882646)
		(width 0.127)
		(layer "F.Cu")
		(net "CPU_FPGA_DISABLE")
	)
	(segment
		(start 83.301332 -36.397438)
		(end 83.301332 -36.071302)
		(width 0.127)
		(layer "F.Cu")
		(net "CPU_FPGA_DISABLE")
	)
	(segment
		(start 83.647788 -36.743894)
		(end 83.301332 -36.397438)
		(width 0.127)
		(layer "F.Cu")
		(net "CPU_FPGA_DISABLE")
	)
	(segment
		(start 120.807988 -2.882646)
		(end 128.27 -10.344658)
		(width 0.127)
		(layer "F.Cu")
		(net "CPU_FPGA_DISABLE")
	)
	(segment
		(start 116.878354 -1.016)
		(end 118.745 -2.882646)
		(width 0.127)
		(layer "F.Cu")
		(net "CPU_FPGA_DISABLE")
	)
	(segment
		(start 158.115 -19.8882)
		(end 157.6578 -19.431)
		(width 0.127)
		(layer "F.Cu")
		(net "CPU_FPGA_DISABLE")
	)
	(segment
		(start 157.6324 -21.1836)
		(end 157.6324 -20.3708)
		(width 0.127)
		(layer "F.Cu")
		(net "CPU_FPGA_DISABLE")
	)
	(segment
		(start 112.649 -1.016)
		(end 116.878354 -1.016)
		(width 0.127)
		(layer "F.Cu")
		(net "CPU_FPGA_DISABLE")
	)
	(segment
		(start 148.540978 -10.999978)
		(end 156.329126 -18.788126)
		(width 0.127)
		(layer "F.Cu")
		(net "CPU_FPGA_DISABLE")
	)
	(segment
		(start 156.972 -19.431)
		(end 156.329126 -18.788126)
		(width 0.127)
		(layer "F.Cu")
		(net "CPU_FPGA_DISABLE")
	)
	(segment
		(start 128.27 -10.77595)
		(end 128.494028 -10.999978)
		(width 0.127)
		(layer "F.Cu")
		(net "CPU_FPGA_DISABLE")
	)
	(segment
		(start 83.301332 -36.071302)
		(end 83.302602 -36.070032)
		(width 0.127)
		(layer "F.Cu")
		(net "CPU_FPGA_DISABLE")
	)
	(segment
		(start 157.6324 -20.3708)
		(end 158.115 -19.8882)
		(width 0.127)
		(layer "F.Cu")
		(net "CPU_FPGA_DISABLE")
	)
	(segment
		(start 158.115 -21.6662)
		(end 157.6324 -21.1836)
		(width 0.127)
		(layer "F.Cu")
		(net "CPU_FPGA_DISABLE")
	)
	(segment
		(start 112.2934 -1.779524)
		(end 112.2934 -1.3716)
		(width 0.127)
		(layer "F.Cu")
		(net "CPU_FPGA_DISABLE")
	)
	(segment
		(start 128.27 -10.344658)
		(end 128.27 -10.77595)
		(width 0.127)
		(layer "F.Cu")
		(net "CPU_FPGA_DISABLE")
	)
	(via
		(at 112.2934 -1.779524)
		(size 0.508)
		(drill 0.254)
		(layers "F.Cu" "B.Cu")
		(net "CPU_FPGA_DISABLE")
	)
	(via
		(at 83.302602 -36.070032)
		(size 0.4318)
		(drill 0.2032)
		(layers "F.Cu" "B.Cu")
		(net "CPU_FPGA_DISABLE")
	)
	(via
		(at 156.329126 -18.788126)
		(size 0.7112)
		(drill 0.3556)
		(layers "F.Cu" "B.Cu")
		(net "CPU_FPGA_DISABLE")
	)
	(via
		(at 78.486 -34.9504)
		(size 0.4318)
		(drill 0.2032)
		(layers "F.Cu" "B.Cu")
		(net "CPU_FPGA_DISABLE")
	)
	(segment
		(start 78.486 -34.9504)
		(end 78.62824 -34.9504)
		(width 0.127)
		(layer "B.Cu")
		(net "CPU_FPGA_DISABLE")
	)
	(segment
		(start 82.543142 -35.56)
		(end 82.81416 -35.56)
		(width 0.127)
		(layer "B.Cu")
		(net "CPU_FPGA_DISABLE")
	)
	(segment
		(start 81.636108 -35.484816)
		(end 82.467958 -35.484816)
		(width 0.127)
		(layer "B.Cu")
		(net "CPU_FPGA_DISABLE")
	)
	(segment
		(start 82.81416 -35.56)
		(end 83.302602 -36.048442)
		(width 0.127)
		(layer "B.Cu")
		(net "CPU_FPGA_DISABLE")
	)
	(segment
		(start 77.842618 -34.9504)
		(end 78.486 -34.9504)
		(width 0.127)
		(layer "B.Cu")
		(net "CPU_FPGA_DISABLE")
	)
	(segment
		(start 75.486768 -33.3883)
		(end 75.502516 -33.3883)
		(width 0.127)
		(layer "B.Cu")
		(net "CPU_FPGA_DISABLE")
	)
	(segment
		(start 78.62824 -34.9504)
		(end 78.63459 -34.94405)
		(width 0.127)
		(layer "B.Cu")
		(net "CPU_FPGA_DISABLE")
	)
	(segment
		(start 78.63459 -34.94405)
		(end 81.095342 -34.94405)
		(width 0.127)
		(layer "B.Cu")
		(net "CPU_FPGA_DISABLE")
	)
	(segment
		(start 74.4728 -33.274)
		(end 75.372468 -33.274)
		(width 0.127)
		(layer "B.Cu")
		(net "CPU_FPGA_DISABLE")
	)
	(segment
		(start 76.547218 -33.655)
		(end 77.842618 -34.9504)
		(width 0.127)
		(layer "B.Cu")
		(net "CPU_FPGA_DISABLE")
	)
	(segment
		(start 82.467958 -35.484816)
		(end 82.543142 -35.56)
		(width 0.127)
		(layer "B.Cu")
		(net "CPU_FPGA_DISABLE")
	)
	(segment
		(start 75.769216 -33.655)
		(end 76.547218 -33.655)
		(width 0.127)
		(layer "B.Cu")
		(net "CPU_FPGA_DISABLE")
	)
	(segment
		(start 75.372468 -33.274)
		(end 75.486768 -33.3883)
		(width 0.127)
		(layer "B.Cu")
		(net "CPU_FPGA_DISABLE")
	)
	(segment
		(start 81.095342 -34.94405)
		(end 81.636108 -35.484816)
		(width 0.127)
		(layer "B.Cu")
		(net "CPU_FPGA_DISABLE")
	)
	(segment
		(start 83.302602 -36.048442)
		(end 83.302602 -36.070032)
		(width 0.127)
		(layer "B.Cu")
		(net "CPU_FPGA_DISABLE")
	)
	(segment
		(start 75.502516 -33.3883)
		(end 75.769216 -33.655)
		(width 0.127)
		(layer "B.Cu")
		(net "CPU_FPGA_DISABLE")
	)
	(segment
		(start 94.86773 -15.8242)
		(end 86.383114 -15.8242)
		(width 0.127)
		(layer "In9.Cu")
		(net "CPU_FPGA_DISABLE")
	)
	(segment
		(start 78.994 -32.7152)
		(end 78.994 -34.4424)
		(width 0.127)
		(layer "In9.Cu")
		(net "CPU_FPGA_DISABLE")
	)
	(segment
		(start 85.252052 -17.275048)
		(end 78.867 -23.6601)
		(width 0.127)
		(layer "In9.Cu")
		(net "CPU_FPGA_DISABLE")
	)
	(segment
		(start 112.2934 -1.779524)
		(end 112.2934 -2.692146)
		(width 0.127)
		(layer "In9.Cu")
		(net "CPU_FPGA_DISABLE")
	)
	(segment
		(start 77.3176 -31.0388)
		(end 78.994 -32.7152)
		(width 0.127)
		(layer "In9.Cu")
		(net "CPU_FPGA_DISABLE")
	)
	(segment
		(start 95.264986 -16.221456)
		(end 94.86773 -15.8242)
		(width 0.127)
		(layer "In9.Cu")
		(net "CPU_FPGA_DISABLE")
	)
	(segment
		(start 78.124558 -26.015442)
		(end 78.124558 -28.213558)
		(width 0.127)
		(layer "In9.Cu")
		(net "CPU_FPGA_DISABLE")
	)
	(segment
		(start 86.383114 -15.8242)
		(end 85.252052 -16.955262)
		(width 0.127)
		(layer "In9.Cu")
		(net "CPU_FPGA_DISABLE")
	)
	(segment
		(start 112.2934 -2.692146)
		(end 110.0836 -4.901946)
		(width 0.127)
		(layer "In9.Cu")
		(net "CPU_FPGA_DISABLE")
	)
	(segment
		(start 77.3176 -29.020516)
		(end 77.3176 -31.0388)
		(width 0.127)
		(layer "In9.Cu")
		(net "CPU_FPGA_DISABLE")
	)
	(segment
		(start 78.124558 -28.213558)
		(end 77.3176 -29.020516)
		(width 0.127)
		(layer "In9.Cu")
		(net "CPU_FPGA_DISABLE")
	)
	(segment
		(start 78.994 -34.4424)
		(end 78.486 -34.9504)
		(width 0.127)
		(layer "In9.Cu")
		(net "CPU_FPGA_DISABLE")
	)
	(segment
		(start 110.0836 -4.901946)
		(end 110.0836 -12.426696)
		(width 0.127)
		(layer "In9.Cu")
		(net "CPU_FPGA_DISABLE")
	)
	(segment
		(start 78.867 -23.6601)
		(end 78.867 -25.273)
		(width 0.127)
		(layer "In9.Cu")
		(net "CPU_FPGA_DISABLE")
	)
	(segment
		(start 106.28884 -16.221456)
		(end 95.264986 -16.221456)
		(width 0.127)
		(layer "In9.Cu")
		(net "CPU_FPGA_DISABLE")
	)
	(segment
		(start 78.867 -25.273)
		(end 78.124558 -26.015442)
		(width 0.127)
		(layer "In9.Cu")
		(net "CPU_FPGA_DISABLE")
	)
	(segment
		(start 110.0836 -12.426696)
		(end 106.28884 -16.221456)
		(width 0.127)
		(layer "In9.Cu")
		(net "CPU_FPGA_DISABLE")
	)
	(segment
		(start 85.252052 -16.955262)
		(end 85.252052 -17.275048)
		(width 0.127)
		(layer "In9.Cu")
		(net "CPU_FPGA_DISABLE")
	)
	(segment
		(start 71.12 -51.955954)
		(end 71.12 -49.604168)
		(width 0.127)
		(layer "F.Cu")
		(net "SMBUS_SW_EN")
	)
	(segment
		(start 61.976 -41.068498)
		(end 61.68771 -40.780208)
		(width 0.127)
		(layer "F.Cu")
		(net "SMBUS_SW_EN")
	)
	(segment
		(start 71.74484 -48.979328)
		(end 71.74484 -48.1076)
		(width 0.127)
		(layer "F.Cu")
		(net "SMBUS_SW_EN")
	)
	(segment
		(start 70.231 -41.2496)
		(end 69.930264 -40.948864)
		(width 0.127)
		(layer "F.Cu")
		(net "SMBUS_SW_EN")
	)
	(segment
		(start 68.525136 -40.948864)
		(end 68.199 -41.275)
		(width 0.127)
		(layer "F.Cu")
		(net "SMBUS_SW_EN")
	)
	(segment
		(start 72.39 -42.4942)
		(end 72.263 -42.4942)
		(width 0.127)
		(layer "F.Cu")
		(net "SMBUS_SW_EN")
	)
	(segment
		(start 61.994542 -40.08374)
		(end 63.246 -40.08374)
		(width 0.127)
		(layer "F.Cu")
		(net "SMBUS_SW_EN")
	)
	(segment
		(start 72.263 -42.4942)
		(end 71.9328 -42.164)
		(width 0.127)
		(layer "F.Cu")
		(net "SMBUS_SW_EN")
	)
	(segment
		(start 71.12 -49.604168)
		(end 71.74484 -48.979328)
		(width 0.127)
		(layer "F.Cu")
		(net "SMBUS_SW_EN")
	)
	(segment
		(start 72.8472 -41.656)
		(end 72.8472 -42.037)
		(width 0.127)
		(layer "F.Cu")
		(net "SMBUS_SW_EN")
	)
	(segment
		(start 70.521322 -42.164)
		(end 70.231 -41.873678)
		(width 0.127)
		(layer "F.Cu")
		(net "SMBUS_SW_EN")
	)
	(segment
		(start 71.681086 -52.51704)
		(end 71.12 -51.955954)
		(width 0.127)
		(layer "F.Cu")
		(net "SMBUS_SW_EN")
	)
	(segment
		(start 65.2272 -41.8084)
		(end 64.60109 -41.8084)
		(width 0.127)
		(layer "F.Cu")
		(net "SMBUS_SW_EN")
	)
	(segment
		(start 64.28994 -40.08374)
		(end 63.246 -40.08374)
		(width 0.127)
		(layer "F.Cu")
		(net "SMBUS_SW_EN")
	)
	(segment
		(start 65.7606 -41.275)
		(end 65.526158 -41.509442)
		(width 0.127)
		(layer "F.Cu")
		(net "SMBUS_SW_EN")
	)
	(segment
		(start 70.231 -41.873678)
		(end 70.231 -41.2496)
		(width 0.127)
		(layer "F.Cu")
		(net "SMBUS_SW_EN")
	)
	(segment
		(start 64.60109 -41.8084)
		(end 64.60109 -40.39489)
		(width 0.127)
		(layer "F.Cu")
		(net "SMBUS_SW_EN")
	)
	(segment
		(start 64.60109 -40.39489)
		(end 64.28994 -40.08374)
		(width 0.127)
		(layer "F.Cu")
		(net "SMBUS_SW_EN")
	)
	(segment
		(start 62.1284 -41.8084)
		(end 61.976 -41.656)
		(width 0.127)
		(layer "F.Cu")
		(net "SMBUS_SW_EN")
	)
	(segment
		(start 61.68771 -40.390572)
		(end 61.994542 -40.08374)
		(width 0.127)
		(layer "F.Cu")
		(net "SMBUS_SW_EN")
	)
	(segment
		(start 69.930264 -40.948864)
		(end 68.525136 -40.948864)
		(width 0.127)
		(layer "F.Cu")
		(net "SMBUS_SW_EN")
	)
	(segment
		(start 61.68771 -40.780208)
		(end 61.68771 -40.390572)
		(width 0.127)
		(layer "F.Cu")
		(net "SMBUS_SW_EN")
	)
	(segment
		(start 71.9328 -42.164)
		(end 70.521322 -42.164)
		(width 0.127)
		(layer "F.Cu")
		(net "SMBUS_SW_EN")
	)
	(segment
		(start 68.199 -41.275)
		(end 65.7606 -41.275)
		(width 0.127)
		(layer "F.Cu")
		(net "SMBUS_SW_EN")
	)
	(segment
		(start 61.976 -41.656)
		(end 61.976 -41.068498)
		(width 0.127)
		(layer "F.Cu")
		(net "SMBUS_SW_EN")
	)
	(segment
		(start 65.526158 -41.509442)
		(end 65.2272 -41.8084)
		(width 0.127)
		(layer "F.Cu")
		(net "SMBUS_SW_EN")
	)
	(segment
		(start 62.60211 -41.8084)
		(end 62.1284 -41.8084)
		(width 0.127)
		(layer "F.Cu")
		(net "SMBUS_SW_EN")
	)
	(segment
		(start 72.8472 -42.037)
		(end 72.39 -42.4942)
		(width 0.127)
		(layer "F.Cu")
		(net "SMBUS_SW_EN")
	)
	(via
		(at 65.526158 -41.509442)
		(size 0.508)
		(drill 0.254)
		(layers "F.Cu" "B.Cu")
		(net "SMBUS_SW_EN")
	)
	(via
		(at 71.74484 -48.1076)
		(size 0.508)
		(drill 0.254)
		(layers "F.Cu" "B.Cu")
		(net "SMBUS_SW_EN")
	)
	(via
		(at 63.246 -40.08374)
		(size 0.7112)
		(drill 0.3556)
		(layers "F.Cu" "B.Cu")
		(net "SMBUS_SW_EN")
	)
	(segment
		(start 65.526158 -41.737534)
		(end 66.4972 -42.708576)
		(width 0.127)
		(layer "In9.Cu")
		(net "SMBUS_SW_EN")
	)
	(segment
		(start 65.526158 -41.509442)
		(end 65.526158 -41.737534)
		(width 0.127)
		(layer "In9.Cu")
		(net "SMBUS_SW_EN")
	)
	(segment
		(start 66.4972 -43.920918)
		(end 67.013582 -44.4373)
		(width 0.127)
		(layer "In9.Cu")
		(net "SMBUS_SW_EN")
	)
	(segment
		(start 67.420236 -44.420282)
		(end 67.962272 -44.420282)
		(width 0.127)
		(layer "In9.Cu")
		(net "SMBUS_SW_EN")
	)
	(segment
		(start 71.642986 -48.100996)
		(end 71.738236 -48.100996)
		(width 0.127)
		(layer "In9.Cu")
		(net "SMBUS_SW_EN")
	)
	(segment
		(start 67.013582 -44.4373)
		(end 67.403218 -44.4373)
		(width 0.127)
		(layer "In9.Cu")
		(net "SMBUS_SW_EN")
	)
	(segment
		(start 67.403218 -44.4373)
		(end 67.420236 -44.420282)
		(width 0.127)
		(layer "In9.Cu")
		(net "SMBUS_SW_EN")
	)
	(segment
		(start 67.962272 -44.420282)
		(end 71.642986 -48.100996)
		(width 0.127)
		(layer "In9.Cu")
		(net "SMBUS_SW_EN")
	)
	(segment
		(start 71.738236 -48.100996)
		(end 71.74484 -48.1076)
		(width 0.127)
		(layer "In9.Cu")
		(net "SMBUS_SW_EN")
	)
	(segment
		(start 66.4972 -42.708576)
		(end 66.4972 -43.920918)
		(width 0.127)
		(layer "In9.Cu")
		(net "SMBUS_SW_EN")
	)
	(segment
		(start 20.349972 -6.195568)
		(end 20.349972 -7.971028)
		(width 0.1397)
		(layer "F.Cu")
		(net "P2E_CPU_ETH10G_RX_DP11")
	)
	(segment
		(start 91.092782 -49.0982)
		(end 90.6018 -49.0982)
		(width 0.1397)
		(layer "F.Cu")
		(net "P2E_CPU_ETH10G_RX_DP11")
	)
	(segment
		(start 20.021296 -9.9441)
		(end 20.327874 -10.250678)
		(width 0.1397)
		(layer "F.Cu")
		(net "P2E_CPU_ETH10G_RX_DP11")
	)
	(segment
		(start 91.407488 -48.783494)
		(end 91.092782 -49.0982)
		(width 0.1397)
		(layer "F.Cu")
		(net "P2E_CPU_ETH10G_RX_DP11")
	)
	(segment
		(start 20.349972 -7.971028)
		(end 20.021296 -8.299704)
		(width 0.1397)
		(layer "F.Cu")
		(net "P2E_CPU_ETH10G_RX_DP11")
	)
	(segment
		(start 20.021296 -8.299704)
		(end 20.021296 -9.9441)
		(width 0.1397)
		(layer "F.Cu")
		(net "P2E_CPU_ETH10G_RX_DP11")
	)
	(via
		(at 90.6018 -49.0982)
		(size 0.4318)
		(drill 0.2032)
		(layers "F.Cu" "B.Cu")
		(net "P2E_CPU_ETH10G_RX_DP11")
	)
	(via
		(at 20.327874 -10.250678)
		(size 0.508)
		(drill 0.254)
		(layers "F.Cu" "B.Cu")
		(net "P2E_CPU_ETH10G_RX_DP11")
	)
	(segment
		(start 23.5712 -13.3604)
		(end 25.6286 -15.4178)
		(width 0.1143)
		(layer "In9.Cu")
		(net "P2E_CPU_ETH10G_RX_DP11")
	)
	(segment
		(start 85.984588 -57.283096)
		(end 86.074504 -57.283096)
		(width 0.1016)
		(layer "In9.Cu")
		(net "P2E_CPU_ETH10G_RX_DP11")
	)
	(segment
		(start 55.040276 -49.85385)
		(end 62.063376 -56.87695)
		(width 0.1143)
		(layer "In9.Cu")
		(net "P2E_CPU_ETH10G_RX_DP11")
	)
	(segment
		(start 85.975444 -57.29224)
		(end 85.984588 -57.283096)
		(width 0.1016)
		(layer "In9.Cu")
		(net "P2E_CPU_ETH10G_RX_DP11")
	)
	(segment
		(start 52.403756 -45.7708)
		(end 53.62575 -46.992794)
		(width 0.1143)
		(layer "In9.Cu")
		(net "P2E_CPU_ETH10G_RX_DP11")
	)
	(segment
		(start 89.432638 -54.978554)
		(end 89.572846 -54.978554)
		(width 0.1016)
		(layer "In9.Cu")
		(net "P2E_CPU_ETH10G_RX_DP11")
	)
	(segment
		(start 53.62575 -48.972978)
		(end 54.506622 -49.85385)
		(width 0.1143)
		(layer "In9.Cu")
		(net "P2E_CPU_ETH10G_RX_DP11")
	)
	(segment
		(start 20.327874 -10.250678)
		(end 20.033234 -10.545318)
		(width 0.1143)
		(layer "In9.Cu")
		(net "P2E_CPU_ETH10G_RX_DP11")
	)
	(segment
		(start 90.5129 -50.672746)
		(end 90.18905 -50.348896)
		(width 0.1016)
		(layer "In9.Cu")
		(net "P2E_CPU_ETH10G_RX_DP11")
	)
	(segment
		(start 90.5129 -51.424332)
		(end 90.5129 -50.672746)
		(width 0.1016)
		(layer "In9.Cu")
		(net "P2E_CPU_ETH10G_RX_DP11")
	)
	(segment
		(start 50.057812 -40.991028)
		(end 50.057812 -44.764706)
		(width 0.1143)
		(layer "In9.Cu")
		(net "P2E_CPU_ETH10G_RX_DP11")
	)
	(segment
		(start 32.12338 -24.97709)
		(end 33.0454 -25.89911)
		(width 0.1143)
		(layer "In9.Cu")
		(net "P2E_CPU_ETH10G_RX_DP11")
	)
	(segment
		(start 51.063906 -45.7708)
		(end 52.403756 -45.7708)
		(width 0.1143)
		(layer "In9.Cu")
		(net "P2E_CPU_ETH10G_RX_DP11")
	)
	(segment
		(start 89.217246 -55.334154)
		(end 89.217246 -55.1942)
		(width 0.1016)
		(layer "In9.Cu")
		(net "P2E_CPU_ETH10G_RX_DP11")
	)
	(segment
		(start 33.0454 -25.89911)
		(end 33.0454 -29.022294)
		(width 0.1143)
		(layer "In9.Cu")
		(net "P2E_CPU_ETH10G_RX_DP11")
	)
	(segment
		(start 85.344 -58.801)
		(end 85.344 -57.923684)
		(width 0.1143)
		(layer "In9.Cu")
		(net "P2E_CPU_ETH10G_RX_DP11")
	)
	(segment
		(start 48.690784 -39.624)
		(end 50.057812 -40.991028)
		(width 0.1143)
		(layer "In9.Cu")
		(net "P2E_CPU_ETH10G_RX_DP11")
	)
	(segment
		(start 50.057812 -44.764706)
		(end 51.063906 -45.7708)
		(width 0.1143)
		(layer "In9.Cu")
		(net "P2E_CPU_ETH10G_RX_DP11")
	)
	(segment
		(start 20.261834 -11.1506)
		(end 22.68474 -11.1506)
		(width 0.1143)
		(layer "In9.Cu")
		(net "P2E_CPU_ETH10G_RX_DP11")
	)
	(segment
		(start 90.41384 -52.331112)
		(end 90.5129 -52.232052)
		(width 0.1016)
		(layer "In9.Cu")
		(net "P2E_CPU_ETH10G_RX_DP11")
	)
	(segment
		(start 23.5712 -12.03706)
		(end 23.5712 -13.3604)
		(width 0.1143)
		(layer "In9.Cu")
		(net "P2E_CPU_ETH10G_RX_DP11")
	)
	(segment
		(start 90.2716 -53.281072)
		(end 90.5129 -53.039772)
		(width 0.1016)
		(layer "In9.Cu")
		(net "P2E_CPU_ETH10G_RX_DP11")
	)
	(segment
		(start 88.646 -55.9054)
		(end 89.217246 -55.334154)
		(width 0.1016)
		(layer "In9.Cu")
		(net "P2E_CPU_ETH10G_RX_DP11")
	)
	(segment
		(start 90.41384 -51.523392)
		(end 90.5129 -51.424332)
		(width 0.1016)
		(layer "In9.Cu")
		(net "P2E_CPU_ETH10G_RX_DP11")
	)
	(segment
		(start 54.506622 -49.85385)
		(end 55.040276 -49.85385)
		(width 0.1143)
		(layer "In9.Cu")
		(net "P2E_CPU_ETH10G_RX_DP11")
	)
	(segment
		(start 90.5129 -53.039772)
		(end 90.5129 -52.734972)
		(width 0.1016)
		(layer "In9.Cu")
		(net "P2E_CPU_ETH10G_RX_DP11")
	)
	(segment
		(start 53.62575 -46.992794)
		(end 53.62575 -48.972978)
		(width 0.1143)
		(layer "In9.Cu")
		(net "P2E_CPU_ETH10G_RX_DP11")
	)
	(segment
		(start 90.18905 -50.348896)
		(end 90.18905 -49.51095)
		(width 0.1016)
		(layer "In9.Cu")
		(net "P2E_CPU_ETH10G_RX_DP11")
	)
	(segment
		(start 90.2716 -54.2798)
		(end 90.2716 -53.281072)
		(width 0.1016)
		(layer "In9.Cu")
		(net "P2E_CPU_ETH10G_RX_DP11")
	)
	(segment
		(start 90.41384 -52.635912)
		(end 90.41384 -52.331112)
		(width 0.1016)
		(layer "In9.Cu")
		(net "P2E_CPU_ETH10G_RX_DP11")
	)
	(segment
		(start 85.344 -57.923684)
		(end 85.975444 -57.29224)
		(width 0.1143)
		(layer "In9.Cu")
		(net "P2E_CPU_ETH10G_RX_DP11")
	)
	(segment
		(start 33.0454 -29.022294)
		(end 43.647106 -39.624)
		(width 0.1143)
		(layer "In9.Cu")
		(net "P2E_CPU_ETH10G_RX_DP11")
	)
	(segment
		(start 87.4522 -55.9054)
		(end 88.646 -55.9054)
		(width 0.1016)
		(layer "In9.Cu")
		(net "P2E_CPU_ETH10G_RX_DP11")
	)
	(segment
		(start 83.1215 -61.0235)
		(end 85.344 -58.801)
		(width 0.1143)
		(layer "In9.Cu")
		(net "P2E_CPU_ETH10G_RX_DP11")
	)
	(segment
		(start 25.6286 -17.527016)
		(end 32.12338 -24.021796)
		(width 0.1143)
		(layer "In9.Cu")
		(net "P2E_CPU_ETH10G_RX_DP11")
	)
	(segment
		(start 20.033234 -10.922)
		(end 20.261834 -11.1506)
		(width 0.1143)
		(layer "In9.Cu")
		(net "P2E_CPU_ETH10G_RX_DP11")
	)
	(segment
		(start 43.647106 -39.624)
		(end 48.690784 -39.624)
		(width 0.1143)
		(layer "In9.Cu")
		(net "P2E_CPU_ETH10G_RX_DP11")
	)
	(segment
		(start 25.6286 -15.4178)
		(end 25.6286 -17.527016)
		(width 0.1143)
		(layer "In9.Cu")
		(net "P2E_CPU_ETH10G_RX_DP11")
	)
	(segment
		(start 90.5129 -51.927252)
		(end 90.41384 -51.828192)
		(width 0.1016)
		(layer "In9.Cu")
		(net "P2E_CPU_ETH10G_RX_DP11")
	)
	(segment
		(start 90.18905 -49.51095)
		(end 90.6018 -49.0982)
		(width 0.1016)
		(layer "In9.Cu")
		(net "P2E_CPU_ETH10G_RX_DP11")
	)
	(segment
		(start 89.572846 -54.978554)
		(end 90.2716 -54.2798)
		(width 0.1016)
		(layer "In9.Cu")
		(net "P2E_CPU_ETH10G_RX_DP11")
	)
	(segment
		(start 89.217246 -55.1942)
		(end 89.432638 -54.978554)
		(width 0.1016)
		(layer "In9.Cu")
		(net "P2E_CPU_ETH10G_RX_DP11")
	)
	(segment
		(start 86.074504 -57.283096)
		(end 87.4522 -55.9054)
		(width 0.1016)
		(layer "In9.Cu")
		(net "P2E_CPU_ETH10G_RX_DP11")
	)
	(segment
		(start 22.68474 -11.1506)
		(end 23.5712 -12.03706)
		(width 0.1143)
		(layer "In9.Cu")
		(net "P2E_CPU_ETH10G_RX_DP11")
	)
	(segment
		(start 90.5129 -52.734972)
		(end 90.41384 -52.635912)
		(width 0.1016)
		(layer "In9.Cu")
		(net "P2E_CPU_ETH10G_RX_DP11")
	)
	(segment
		(start 65.6844 -56.87695)
		(end 69.83095 -61.0235)
		(width 0.1143)
		(layer "In9.Cu")
		(net "P2E_CPU_ETH10G_RX_DP11")
	)
	(segment
		(start 90.5129 -52.232052)
		(end 90.5129 -51.927252)
		(width 0.1016)
		(layer "In9.Cu")
		(net "P2E_CPU_ETH10G_RX_DP11")
	)
	(segment
		(start 69.83095 -61.0235)
		(end 83.1215 -61.0235)
		(width 0.1143)
		(layer "In9.Cu")
		(net "P2E_CPU_ETH10G_RX_DP11")
	)
	(segment
		(start 32.12338 -24.021796)
		(end 32.12338 -24.97709)
		(width 0.1143)
		(layer "In9.Cu")
		(net "P2E_CPU_ETH10G_RX_DP11")
	)
	(segment
		(start 62.063376 -56.87695)
		(end 65.6844 -56.87695)
		(width 0.1143)
		(layer "In9.Cu")
		(net "P2E_CPU_ETH10G_RX_DP11")
	)
	(segment
		(start 20.033234 -10.545318)
		(end 20.033234 -10.922)
		(width 0.1143)
		(layer "In9.Cu")
		(net "P2E_CPU_ETH10G_RX_DP11")
	)
	(segment
		(start 90.41384 -51.828192)
		(end 90.41384 -51.523392)
		(width 0.1016)
		(layer "In9.Cu")
		(net "P2E_CPU_ETH10G_RX_DP11")
	)
	(segment
		(start 24.349964 -6.195568)
		(end 24.349964 -8.009636)
		(width 0.1397)
		(layer "F.Cu")
		(net "P2E_CPU_ETH10G_RX_DP10")
	)
	(segment
		(start 24.349964 -8.009636)
		(end 24.021542 -8.338058)
		(width 0.1397)
		(layer "F.Cu")
		(net "P2E_CPU_ETH10G_RX_DP10")
	)
	(segment
		(start 24.021542 -9.944354)
		(end 24.327866 -10.250678)
		(width 0.1397)
		(layer "F.Cu")
		(net "P2E_CPU_ETH10G_RX_DP10")
	)
	(segment
		(start 90.122248 -48.402494)
		(end 89.82075 -48.703992)
		(width 0.1397)
		(layer "F.Cu")
		(net "P2E_CPU_ETH10G_RX_DP10")
	)
	(segment
		(start 89.82075 -48.703992)
		(end 89.82075 -48.77943)
		(width 0.1397)
		(layer "F.Cu")
		(net "P2E_CPU_ETH10G_RX_DP10")
	)
	(segment
		(start 24.021542 -8.338058)
		(end 24.021542 -9.944354)
		(width 0.1397)
		(layer "F.Cu")
		(net "P2E_CPU_ETH10G_RX_DP10")
	)
	(via
		(at 89.82075 -48.77943)
		(size 0.4318)
		(drill 0.2032)
		(layers "F.Cu" "B.Cu")
		(net "P2E_CPU_ETH10G_RX_DP10")
	)
	(via
		(at 24.327866 -10.250678)
		(size 0.508)
		(drill 0.254)
		(layers "F.Cu" "B.Cu")
		(net "P2E_CPU_ETH10G_RX_DP10")
	)
	(segment
		(start 27.3304 -13.553694)
		(end 27.05862 -13.281914)
		(width 0.1143)
		(layer "In9.Cu")
		(net "P2E_CPU_ETH10G_RX_DP10")
	)
	(segment
		(start 33.076134 -23.627334)
		(end 27.1018 -17.653)
		(width 0.1143)
		(layer "In9.Cu")
		(net "P2E_CPU_ETH10G_RX_DP10")
	)
	(segment
		(start 27.05862 -13.281914)
		(end 27.05862 -11.90752)
		(width 0.1143)
		(layer "In9.Cu")
		(net "P2E_CPU_ETH10G_RX_DP10")
	)
	(segment
		(start 49.0728 -38.6588)
		(end 44.029122 -38.6588)
		(width 0.1143)
		(layer "In9.Cu")
		(net "P2E_CPU_ETH10G_RX_DP10")
	)
	(segment
		(start 62.459362 -55.92445)
		(end 54.57825 -48.043338)
		(width 0.1143)
		(layer "In9.Cu")
		(net "P2E_CPU_ETH10G_RX_DP10")
	)
	(segment
		(start 66.155316 -55.92445)
		(end 62.459362 -55.92445)
		(width 0.1143)
		(layer "In9.Cu")
		(net "P2E_CPU_ETH10G_RX_DP10")
	)
	(segment
		(start 33.076134 -24.582628)
		(end 33.076134 -23.627334)
		(width 0.1143)
		(layer "In9.Cu")
		(net "P2E_CPU_ETH10G_RX_DP10")
	)
	(segment
		(start 24.007572 -10.875772)
		(end 24.007572 -10.570972)
		(width 0.1143)
		(layer "In9.Cu")
		(net "P2E_CPU_ETH10G_RX_DP10")
	)
	(segment
		(start 88.7349 -53.230272)
		(end 88.7349 -54.614572)
		(width 0.1016)
		(layer "In9.Cu")
		(net "P2E_CPU_ETH10G_RX_DP10")
	)
	(segment
		(start 89.349326 -51.482244)
		(end 89.349326 -51.787044)
		(width 0.1016)
		(layer "In9.Cu")
		(net "P2E_CPU_ETH10G_RX_DP10")
	)
	(segment
		(start 87.139272 -55.4228)
		(end 85.793072 -56.769)
		(width 0.1016)
		(layer "In9.Cu")
		(net "P2E_CPU_ETH10G_RX_DP10")
	)
	(segment
		(start 89.448386 -51.383184)
		(end 89.349326 -51.482244)
		(width 0.1016)
		(layer "In9.Cu")
		(net "P2E_CPU_ETH10G_RX_DP10")
	)
	(segment
		(start 27.1018 -15.402306)
		(end 27.3304 -15.173706)
		(width 0.1143)
		(layer "In9.Cu")
		(net "P2E_CPU_ETH10G_RX_DP10")
	)
	(segment
		(start 52.4002 -44.420028)
		(end 52.4002 -40.5892)
		(width 0.1143)
		(layer "In9.Cu")
		(net "P2E_CPU_ETH10G_RX_DP10")
	)
	(segment
		(start 34.0106 -25.517094)
		(end 33.076134 -24.582628)
		(width 0.1143)
		(layer "In9.Cu")
		(net "P2E_CPU_ETH10G_RX_DP10")
	)
	(segment
		(start 34.0106 -28.640278)
		(end 34.0106 -25.517094)
		(width 0.1143)
		(layer "In9.Cu")
		(net "P2E_CPU_ETH10G_RX_DP10")
	)
	(segment
		(start 84.695284 -57.014872)
		(end 84.605622 -57.014872)
		(width 0.1016)
		(layer "In9.Cu")
		(net "P2E_CPU_ETH10G_RX_DP10")
	)
	(segment
		(start 89.448386 -49.151794)
		(end 89.448386 -51.383184)
		(width 0.1016)
		(layer "In9.Cu")
		(net "P2E_CPU_ETH10G_RX_DP10")
	)
	(segment
		(start 89.448386 -51.886104)
		(end 89.448386 -52.516786)
		(width 0.1016)
		(layer "In9.Cu")
		(net "P2E_CPU_ETH10G_RX_DP10")
	)
	(segment
		(start 27.05862 -11.90752)
		(end 26.5176 -11.3665)
		(width 0.1143)
		(layer "In9.Cu")
		(net "P2E_CPU_ETH10G_RX_DP10")
	)
	(segment
		(start 82.019394 -59.6011)
		(end 69.831966 -59.6011)
		(width 0.1143)
		(layer "In9.Cu")
		(net "P2E_CPU_ETH10G_RX_DP10")
	)
	(segment
		(start 24.007572 -10.570972)
		(end 24.327866 -10.250678)
		(width 0.1143)
		(layer "In9.Cu")
		(net "P2E_CPU_ETH10G_RX_DP10")
	)
	(segment
		(start 88.7349 -54.614572)
		(end 87.926672 -55.4228)
		(width 0.1016)
		(layer "In9.Cu")
		(net "P2E_CPU_ETH10G_RX_DP10")
	)
	(segment
		(start 87.926672 -55.4228)
		(end 87.139272 -55.4228)
		(width 0.1016)
		(layer "In9.Cu")
		(net "P2E_CPU_ETH10G_RX_DP10")
	)
	(segment
		(start 89.448386 -52.516786)
		(end 88.7349 -53.230272)
		(width 0.1016)
		(layer "In9.Cu")
		(net "P2E_CPU_ETH10G_RX_DP10")
	)
	(segment
		(start 52.4002 -40.5892)
		(end 51.4858 -39.6748)
		(width 0.1143)
		(layer "In9.Cu")
		(net "P2E_CPU_ETH10G_RX_DP10")
	)
	(segment
		(start 84.941156 -56.769)
		(end 84.695284 -57.014872)
		(width 0.1016)
		(layer "In9.Cu")
		(net "P2E_CPU_ETH10G_RX_DP10")
	)
	(segment
		(start 24.4983 -11.3665)
		(end 24.007572 -10.875772)
		(width 0.1143)
		(layer "In9.Cu")
		(net "P2E_CPU_ETH10G_RX_DP10")
	)
	(segment
		(start 50.0888 -39.6748)
		(end 49.0728 -38.6588)
		(width 0.1143)
		(layer "In9.Cu")
		(net "P2E_CPU_ETH10G_RX_DP10")
	)
	(segment
		(start 26.5176 -11.3665)
		(end 24.4983 -11.3665)
		(width 0.1143)
		(layer "In9.Cu")
		(net "P2E_CPU_ETH10G_RX_DP10")
	)
	(segment
		(start 84.605622 -57.014872)
		(end 82.019394 -59.6011)
		(width 0.1143)
		(layer "In9.Cu")
		(net "P2E_CPU_ETH10G_RX_DP10")
	)
	(segment
		(start 51.4858 -39.6748)
		(end 50.0888 -39.6748)
		(width 0.1143)
		(layer "In9.Cu")
		(net "P2E_CPU_ETH10G_RX_DP10")
	)
	(segment
		(start 85.793072 -56.769)
		(end 84.941156 -56.769)
		(width 0.1016)
		(layer "In9.Cu")
		(net "P2E_CPU_ETH10G_RX_DP10")
	)
	(segment
		(start 27.1018 -17.653)
		(end 27.1018 -15.402306)
		(width 0.1143)
		(layer "In9.Cu")
		(net "P2E_CPU_ETH10G_RX_DP10")
	)
	(segment
		(start 44.029122 -38.6588)
		(end 34.0106 -28.640278)
		(width 0.1143)
		(layer "In9.Cu")
		(net "P2E_CPU_ETH10G_RX_DP10")
	)
	(segment
		(start 89.82075 -48.77943)
		(end 89.448386 -49.151794)
		(width 0.1016)
		(layer "In9.Cu")
		(net "P2E_CPU_ETH10G_RX_DP10")
	)
	(segment
		(start 54.57825 -46.598078)
		(end 52.4002 -44.420028)
		(width 0.1143)
		(layer "In9.Cu")
		(net "P2E_CPU_ETH10G_RX_DP10")
	)
	(segment
		(start 54.57825 -48.043338)
		(end 54.57825 -46.598078)
		(width 0.1143)
		(layer "In9.Cu")
		(net "P2E_CPU_ETH10G_RX_DP10")
	)
	(segment
		(start 69.831966 -59.6011)
		(end 66.155316 -55.92445)
		(width 0.1143)
		(layer "In9.Cu")
		(net "P2E_CPU_ETH10G_RX_DP10")
	)
	(segment
		(start 27.3304 -15.173706)
		(end 27.3304 -13.553694)
		(width 0.1143)
		(layer "In9.Cu")
		(net "P2E_CPU_ETH10G_RX_DP10")
	)
	(segment
		(start 89.349326 -51.787044)
		(end 89.448386 -51.886104)
		(width 0.1016)
		(layer "In9.Cu")
		(net "P2E_CPU_ETH10G_RX_DP10")
	)
	(segment
		(start 90.122248 -49.164494)
		(end 89.82075 -49.465992)
		(width 0.1397)
		(layer "F.Cu")
		(net "P2E_CPU_ETH10G_RX_DN10")
	)
	(segment
		(start 23.349966 -6.195568)
		(end 23.349966 -8.027924)
		(width 0.1397)
		(layer "F.Cu")
		(net "P2E_CPU_ETH10G_RX_DN10")
	)
	(segment
		(start 23.678642 -9.980422)
		(end 23.408386 -10.250678)
		(width 0.1397)
		(layer "F.Cu")
		(net "P2E_CPU_ETH10G_RX_DN10")
	)
	(segment
		(start 89.82075 -49.465992)
		(end 89.82075 -49.54143)
		(width 0.1397)
		(layer "F.Cu")
		(net "P2E_CPU_ETH10G_RX_DN10")
	)
	(segment
		(start 23.678642 -8.3566)
		(end 23.678642 -9.980422)
		(width 0.1397)
		(layer "F.Cu")
		(net "P2E_CPU_ETH10G_RX_DN10")
	)
	(segment
		(start 23.349966 -8.027924)
		(end 23.678642 -8.3566)
		(width 0.1397)
		(layer "F.Cu")
		(net "P2E_CPU_ETH10G_RX_DN10")
	)
	(via
		(at 23.408386 -10.250678)
		(size 0.508)
		(drill 0.254)
		(layers "F.Cu" "B.Cu")
		(net "P2E_CPU_ETH10G_RX_DN10")
	)
	(via
		(at 89.82075 -49.54143)
		(size 0.4318)
		(drill 0.2032)
		(layers "F.Cu" "B.Cu")
		(net "P2E_CPU_ETH10G_RX_DN10")
	)
	(segment
		(start 84.93633 -57.061354)
		(end 84.93633 -57.15127)
		(width 0.1016)
		(layer "In9.Cu")
		(net "P2E_CPU_ETH10G_RX_DN10")
	)
	(segment
		(start 85.8774 -56.9722)
		(end 85.025484 -56.9722)
		(width 0.1016)
		(layer "In9.Cu")
		(net "P2E_CPU_ETH10G_RX_DN10")
	)
	(segment
		(start 89.651586 -52.601114)
		(end 88.9381 -53.3146)
		(width 0.1016)
		(layer "In9.Cu")
		(net "P2E_CPU_ETH10G_RX_DN10")
	)
	(segment
		(start 33.6804 -28.777184)
		(end 33.6804 -25.654)
		(width 0.1143)
		(layer "In9.Cu")
		(net "P2E_CPU_ETH10G_RX_DN10")
	)
	(segment
		(start 26.7716 -15.2654)
		(end 27.0002 -15.0368)
		(width 0.1143)
		(layer "In9.Cu")
		(net "P2E_CPU_ETH10G_RX_DN10")
	)
	(segment
		(start 89.82075 -49.54143)
		(end 89.651586 -49.710594)
		(width 0.1016)
		(layer "In9.Cu")
		(net "P2E_CPU_ETH10G_RX_DN10")
	)
	(segment
		(start 24.361394 -11.6967)
		(end 23.677372 -11.012678)
		(width 0.1143)
		(layer "In9.Cu")
		(net "P2E_CPU_ETH10G_RX_DN10")
	)
	(segment
		(start 48.935894 -38.989)
		(end 43.892216 -38.989)
		(width 0.1143)
		(layer "In9.Cu")
		(net "P2E_CPU_ETH10G_RX_DN10")
	)
	(segment
		(start 88.9381 -54.6989)
		(end 88.011 -55.626)
		(width 0.1016)
		(layer "In9.Cu")
		(net "P2E_CPU_ETH10G_RX_DN10")
	)
	(segment
		(start 32.745934 -24.719534)
		(end 32.745934 -23.76424)
		(width 0.1143)
		(layer "In9.Cu")
		(net "P2E_CPU_ETH10G_RX_DN10")
	)
	(segment
		(start 27.0002 -15.0368)
		(end 27.0002 -13.6906)
		(width 0.1143)
		(layer "In9.Cu")
		(net "P2E_CPU_ETH10G_RX_DN10")
	)
	(segment
		(start 26.72842 -12.044426)
		(end 26.380694 -11.6967)
		(width 0.1143)
		(layer "In9.Cu")
		(net "P2E_CPU_ETH10G_RX_DN10")
	)
	(segment
		(start 51.348894 -40.005)
		(end 49.951894 -40.005)
		(width 0.1143)
		(layer "In9.Cu")
		(net "P2E_CPU_ETH10G_RX_DN10")
	)
	(segment
		(start 82.1563 -59.9313)
		(end 69.69506 -59.9313)
		(width 0.1143)
		(layer "In9.Cu")
		(net "P2E_CPU_ETH10G_RX_DN10")
	)
	(segment
		(start 54.24805 -46.734984)
		(end 52.07 -44.556934)
		(width 0.1143)
		(layer "In9.Cu")
		(net "P2E_CPU_ETH10G_RX_DN10")
	)
	(segment
		(start 27.0002 -13.6906)
		(end 26.72842 -13.41882)
		(width 0.1143)
		(layer "In9.Cu")
		(net "P2E_CPU_ETH10G_RX_DN10")
	)
	(segment
		(start 84.839302 -57.248298)
		(end 82.1563 -59.9313)
		(width 0.1143)
		(layer "In9.Cu")
		(net "P2E_CPU_ETH10G_RX_DN10")
	)
	(segment
		(start 49.951894 -40.005)
		(end 48.935894 -38.989)
		(width 0.1143)
		(layer "In9.Cu")
		(net "P2E_CPU_ETH10G_RX_DN10")
	)
	(segment
		(start 87.2236 -55.626)
		(end 85.8774 -56.9722)
		(width 0.1016)
		(layer "In9.Cu")
		(net "P2E_CPU_ETH10G_RX_DN10")
	)
	(segment
		(start 33.6804 -25.654)
		(end 32.745934 -24.719534)
		(width 0.1143)
		(layer "In9.Cu")
		(net "P2E_CPU_ETH10G_RX_DN10")
	)
	(segment
		(start 26.380694 -11.6967)
		(end 24.361394 -11.6967)
		(width 0.1143)
		(layer "In9.Cu")
		(net "P2E_CPU_ETH10G_RX_DN10")
	)
	(segment
		(start 26.7716 -17.789906)
		(end 26.7716 -15.2654)
		(width 0.1143)
		(layer "In9.Cu")
		(net "P2E_CPU_ETH10G_RX_DN10")
	)
	(segment
		(start 85.025484 -56.9722)
		(end 84.93633 -57.061354)
		(width 0.1016)
		(layer "In9.Cu")
		(net "P2E_CPU_ETH10G_RX_DN10")
	)
	(segment
		(start 88.011 -55.626)
		(end 87.2236 -55.626)
		(width 0.1016)
		(layer "In9.Cu")
		(net "P2E_CPU_ETH10G_RX_DN10")
	)
	(segment
		(start 32.745934 -23.76424)
		(end 26.7716 -17.789906)
		(width 0.1143)
		(layer "In9.Cu")
		(net "P2E_CPU_ETH10G_RX_DN10")
	)
	(segment
		(start 89.651586 -49.710594)
		(end 89.651586 -52.601114)
		(width 0.1016)
		(layer "In9.Cu")
		(net "P2E_CPU_ETH10G_RX_DN10")
	)
	(segment
		(start 52.07 -44.556934)
		(end 52.07 -40.726106)
		(width 0.1143)
		(layer "In9.Cu")
		(net "P2E_CPU_ETH10G_RX_DN10")
	)
	(segment
		(start 84.93633 -57.15127)
		(end 84.839302 -57.248298)
		(width 0.1016)
		(layer "In9.Cu")
		(net "P2E_CPU_ETH10G_RX_DN10")
	)
	(segment
		(start 62.322456 -56.25465)
		(end 54.24805 -48.180244)
		(width 0.1143)
		(layer "In9.Cu")
		(net "P2E_CPU_ETH10G_RX_DN10")
	)
	(segment
		(start 66.01841 -56.25465)
		(end 62.322456 -56.25465)
		(width 0.1143)
		(layer "In9.Cu")
		(net "P2E_CPU_ETH10G_RX_DN10")
	)
	(segment
		(start 23.677372 -11.012678)
		(end 23.677372 -10.519664)
		(width 0.1143)
		(layer "In9.Cu")
		(net "P2E_CPU_ETH10G_RX_DN10")
	)
	(segment
		(start 43.892216 -38.989)
		(end 33.6804 -28.777184)
		(width 0.1143)
		(layer "In9.Cu")
		(net "P2E_CPU_ETH10G_RX_DN10")
	)
	(segment
		(start 52.07 -40.726106)
		(end 51.348894 -40.005)
		(width 0.1143)
		(layer "In9.Cu")
		(net "P2E_CPU_ETH10G_RX_DN10")
	)
	(segment
		(start 23.677372 -10.519664)
		(end 23.408386 -10.250678)
		(width 0.1143)
		(layer "In9.Cu")
		(net "P2E_CPU_ETH10G_RX_DN10")
	)
	(segment
		(start 54.24805 -48.180244)
		(end 54.24805 -46.734984)
		(width 0.1143)
		(layer "In9.Cu")
		(net "P2E_CPU_ETH10G_RX_DN10")
	)
	(segment
		(start 26.72842 -13.41882)
		(end 26.72842 -12.044426)
		(width 0.1143)
		(layer "In9.Cu")
		(net "P2E_CPU_ETH10G_RX_DN10")
	)
	(segment
		(start 88.9381 -53.3146)
		(end 88.9381 -54.6989)
		(width 0.1016)
		(layer "In9.Cu")
		(net "P2E_CPU_ETH10G_RX_DN10")
	)
	(segment
		(start 69.69506 -59.9313)
		(end 66.01841 -56.25465)
		(width 0.1143)
		(layer "In9.Cu")
		(net "P2E_CPU_ETH10G_RX_DN10")
	)
	(segment
		(start 19.678396 -8.3058)
		(end 19.678396 -9.980676)
		(width 0.1397)
		(layer "F.Cu")
		(net "P2E_CPU_ETH10G_RX_DN11")
	)
	(segment
		(start 19.349974 -6.195568)
		(end 19.349974 -7.977378)
		(width 0.1397)
		(layer "F.Cu")
		(net "P2E_CPU_ETH10G_RX_DN11")
	)
	(segment
		(start 19.349974 -7.977378)
		(end 19.678396 -8.3058)
		(width 0.1397)
		(layer "F.Cu")
		(net "P2E_CPU_ETH10G_RX_DN11")
	)
	(segment
		(start 19.678396 -9.980676)
		(end 19.408394 -10.250678)
		(width 0.1397)
		(layer "F.Cu")
		(net "P2E_CPU_ETH10G_RX_DN11")
	)
	(segment
		(start 90.738706 -49.545494)
		(end 90.5764 -49.7078)
		(width 0.1397)
		(layer "F.Cu")
		(net "P2E_CPU_ETH10G_RX_DN11")
	)
	(segment
		(start 91.407488 -49.545494)
		(end 90.738706 -49.545494)
		(width 0.1397)
		(layer "F.Cu")
		(net "P2E_CPU_ETH10G_RX_DN11")
	)
	(via
		(at 90.5764 -49.7078)
		(size 0.4318)
		(drill 0.2032)
		(layers "F.Cu" "B.Cu")
		(net "P2E_CPU_ETH10G_RX_DN11")
	)
	(via
		(at 19.408394 -10.250678)
		(size 0.508)
		(drill 0.254)
		(layers "F.Cu" "B.Cu")
		(net "P2E_CPU_ETH10G_RX_DN11")
	)
	(segment
		(start 52.26685 -46.101)
		(end 50.927 -46.101)
		(width 0.1143)
		(layer "In9.Cu")
		(net "P2E_CPU_ETH10G_RX_DN11")
	)
	(segment
		(start 85.6742 -58.937906)
		(end 83.258406 -61.3537)
		(width 0.1143)
		(layer "In9.Cu")
		(net "P2E_CPU_ETH10G_RX_DN11")
	)
	(segment
		(start 49.727612 -44.901612)
		(end 49.727612 -41.127934)
		(width 0.1143)
		(layer "In9.Cu")
		(net "P2E_CPU_ETH10G_RX_DN11")
	)
	(segment
		(start 90.4748 -54.364128)
		(end 88.730328 -56.1086)
		(width 0.1016)
		(layer "In9.Cu")
		(net "P2E_CPU_ETH10G_RX_DN11")
	)
	(segment
		(start 88.730328 -56.1086)
		(end 87.536528 -56.1086)
		(width 0.1016)
		(layer "In9.Cu")
		(net "P2E_CPU_ETH10G_RX_DN11")
	)
	(segment
		(start 22.547834 -11.4808)
		(end 20.124928 -11.4808)
		(width 0.1143)
		(layer "In9.Cu")
		(net "P2E_CPU_ETH10G_RX_DN11")
	)
	(segment
		(start 49.727612 -41.127934)
		(end 48.553878 -39.9542)
		(width 0.1143)
		(layer "In9.Cu")
		(net "P2E_CPU_ETH10G_RX_DN11")
	)
	(segment
		(start 85.6742 -58.06059)
		(end 85.6742 -58.937906)
		(width 0.1143)
		(layer "In9.Cu")
		(net "P2E_CPU_ETH10G_RX_DN11")
	)
	(segment
		(start 86.20887 -57.436258)
		(end 86.20887 -57.52592)
		(width 0.1016)
		(layer "In9.Cu")
		(net "P2E_CPU_ETH10G_RX_DN11")
	)
	(segment
		(start 87.536528 -56.1086)
		(end 86.20887 -57.436258)
		(width 0.1016)
		(layer "In9.Cu")
		(net "P2E_CPU_ETH10G_RX_DN11")
	)
	(segment
		(start 25.2984 -17.663922)
		(end 25.2984 -15.554706)
		(width 0.1143)
		(layer "In9.Cu")
		(net "P2E_CPU_ETH10G_RX_DN11")
	)
	(segment
		(start 54.369716 -50.18405)
		(end 53.29555 -49.109884)
		(width 0.1143)
		(layer "In9.Cu")
		(net "P2E_CPU_ETH10G_RX_DN11")
	)
	(segment
		(start 83.258406 -61.3537)
		(end 69.694044 -61.3537)
		(width 0.1143)
		(layer "In9.Cu")
		(net "P2E_CPU_ETH10G_RX_DN11")
	)
	(segment
		(start 90.39225 -49.89195)
		(end 90.39225 -50.264568)
		(width 0.1016)
		(layer "In9.Cu")
		(net "P2E_CPU_ETH10G_RX_DN11")
	)
	(segment
		(start 61.92647 -57.20715)
		(end 54.90337 -50.18405)
		(width 0.1143)
		(layer "In9.Cu")
		(net "P2E_CPU_ETH10G_RX_DN11")
	)
	(segment
		(start 90.7161 -50.588418)
		(end 90.7161 -53.1241)
		(width 0.1016)
		(layer "In9.Cu")
		(net "P2E_CPU_ETH10G_RX_DN11")
	)
	(segment
		(start 48.553878 -39.9542)
		(end 43.5102 -39.9542)
		(width 0.1143)
		(layer "In9.Cu")
		(net "P2E_CPU_ETH10G_RX_DN11")
	)
	(segment
		(start 43.5102 -39.9542)
		(end 32.7152 -29.1592)
		(width 0.1143)
		(layer "In9.Cu")
		(net "P2E_CPU_ETH10G_RX_DN11")
	)
	(segment
		(start 53.29555 -49.109884)
		(end 53.29555 -47.1297)
		(width 0.1143)
		(layer "In9.Cu")
		(net "P2E_CPU_ETH10G_RX_DN11")
	)
	(segment
		(start 90.7161 -53.1241)
		(end 90.4748 -53.3654)
		(width 0.1016)
		(layer "In9.Cu")
		(net "P2E_CPU_ETH10G_RX_DN11")
	)
	(segment
		(start 31.79318 -24.158702)
		(end 25.2984 -17.663922)
		(width 0.1143)
		(layer "In9.Cu")
		(net "P2E_CPU_ETH10G_RX_DN11")
	)
	(segment
		(start 19.703034 -11.058906)
		(end 19.703034 -10.545318)
		(width 0.1143)
		(layer "In9.Cu")
		(net "P2E_CPU_ETH10G_RX_DN11")
	)
	(segment
		(start 20.124928 -11.4808)
		(end 19.703034 -11.058906)
		(width 0.1143)
		(layer "In9.Cu")
		(net "P2E_CPU_ETH10G_RX_DN11")
	)
	(segment
		(start 32.7152 -29.1592)
		(end 32.7152 -26.036016)
		(width 0.1143)
		(layer "In9.Cu")
		(net "P2E_CPU_ETH10G_RX_DN11")
	)
	(segment
		(start 90.39225 -50.264568)
		(end 90.7161 -50.588418)
		(width 0.1016)
		(layer "In9.Cu")
		(net "P2E_CPU_ETH10G_RX_DN11")
	)
	(segment
		(start 32.7152 -26.036016)
		(end 31.79318 -25.113996)
		(width 0.1143)
		(layer "In9.Cu")
		(net "P2E_CPU_ETH10G_RX_DN11")
	)
	(segment
		(start 25.2984 -15.554706)
		(end 23.241 -13.497306)
		(width 0.1143)
		(layer "In9.Cu")
		(net "P2E_CPU_ETH10G_RX_DN11")
	)
	(segment
		(start 31.79318 -25.113996)
		(end 31.79318 -24.158702)
		(width 0.1143)
		(layer "In9.Cu")
		(net "P2E_CPU_ETH10G_RX_DN11")
	)
	(segment
		(start 19.703034 -10.545318)
		(end 19.408394 -10.250678)
		(width 0.1143)
		(layer "In9.Cu")
		(net "P2E_CPU_ETH10G_RX_DN11")
	)
	(segment
		(start 50.927 -46.101)
		(end 49.727612 -44.901612)
		(width 0.1143)
		(layer "In9.Cu")
		(net "P2E_CPU_ETH10G_RX_DN11")
	)
	(segment
		(start 90.4748 -53.3654)
		(end 90.4748 -54.364128)
		(width 0.1016)
		(layer "In9.Cu")
		(net "P2E_CPU_ETH10G_RX_DN11")
	)
	(segment
		(start 69.694044 -61.3537)
		(end 65.547494 -57.20715)
		(width 0.1143)
		(layer "In9.Cu")
		(net "P2E_CPU_ETH10G_RX_DN11")
	)
	(segment
		(start 65.547494 -57.20715)
		(end 61.92647 -57.20715)
		(width 0.1143)
		(layer "In9.Cu")
		(net "P2E_CPU_ETH10G_RX_DN11")
	)
	(segment
		(start 86.20887 -57.52592)
		(end 85.6742 -58.06059)
		(width 0.1143)
		(layer "In9.Cu")
		(net "P2E_CPU_ETH10G_RX_DN11")
	)
	(segment
		(start 54.90337 -50.18405)
		(end 54.369716 -50.18405)
		(width 0.1143)
		(layer "In9.Cu")
		(net "P2E_CPU_ETH10G_RX_DN11")
	)
	(segment
		(start 23.241 -12.173966)
		(end 22.547834 -11.4808)
		(width 0.1143)
		(layer "In9.Cu")
		(net "P2E_CPU_ETH10G_RX_DN11")
	)
	(segment
		(start 90.5764 -49.7078)
		(end 90.39225 -49.89195)
		(width 0.1016)
		(layer "In9.Cu")
		(net "P2E_CPU_ETH10G_RX_DN11")
	)
	(segment
		(start 23.241 -13.497306)
		(end 23.241 -12.173966)
		(width 0.1143)
		(layer "In9.Cu")
		(net "P2E_CPU_ETH10G_RX_DN11")
	)
	(segment
		(start 53.29555 -47.1297)
		(end 52.26685 -46.101)
		(width 0.1143)
		(layer "In9.Cu")
		(net "P2E_CPU_ETH10G_RX_DN11")
	)
	(segment
		(start 89.102184 -48.721518)
		(end 89.421208 -48.402494)
		(width 0.1397)
		(layer "F.Cu")
		(net "P2E_CPU_ETH10G_RX_DN9")
	)
	(segment
		(start 88.6714 -48.7426)
		(end 88.692482 -48.721518)
		(width 0.1397)
		(layer "F.Cu")
		(net "P2E_CPU_ETH10G_RX_DN9")
	)
	(segment
		(start 27.349958 -6.195568)
		(end 27.349958 -8.002778)
		(width 0.1397)
		(layer "F.Cu")
		(net "P2E_CPU_ETH10G_RX_DN9")
	)
	(segment
		(start 27.67838 -8.3312)
		(end 27.67838 -9.980676)
		(width 0.1397)
		(layer "F.Cu")
		(net "P2E_CPU_ETH10G_RX_DN9")
	)
	(segment
		(start 27.349958 -8.002778)
		(end 27.67838 -8.3312)
		(width 0.1397)
		(layer "F.Cu")
		(net "P2E_CPU_ETH10G_RX_DN9")
	)
	(segment
		(start 88.692482 -48.721518)
		(end 89.102184 -48.721518)
		(width 0.1397)
		(layer "F.Cu")
		(net "P2E_CPU_ETH10G_RX_DN9")
	)
	(segment
		(start 27.67838 -9.980676)
		(end 27.408378 -10.250678)
		(width 0.1397)
		(layer "F.Cu")
		(net "P2E_CPU_ETH10G_RX_DN9")
	)
	(via
		(at 27.408378 -10.250678)
		(size 0.508)
		(drill 0.254)
		(layers "F.Cu" "B.Cu")
		(net "P2E_CPU_ETH10G_RX_DN9")
	)
	(via
		(at 88.6714 -48.7426)
		(size 0.4318)
		(drill 0.2032)
		(layers "F.Cu" "B.Cu")
		(net "P2E_CPU_ETH10G_RX_DN9")
	)
	(segment
		(start 51.152044 -38.354)
		(end 50.50028 -38.354)
		(width 0.1143)
		(layer "In9.Cu")
		(net "P2E_CPU_ETH10G_RX_DN9")
	)
	(segment
		(start 88.416384 -48.976534)
		(end 88.416384 -51.791616)
		(width 0.1016)
		(layer "In9.Cu")
		(net "P2E_CPU_ETH10G_RX_DN9")
	)
	(segment
		(start 55.20055 -47.7774)
		(end 55.20055 -45.90034)
		(width 0.1143)
		(layer "In9.Cu")
		(net "P2E_CPU_ETH10G_RX_DN9")
	)
	(segment
		(start 59.894978 -52.479956)
		(end 59.894978 -52.042822)
		(width 0.1143)
		(layer "In9.Cu")
		(net "P2E_CPU_ETH10G_RX_DN9")
	)
	(segment
		(start 48.48098 -36.3347)
		(end 46.773084 -36.3347)
		(width 0.1143)
		(layer "In9.Cu")
		(net "P2E_CPU_ETH10G_RX_DN9")
	)
	(segment
		(start 29.662374 -16.2306)
		(end 28.844494 -16.2306)
		(width 0.1143)
		(layer "In9.Cu")
		(net "P2E_CPU_ETH10G_RX_DN9")
	)
	(segment
		(start 53.0225 -40.224456)
		(end 51.152044 -38.354)
		(width 0.1143)
		(layer "In9.Cu")
		(net "P2E_CPU_ETH10G_RX_DN9")
	)
	(segment
		(start 70.064376 -58.9534)
		(end 66.279776 -55.1688)
		(width 0.1143)
		(layer "In9.Cu")
		(net "P2E_CPU_ETH10G_RX_DN9")
	)
	(segment
		(start 86.4616 -55.557928)
		(end 85.631528 -56.388)
		(width 0.1016)
		(layer "In9.Cu")
		(net "P2E_CPU_ETH10G_RX_DN9")
	)
	(segment
		(start 86.9442 -53.2638)
		(end 86.9442 -53.830728)
		(width 0.1016)
		(layer "In9.Cu")
		(net "P2E_CPU_ETH10G_RX_DN9")
	)
	(segment
		(start 85.631528 -56.388)
		(end 84.553044 -56.388)
		(width 0.1016)
		(layer "In9.Cu")
		(net "P2E_CPU_ETH10G_RX_DN9")
	)
	(segment
		(start 37.366702 -26.607008)
		(end 37.366702 -23.934928)
		(width 0.1143)
		(layer "In9.Cu")
		(net "P2E_CPU_ETH10G_RX_DN9")
	)
	(segment
		(start 88.650318 -48.7426)
		(end 88.416384 -48.976534)
		(width 0.1016)
		(layer "In9.Cu")
		(net "P2E_CPU_ETH10G_RX_DN9")
	)
	(segment
		(start 38.9382 -30.464506)
		(end 38.9382 -28.178506)
		(width 0.1143)
		(layer "In9.Cu")
		(net "P2E_CPU_ETH10G_RX_DN9")
	)
	(segment
		(start 84.167472 -56.863234)
		(end 82.077306 -58.9534)
		(width 0.1143)
		(layer "In9.Cu")
		(net "P2E_CPU_ETH10G_RX_DN9")
	)
	(segment
		(start 37.366702 -23.934928)
		(end 29.662374 -16.2306)
		(width 0.1143)
		(layer "In9.Cu")
		(net "P2E_CPU_ETH10G_RX_DN9")
	)
	(segment
		(start 88.6714 -48.7426)
		(end 88.650318 -48.7426)
		(width 0.1016)
		(layer "In9.Cu")
		(net "P2E_CPU_ETH10G_RX_DN9")
	)
	(segment
		(start 28.3464 -15.732506)
		(end 28.3464 -13.319506)
		(width 0.1143)
		(layer "In9.Cu")
		(net "P2E_CPU_ETH10G_RX_DN9")
	)
	(segment
		(start 82.077306 -58.9534)
		(end 70.064376 -58.9534)
		(width 0.1143)
		(layer "In9.Cu")
		(net "P2E_CPU_ETH10G_RX_DN9")
	)
	(segment
		(start 27.703018 -10.545318)
		(end 27.408378 -10.250678)
		(width 0.1143)
		(layer "In9.Cu")
		(net "P2E_CPU_ETH10G_RX_DN9")
	)
	(segment
		(start 84.185506 -56.8452)
		(end 84.167472 -56.863234)
		(width 0.1016)
		(layer "In9.Cu")
		(net "P2E_CPU_ETH10G_RX_DN9")
	)
	(segment
		(start 28.844494 -16.2306)
		(end 28.3464 -15.732506)
		(width 0.1143)
		(layer "In9.Cu")
		(net "P2E_CPU_ETH10G_RX_DN9")
	)
	(segment
		(start 84.553044 -56.388)
		(end 84.185252 -56.755792)
		(width 0.1016)
		(layer "In9.Cu")
		(net "P2E_CPU_ETH10G_RX_DN9")
	)
	(segment
		(start 84.185252 -56.755792)
		(end 84.185252 -56.844692)
		(width 0.1016)
		(layer "In9.Cu")
		(net "P2E_CPU_ETH10G_RX_DN9")
	)
	(segment
		(start 46.277784 -35.8394)
		(end 44.313094 -35.8394)
		(width 0.1143)
		(layer "In9.Cu")
		(net "P2E_CPU_ETH10G_RX_DN9")
	)
	(segment
		(start 86.4616 -54.313328)
		(end 86.4616 -55.557928)
		(width 0.1016)
		(layer "In9.Cu")
		(net "P2E_CPU_ETH10G_RX_DN9")
	)
	(segment
		(start 66.279776 -55.1688)
		(end 62.583822 -55.1688)
		(width 0.1143)
		(layer "In9.Cu")
		(net "P2E_CPU_ETH10G_RX_DN9")
	)
	(segment
		(start 55.20055 -45.90034)
		(end 53.0225 -43.72229)
		(width 0.1143)
		(layer "In9.Cu")
		(net "P2E_CPU_ETH10G_RX_DN9")
	)
	(segment
		(start 46.773084 -36.3347)
		(end 46.277784 -35.8394)
		(width 0.1143)
		(layer "In9.Cu")
		(net "P2E_CPU_ETH10G_RX_DN9")
	)
	(segment
		(start 27.703018 -12.676124)
		(end 27.703018 -10.545318)
		(width 0.1143)
		(layer "In9.Cu")
		(net "P2E_CPU_ETH10G_RX_DN9")
	)
	(segment
		(start 86.9442 -53.830728)
		(end 86.4616 -54.313328)
		(width 0.1016)
		(layer "In9.Cu")
		(net "P2E_CPU_ETH10G_RX_DN9")
	)
	(segment
		(start 28.3464 -13.319506)
		(end 27.703018 -12.676124)
		(width 0.1143)
		(layer "In9.Cu")
		(net "P2E_CPU_ETH10G_RX_DN9")
	)
	(segment
		(start 44.313094 -35.8394)
		(end 38.9382 -30.464506)
		(width 0.1143)
		(layer "In9.Cu")
		(net "P2E_CPU_ETH10G_RX_DN9")
	)
	(segment
		(start 53.0225 -43.72229)
		(end 53.0225 -40.224456)
		(width 0.1143)
		(layer "In9.Cu")
		(net "P2E_CPU_ETH10G_RX_DN9")
	)
	(segment
		(start 84.185506 -56.844946)
		(end 84.185506 -56.8452)
		(width 0.1016)
		(layer "In9.Cu")
		(net "P2E_CPU_ETH10G_RX_DN9")
	)
	(segment
		(start 59.894978 -52.042822)
		(end 59.141106 -51.28895)
		(width 0.1143)
		(layer "In9.Cu")
		(net "P2E_CPU_ETH10G_RX_DN9")
	)
	(segment
		(start 38.9382 -28.178506)
		(end 37.366702 -26.607008)
		(width 0.1143)
		(layer "In9.Cu")
		(net "P2E_CPU_ETH10G_RX_DN9")
	)
	(segment
		(start 62.583822 -55.1688)
		(end 59.894978 -52.479956)
		(width 0.1143)
		(layer "In9.Cu")
		(net "P2E_CPU_ETH10G_RX_DN9")
	)
	(segment
		(start 88.416384 -51.791616)
		(end 86.9442 -53.2638)
		(width 0.1016)
		(layer "In9.Cu")
		(net "P2E_CPU_ETH10G_RX_DN9")
	)
	(segment
		(start 84.185252 -56.844692)
		(end 84.185506 -56.844946)
		(width 0.1016)
		(layer "In9.Cu")
		(net "P2E_CPU_ETH10G_RX_DN9")
	)
	(segment
		(start 50.50028 -38.354)
		(end 48.48098 -36.3347)
		(width 0.1143)
		(layer "In9.Cu")
		(net "P2E_CPU_ETH10G_RX_DN9")
	)
	(segment
		(start 58.7121 -51.28895)
		(end 55.20055 -47.7774)
		(width 0.1143)
		(layer "In9.Cu")
		(net "P2E_CPU_ETH10G_RX_DN9")
	)
	(segment
		(start 59.141106 -51.28895)
		(end 58.7121 -51.28895)
		(width 0.1143)
		(layer "In9.Cu")
		(net "P2E_CPU_ETH10G_RX_DN9")
	)
	(segment
		(start 28.349956 -6.195568)
		(end 28.349956 -7.977124)
		(width 0.1397)
		(layer "F.Cu")
		(net "P2E_CPU_ETH10G_RX_DP9")
	)
	(segment
		(start 89.421208 -47.640494)
		(end 88.877902 -48.1838)
		(width 0.1397)
		(layer "F.Cu")
		(net "P2E_CPU_ETH10G_RX_DP9")
	)
	(segment
		(start 28.02128 -9.9441)
		(end 28.327858 -10.250678)
		(width 0.1397)
		(layer "F.Cu")
		(net "P2E_CPU_ETH10G_RX_DP9")
	)
	(segment
		(start 28.02128 -8.3058)
		(end 28.02128 -9.9441)
		(width 0.1397)
		(layer "F.Cu")
		(net "P2E_CPU_ETH10G_RX_DP9")
	)
	(segment
		(start 28.349956 -7.977124)
		(end 28.02128 -8.3058)
		(width 0.1397)
		(layer "F.Cu")
		(net "P2E_CPU_ETH10G_RX_DP9")
	)
	(segment
		(start 88.877902 -48.1838)
		(end 88.6714 -48.1838)
		(width 0.1397)
		(layer "F.Cu")
		(net "P2E_CPU_ETH10G_RX_DP9")
	)
	(via
		(at 28.327858 -10.250678)
		(size 0.508)
		(drill 0.254)
		(layers "F.Cu" "B.Cu")
		(net "P2E_CPU_ETH10G_RX_DP9")
	)
	(via
		(at 88.6714 -48.1838)
		(size 0.4318)
		(drill 0.2032)
		(layers "F.Cu" "B.Cu")
		(net "P2E_CPU_ETH10G_RX_DP9")
	)
	(segment
		(start 59.278012 -50.95875)
		(end 58.849006 -50.95875)
		(width 0.1143)
		(layer "In9.Cu")
		(net "P2E_CPU_ETH10G_RX_DP9")
	)
	(segment
		(start 46.41469 -35.5092)
		(end 44.45 -35.5092)
		(width 0.1143)
		(layer "In9.Cu")
		(net "P2E_CPU_ETH10G_RX_DP9")
	)
	(segment
		(start 88.213184 -48.642016)
		(end 88.213184 -49.741836)
		(width 0.1016)
		(layer "In9.Cu")
		(net "P2E_CPU_ETH10G_RX_DP9")
	)
	(segment
		(start 86.741 -53.179472)
		(end 86.741 -53.7464)
		(width 0.1016)
		(layer "In9.Cu")
		(net "P2E_CPU_ETH10G_RX_DP9")
	)
	(segment
		(start 50.637186 -38.0238)
		(end 48.617886 -36.0045)
		(width 0.1143)
		(layer "In9.Cu")
		(net "P2E_CPU_ETH10G_RX_DP9")
	)
	(segment
		(start 51.28895 -38.0238)
		(end 50.637186 -38.0238)
		(width 0.1143)
		(layer "In9.Cu")
		(net "P2E_CPU_ETH10G_RX_DP9")
	)
	(segment
		(start 29.79928 -15.9004)
		(end 28.9814 -15.9004)
		(width 0.1143)
		(layer "In9.Cu")
		(net "P2E_CPU_ETH10G_RX_DP9")
	)
	(segment
		(start 44.45 -35.5092)
		(end 39.2684 -30.3276)
		(width 0.1143)
		(layer "In9.Cu")
		(net "P2E_CPU_ETH10G_RX_DP9")
	)
	(segment
		(start 55.53075 -45.763434)
		(end 53.3527 -43.585384)
		(width 0.1143)
		(layer "In9.Cu")
		(net "P2E_CPU_ETH10G_RX_DP9")
	)
	(segment
		(start 88.213184 -50.244756)
		(end 88.213184 -51.707288)
		(width 0.1016)
		(layer "In9.Cu")
		(net "P2E_CPU_ETH10G_RX_DP9")
	)
	(segment
		(start 39.2684 -30.3276)
		(end 39.2684 -28.0416)
		(width 0.1143)
		(layer "In9.Cu")
		(net "P2E_CPU_ETH10G_RX_DP9")
	)
	(segment
		(start 88.114124 -49.840896)
		(end 88.114124 -50.145696)
		(width 0.1016)
		(layer "In9.Cu")
		(net "P2E_CPU_ETH10G_RX_DP9")
	)
	(segment
		(start 83.934046 -56.629554)
		(end 81.9404 -58.6232)
		(width 0.1143)
		(layer "In9.Cu")
		(net "P2E_CPU_ETH10G_RX_DP9")
	)
	(segment
		(start 37.696902 -26.470102)
		(end 37.696902 -23.798022)
		(width 0.1143)
		(layer "In9.Cu")
		(net "P2E_CPU_ETH10G_RX_DP9")
	)
	(segment
		(start 28.033218 -12.539218)
		(end 28.033218 -12.05103)
		(width 0.1143)
		(layer "In9.Cu")
		(net "P2E_CPU_ETH10G_RX_DP9")
	)
	(segment
		(start 46.90999 -36.0045)
		(end 46.41469 -35.5092)
		(width 0.1143)
		(layer "In9.Cu")
		(net "P2E_CPU_ETH10G_RX_DP9")
	)
	(segment
		(start 39.2684 -28.0416)
		(end 37.696902 -26.470102)
		(width 0.1143)
		(layer "In9.Cu")
		(net "P2E_CPU_ETH10G_RX_DP9")
	)
	(segment
		(start 86.741 -53.7464)
		(end 86.2584 -54.229)
		(width 0.1016)
		(layer "In9.Cu")
		(net "P2E_CPU_ETH10G_RX_DP9")
	)
	(segment
		(start 60.225178 -52.34305)
		(end 60.225178 -51.905916)
		(width 0.1143)
		(layer "In9.Cu")
		(net "P2E_CPU_ETH10G_RX_DP9")
	)
	(segment
		(start 28.033218 -10.545318)
		(end 28.327858 -10.250678)
		(width 0.1143)
		(layer "In9.Cu")
		(net "P2E_CPU_ETH10G_RX_DP9")
	)
	(segment
		(start 37.696902 -23.798022)
		(end 29.79928 -15.9004)
		(width 0.1143)
		(layer "In9.Cu")
		(net "P2E_CPU_ETH10G_RX_DP9")
	)
	(segment
		(start 55.53075 -47.640494)
		(end 55.53075 -45.763434)
		(width 0.1143)
		(layer "In9.Cu")
		(net "P2E_CPU_ETH10G_RX_DP9")
	)
	(segment
		(start 86.2584 -55.4736)
		(end 85.5472 -56.1848)
		(width 0.1016)
		(layer "In9.Cu")
		(net "P2E_CPU_ETH10G_RX_DP9")
	)
	(segment
		(start 88.114124 -50.145696)
		(end 88.213184 -50.244756)
		(width 0.1016)
		(layer "In9.Cu")
		(net "P2E_CPU_ETH10G_RX_DP9")
	)
	(segment
		(start 48.617886 -36.0045)
		(end 46.90999 -36.0045)
		(width 0.1143)
		(layer "In9.Cu")
		(net "P2E_CPU_ETH10G_RX_DP9")
	)
	(segment
		(start 88.213184 -51.707288)
		(end 86.741 -53.179472)
		(width 0.1016)
		(layer "In9.Cu")
		(net "P2E_CPU_ETH10G_RX_DP9")
	)
	(segment
		(start 84.468716 -56.1848)
		(end 84.041996 -56.61152)
		(width 0.1016)
		(layer "In9.Cu")
		(net "P2E_CPU_ETH10G_RX_DP9")
	)
	(segment
		(start 58.849006 -50.95875)
		(end 55.53075 -47.640494)
		(width 0.1143)
		(layer "In9.Cu")
		(net "P2E_CPU_ETH10G_RX_DP9")
	)
	(segment
		(start 62.720728 -54.8386)
		(end 60.225178 -52.34305)
		(width 0.1143)
		(layer "In9.Cu")
		(net "P2E_CPU_ETH10G_RX_DP9")
	)
	(segment
		(start 53.3527 -43.585384)
		(end 53.3527 -40.08755)
		(width 0.1143)
		(layer "In9.Cu")
		(net "P2E_CPU_ETH10G_RX_DP9")
	)
	(segment
		(start 28.033218 -12.05103)
		(end 28.246578 -11.83767)
		(width 0.1143)
		(layer "In9.Cu")
		(net "P2E_CPU_ETH10G_RX_DP9")
	)
	(segment
		(start 28.6766 -15.5956)
		(end 28.6766 -13.1826)
		(width 0.1143)
		(layer "In9.Cu")
		(net "P2E_CPU_ETH10G_RX_DP9")
	)
	(segment
		(start 86.2584 -54.229)
		(end 86.2584 -55.4736)
		(width 0.1016)
		(layer "In9.Cu")
		(net "P2E_CPU_ETH10G_RX_DP9")
	)
	(segment
		(start 28.033218 -11.28141)
		(end 28.033218 -10.545318)
		(width 0.1143)
		(layer "In9.Cu")
		(net "P2E_CPU_ETH10G_RX_DP9")
	)
	(segment
		(start 84.041996 -56.61152)
		(end 83.95208 -56.61152)
		(width 0.1016)
		(layer "In9.Cu")
		(net "P2E_CPU_ETH10G_RX_DP9")
	)
	(segment
		(start 53.3527 -40.08755)
		(end 51.28895 -38.0238)
		(width 0.1143)
		(layer "In9.Cu")
		(net "P2E_CPU_ETH10G_RX_DP9")
	)
	(segment
		(start 85.5472 -56.1848)
		(end 84.468716 -56.1848)
		(width 0.1016)
		(layer "In9.Cu")
		(net "P2E_CPU_ETH10G_RX_DP9")
	)
	(segment
		(start 28.9814 -15.9004)
		(end 28.6766 -15.5956)
		(width 0.1143)
		(layer "In9.Cu")
		(net "P2E_CPU_ETH10G_RX_DP9")
	)
	(segment
		(start 28.246578 -11.49477)
		(end 28.033218 -11.28141)
		(width 0.1143)
		(layer "In9.Cu")
		(net "P2E_CPU_ETH10G_RX_DP9")
	)
	(segment
		(start 83.95208 -56.61152)
		(end 83.934046 -56.629554)
		(width 0.1016)
		(layer "In9.Cu")
		(net "P2E_CPU_ETH10G_RX_DP9")
	)
	(segment
		(start 88.213184 -49.741836)
		(end 88.114124 -49.840896)
		(width 0.1016)
		(layer "In9.Cu")
		(net "P2E_CPU_ETH10G_RX_DP9")
	)
	(segment
		(start 88.6714 -48.1838)
		(end 88.213184 -48.642016)
		(width 0.1016)
		(layer "In9.Cu")
		(net "P2E_CPU_ETH10G_RX_DP9")
	)
	(segment
		(start 28.246578 -11.83767)
		(end 28.246578 -11.49477)
		(width 0.1143)
		(layer "In9.Cu")
		(net "P2E_CPU_ETH10G_RX_DP9")
	)
	(segment
		(start 60.225178 -51.905916)
		(end 59.278012 -50.95875)
		(width 0.1143)
		(layer "In9.Cu")
		(net "P2E_CPU_ETH10G_RX_DP9")
	)
	(segment
		(start 66.416682 -54.8386)
		(end 62.720728 -54.8386)
		(width 0.1143)
		(layer "In9.Cu")
		(net "P2E_CPU_ETH10G_RX_DP9")
	)
	(segment
		(start 81.9404 -58.6232)
		(end 70.201282 -58.6232)
		(width 0.1143)
		(layer "In9.Cu")
		(net "P2E_CPU_ETH10G_RX_DP9")
	)
	(segment
		(start 28.6766 -13.1826)
		(end 28.033218 -12.539218)
		(width 0.1143)
		(layer "In9.Cu")
		(net "P2E_CPU_ETH10G_RX_DP9")
	)
	(segment
		(start 70.201282 -58.6232)
		(end 66.416682 -54.8386)
		(width 0.1143)
		(layer "In9.Cu")
		(net "P2E_CPU_ETH10G_RX_DP9")
	)
	(segment
		(start 87.781384 -49.166018)
		(end 87.757762 -49.142396)
		(width 0.1397)
		(layer "F.Cu")
		(net "P2E_CPU_ETH10G_RX_DN8")
	)
	(segment
		(start 31.34995 -7.977124)
		(end 31.678626 -8.3058)
		(width 0.1397)
		(layer "F.Cu")
		(net "P2E_CPU_ETH10G_RX_DN8")
	)
	(segment
		(start 88.135968 -49.545494)
		(end 87.781384 -49.19091)
		(width 0.1397)
		(layer "F.Cu")
		(net "P2E_CPU_ETH10G_RX_DN8")
	)
	(segment
		(start 31.678626 -9.980422)
		(end 31.40837 -10.250678)
		(width 0.1397)
		(layer "F.Cu")
		(net "P2E_CPU_ETH10G_RX_DN8")
	)
	(segment
		(start 31.34995 -6.195568)
		(end 31.34995 -7.977124)
		(width 0.1397)
		(layer "F.Cu")
		(net "P2E_CPU_ETH10G_RX_DN8")
	)
	(segment
		(start 31.678626 -8.3058)
		(end 31.678626 -9.980422)
		(width 0.1397)
		(layer "F.Cu")
		(net "P2E_CPU_ETH10G_RX_DN8")
	)
	(segment
		(start 87.781384 -49.19091)
		(end 87.781384 -49.166018)
		(width 0.1397)
		(layer "F.Cu")
		(net "P2E_CPU_ETH10G_RX_DN8")
	)
	(via
		(at 31.40837 -10.250678)
		(size 0.508)
		(drill 0.254)
		(layers "F.Cu" "B.Cu")
		(net "P2E_CPU_ETH10G_RX_DN8")
	)
	(via
		(at 87.757762 -49.142396)
		(size 0.4318)
		(drill 0.2032)
		(layers "F.Cu" "B.Cu")
		(net "P2E_CPU_ETH10G_RX_DN8")
	)
	(segment
		(start 54.813708 -44.166282)
		(end 54.813708 -39.838122)
		(width 0.1143)
		(layer "In9.Cu")
		(net "P2E_CPU_ETH10G_RX_DN8")
	)
	(segment
		(start 65.5066 -53.6448)
		(end 62.844172 -53.6448)
		(width 0.1143)
		(layer "In9.Cu")
		(net "P2E_CPU_ETH10G_RX_DN8")
	)
	(segment
		(start 32.55137 -16.7894)
		(end 31.70301 -15.94104)
		(width 0.1143)
		(layer "In9.Cu")
		(net "P2E_CPU_ETH10G_RX_DN8")
	)
	(segment
		(start 87.592662 -50.459132)
		(end 87.1093 -50.942494)
		(width 0.1016)
		(layer "In9.Cu")
		(net "P2E_CPU_ETH10G_RX_DN8")
	)
	(segment
		(start 59.535822 -50.33645)
		(end 59.106816 -50.33645)
		(width 0.1143)
		(layer "In9.Cu")
		(net "P2E_CPU_ETH10G_RX_DN8")
	)
	(segment
		(start 59.106816 -50.33645)
		(end 56.15305 -47.382684)
		(width 0.1143)
		(layer "In9.Cu")
		(net "P2E_CPU_ETH10G_RX_DN8")
	)
	(segment
		(start 82.000344 -58.0009)
		(end 72.029066 -58.0009)
		(width 0.1143)
		(layer "In9.Cu")
		(net "P2E_CPU_ETH10G_RX_DN8")
	)
	(segment
		(start 66.0781 -54.2163)
		(end 65.5066 -53.6448)
		(width 0.1143)
		(layer "In9.Cu")
		(net "P2E_CPU_ETH10G_RX_DN8")
	)
	(segment
		(start 56.15305 -47.382684)
		(end 56.15305 -45.505624)
		(width 0.1143)
		(layer "In9.Cu")
		(net "P2E_CPU_ETH10G_RX_DN8")
	)
	(segment
		(start 87.592662 -49.307496)
		(end 87.592662 -50.459132)
		(width 0.1016)
		(layer "In9.Cu")
		(net "P2E_CPU_ETH10G_RX_DN8")
	)
	(segment
		(start 83.110578 -56.890666)
		(end 82.000344 -58.0009)
		(width 0.1143)
		(layer "In9.Cu")
		(net "P2E_CPU_ETH10G_RX_DN8")
	)
	(segment
		(start 56.15305 -45.505624)
		(end 54.813708 -44.166282)
		(width 0.1143)
		(layer "In9.Cu")
		(net "P2E_CPU_ETH10G_RX_DN8")
	)
	(segment
		(start 31.70301 -10.545318)
		(end 31.40837 -10.250678)
		(width 0.1143)
		(layer "In9.Cu")
		(net "P2E_CPU_ETH10G_RX_DN8")
	)
	(segment
		(start 87.757762 -49.142396)
		(end 87.592662 -49.307496)
		(width 0.1016)
		(layer "In9.Cu")
		(net "P2E_CPU_ETH10G_RX_DN8")
	)
	(segment
		(start 87.1093 -51.151028)
		(end 85.1662 -53.094128)
		(width 0.1016)
		(layer "In9.Cu")
		(net "P2E_CPU_ETH10G_RX_DN8")
	)
	(segment
		(start 31.70301 -15.94104)
		(end 31.70301 -10.545318)
		(width 0.1143)
		(layer "In9.Cu")
		(net "P2E_CPU_ETH10G_RX_DN8")
	)
	(segment
		(start 85.1662 -53.094128)
		(end 85.1662 -54.745128)
		(width 0.1016)
		(layer "In9.Cu")
		(net "P2E_CPU_ETH10G_RX_DN8")
	)
	(segment
		(start 40.8432 -27.349704)
		(end 40.8432 -24.254206)
		(width 0.1143)
		(layer "In9.Cu")
		(net "P2E_CPU_ETH10G_RX_DN8")
	)
	(segment
		(start 54.813708 -39.838122)
		(end 52.377086 -37.4015)
		(width 0.1143)
		(layer "In9.Cu")
		(net "P2E_CPU_ETH10G_RX_DN8")
	)
	(segment
		(start 40.8432 -24.254206)
		(end 39.042594 -22.4536)
		(width 0.1143)
		(layer "In9.Cu")
		(net "P2E_CPU_ETH10G_RX_DN8")
	)
	(segment
		(start 72.029066 -58.0009)
		(end 69.958966 -55.9308)
		(width 0.1143)
		(layer "In9.Cu")
		(net "P2E_CPU_ETH10G_RX_DN8")
	)
	(segment
		(start 52.377086 -37.4015)
		(end 50.894996 -37.4015)
		(width 0.1143)
		(layer "In9.Cu")
		(net "P2E_CPU_ETH10G_RX_DN8")
	)
	(segment
		(start 45.6946 -32.201104)
		(end 40.8432 -27.349704)
		(width 0.1143)
		(layer "In9.Cu")
		(net "P2E_CPU_ETH10G_RX_DN8")
	)
	(segment
		(start 85.1662 -54.745128)
		(end 83.128358 -56.78297)
		(width 0.1016)
		(layer "In9.Cu")
		(net "P2E_CPU_ETH10G_RX_DN8")
	)
	(segment
		(start 62.844172 -53.6448)
		(end 59.535822 -50.33645)
		(width 0.1143)
		(layer "In9.Cu")
		(net "P2E_CPU_ETH10G_RX_DN8")
	)
	(segment
		(start 83.128358 -56.872886)
		(end 83.110578 -56.890666)
		(width 0.1016)
		(layer "In9.Cu")
		(net "P2E_CPU_ETH10G_RX_DN8")
	)
	(segment
		(start 50.894996 -37.4015)
		(end 48.875696 -35.3822)
		(width 0.1143)
		(layer "In9.Cu")
		(net "P2E_CPU_ETH10G_RX_DN8")
	)
	(segment
		(start 45.6946 -33.909)
		(end 45.6946 -32.201104)
		(width 0.1143)
		(layer "In9.Cu")
		(net "P2E_CPU_ETH10G_RX_DN8")
	)
	(segment
		(start 38.582854 -22.4536)
		(end 32.918654 -16.7894)
		(width 0.1143)
		(layer "In9.Cu")
		(net "P2E_CPU_ETH10G_RX_DN8")
	)
	(segment
		(start 67.318128 -54.2163)
		(end 66.0781 -54.2163)
		(width 0.1143)
		(layer "In9.Cu")
		(net "P2E_CPU_ETH10G_RX_DN8")
	)
	(segment
		(start 87.1093 -50.942494)
		(end 87.1093 -51.151028)
		(width 0.1016)
		(layer "In9.Cu")
		(net "P2E_CPU_ETH10G_RX_DN8")
	)
	(segment
		(start 39.042594 -22.4536)
		(end 38.582854 -22.4536)
		(width 0.1143)
		(layer "In9.Cu")
		(net "P2E_CPU_ETH10G_RX_DN8")
	)
	(segment
		(start 32.918654 -16.7894)
		(end 32.55137 -16.7894)
		(width 0.1143)
		(layer "In9.Cu")
		(net "P2E_CPU_ETH10G_RX_DN8")
	)
	(segment
		(start 47.1678 -35.3822)
		(end 45.6946 -33.909)
		(width 0.1143)
		(layer "In9.Cu")
		(net "P2E_CPU_ETH10G_RX_DN8")
	)
	(segment
		(start 48.875696 -35.3822)
		(end 47.1678 -35.3822)
		(width 0.1143)
		(layer "In9.Cu")
		(net "P2E_CPU_ETH10G_RX_DN8")
	)
	(segment
		(start 83.128358 -56.78297)
		(end 83.128358 -56.872886)
		(width 0.1016)
		(layer "In9.Cu")
		(net "P2E_CPU_ETH10G_RX_DN8")
	)
	(segment
		(start 69.032628 -55.9308)
		(end 67.318128 -54.2163)
		(width 0.1143)
		(layer "In9.Cu")
		(net "P2E_CPU_ETH10G_RX_DN8")
	)
	(segment
		(start 69.958966 -55.9308)
		(end 69.032628 -55.9308)
		(width 0.1143)
		(layer "In9.Cu")
		(net "P2E_CPU_ETH10G_RX_DN8")
	)
	(segment
		(start 32.021526 -9.944354)
		(end 32.32785 -10.250678)
		(width 0.1397)
		(layer "F.Cu")
		(net "P2E_CPU_ETH10G_RX_DP8")
	)
	(segment
		(start 32.349948 -6.195568)
		(end 32.349948 -8.002778)
		(width 0.1397)
		(layer "F.Cu")
		(net "P2E_CPU_ETH10G_RX_DP8")
	)
	(segment
		(start 32.021526 -8.3312)
		(end 32.021526 -9.944354)
		(width 0.1397)
		(layer "F.Cu")
		(net "P2E_CPU_ETH10G_RX_DP8")
	)
	(segment
		(start 87.757 -48.388016)
		(end 87.757 -48.387)
		(width 0.1397)
		(layer "F.Cu")
		(net "P2E_CPU_ETH10G_RX_DP8")
	)
	(segment
		(start 88.135968 -48.783494)
		(end 88.135968 -48.766984)
		(width 0.1397)
		(layer "F.Cu")
		(net "P2E_CPU_ETH10G_RX_DP8")
	)
	(segment
		(start 88.135968 -48.766984)
		(end 87.757 -48.388016)
		(width 0.1397)
		(layer "F.Cu")
		(net "P2E_CPU_ETH10G_RX_DP8")
	)
	(segment
		(start 32.349948 -8.002778)
		(end 32.021526 -8.3312)
		(width 0.1397)
		(layer "F.Cu")
		(net "P2E_CPU_ETH10G_RX_DP8")
	)
	(via
		(at 32.32785 -10.250678)
		(size 0.508)
		(drill 0.254)
		(layers "F.Cu" "B.Cu")
		(net "P2E_CPU_ETH10G_RX_DP8")
	)
	(via
		(at 87.757 -48.387)
		(size 0.4318)
		(drill 0.2032)
		(layers "F.Cu" "B.Cu")
		(net "P2E_CPU_ETH10G_RX_DP8")
	)
	(segment
		(start 72.165972 -57.6707)
		(end 70.095872 -55.6006)
		(width 0.1143)
		(layer "In9.Cu")
		(net "P2E_CPU_ETH10G_RX_DP8")
	)
	(segment
		(start 33.05556 -16.4592)
		(end 32.688276 -16.4592)
		(width 0.1143)
		(layer "In9.Cu")
		(net "P2E_CPU_ETH10G_RX_DP8")
	)
	(segment
		(start 84.391754 -55.231284)
		(end 84.176362 -55.44693)
		(width 0.1016)
		(layer "In9.Cu")
		(net "P2E_CPU_ETH10G_RX_DP8")
	)
	(segment
		(start 51.031902 -37.0713)
		(end 49.012602 -35.052)
		(width 0.1143)
		(layer "In9.Cu")
		(net "P2E_CPU_ETH10G_RX_DP8")
	)
	(segment
		(start 84.86394 -53.90134)
		(end 84.86394 -54.20614)
		(width 0.1016)
		(layer "In9.Cu")
		(net "P2E_CPU_ETH10G_RX_DP8")
	)
	(segment
		(start 39.1795 -22.1234)
		(end 38.71976 -22.1234)
		(width 0.1143)
		(layer "In9.Cu")
		(net "P2E_CPU_ETH10G_RX_DP8")
	)
	(segment
		(start 84.963 -54.660546)
		(end 84.962492 -54.660546)
		(width 0.1016)
		(layer "In9.Cu")
		(net "P2E_CPU_ETH10G_RX_DP8")
	)
	(segment
		(start 46.0248 -33.772094)
		(end 46.0248 -32.064198)
		(width 0.1143)
		(layer "In9.Cu")
		(net "P2E_CPU_ETH10G_RX_DP8")
	)
	(segment
		(start 67.455034 -53.8861)
		(end 66.215006 -53.8861)
		(width 0.1143)
		(layer "In9.Cu")
		(net "P2E_CPU_ETH10G_RX_DP8")
	)
	(segment
		(start 49.012602 -35.052)
		(end 47.304706 -35.052)
		(width 0.1143)
		(layer "In9.Cu")
		(net "P2E_CPU_ETH10G_RX_DP8")
	)
	(segment
		(start 84.962492 -54.660546)
		(end 84.391754 -55.231284)
		(width 0.1016)
		(layer "In9.Cu")
		(net "P2E_CPU_ETH10G_RX_DP8")
	)
	(segment
		(start 84.963 -53.80228)
		(end 84.86394 -53.90134)
		(width 0.1016)
		(layer "In9.Cu")
		(net "P2E_CPU_ETH10G_RX_DP8")
	)
	(segment
		(start 52.513992 -37.0713)
		(end 51.031902 -37.0713)
		(width 0.1143)
		(layer "In9.Cu")
		(net "P2E_CPU_ETH10G_RX_DP8")
	)
	(segment
		(start 41.1734 -24.1173)
		(end 39.1795 -22.1234)
		(width 0.1143)
		(layer "In9.Cu")
		(net "P2E_CPU_ETH10G_RX_DP8")
	)
	(segment
		(start 69.169534 -55.6006)
		(end 67.455034 -53.8861)
		(width 0.1143)
		(layer "In9.Cu")
		(net "P2E_CPU_ETH10G_RX_DP8")
	)
	(segment
		(start 59.243722 -50.00625)
		(end 56.48325 -47.245778)
		(width 0.1143)
		(layer "In9.Cu")
		(net "P2E_CPU_ETH10G_RX_DP8")
	)
	(segment
		(start 62.981078 -53.3146)
		(end 59.672728 -50.00625)
		(width 0.1143)
		(layer "In9.Cu")
		(net "P2E_CPU_ETH10G_RX_DP8")
	)
	(segment
		(start 47.304706 -35.052)
		(end 46.0248 -33.772094)
		(width 0.1143)
		(layer "In9.Cu")
		(net "P2E_CPU_ETH10G_RX_DP8")
	)
	(segment
		(start 81.863184 -57.6707)
		(end 72.165972 -57.6707)
		(width 0.1143)
		(layer "In9.Cu")
		(net "P2E_CPU_ETH10G_RX_DP8")
	)
	(segment
		(start 55.143908 -39.701216)
		(end 52.513992 -37.0713)
		(width 0.1143)
		(layer "In9.Cu")
		(net "P2E_CPU_ETH10G_RX_DP8")
	)
	(segment
		(start 38.71976 -22.1234)
		(end 33.05556 -16.4592)
		(width 0.1143)
		(layer "In9.Cu")
		(net "P2E_CPU_ETH10G_RX_DP8")
	)
	(segment
		(start 32.688276 -16.4592)
		(end 32.03321 -15.804134)
		(width 0.1143)
		(layer "In9.Cu")
		(net "P2E_CPU_ETH10G_RX_DP8")
	)
	(segment
		(start 84.86394 -54.20614)
		(end 84.963 -54.3052)
		(width 0.1016)
		(layer "In9.Cu")
		(net "P2E_CPU_ETH10G_RX_DP8")
	)
	(segment
		(start 84.176362 -55.44693)
		(end 84.036154 -55.44693)
		(width 0.1016)
		(layer "In9.Cu")
		(net "P2E_CPU_ETH10G_RX_DP8")
	)
	(segment
		(start 55.143908 -44.029376)
		(end 55.143908 -39.701216)
		(width 0.1143)
		(layer "In9.Cu")
		(net "P2E_CPU_ETH10G_RX_DP8")
	)
	(segment
		(start 70.095872 -55.6006)
		(end 69.169534 -55.6006)
		(width 0.1143)
		(layer "In9.Cu")
		(net "P2E_CPU_ETH10G_RX_DP8")
	)
	(segment
		(start 65.643506 -53.3146)
		(end 62.981078 -53.3146)
		(width 0.1143)
		(layer "In9.Cu")
		(net "P2E_CPU_ETH10G_RX_DP8")
	)
	(segment
		(start 82.876898 -56.656986)
		(end 81.863184 -57.6707)
		(width 0.1143)
		(layer "In9.Cu")
		(net "P2E_CPU_ETH10G_RX_DP8")
	)
	(segment
		(start 87.389462 -48.754538)
		(end 87.389462 -50.374804)
		(width 0.1016)
		(layer "In9.Cu")
		(net "P2E_CPU_ETH10G_RX_DP8")
	)
	(segment
		(start 59.672728 -50.00625)
		(end 59.243722 -50.00625)
		(width 0.1143)
		(layer "In9.Cu")
		(net "P2E_CPU_ETH10G_RX_DP8")
	)
	(segment
		(start 66.215006 -53.8861)
		(end 65.643506 -53.3146)
		(width 0.1143)
		(layer "In9.Cu")
		(net "P2E_CPU_ETH10G_RX_DP8")
	)
	(segment
		(start 83.820762 -55.662322)
		(end 83.820762 -55.80253)
		(width 0.1016)
		(layer "In9.Cu")
		(net "P2E_CPU_ETH10G_RX_DP8")
	)
	(segment
		(start 84.963 -53.0098)
		(end 84.963 -53.80228)
		(width 0.1016)
		(layer "In9.Cu")
		(net "P2E_CPU_ETH10G_RX_DP8")
	)
	(segment
		(start 41.1734 -27.212798)
		(end 41.1734 -24.1173)
		(width 0.1143)
		(layer "In9.Cu")
		(net "P2E_CPU_ETH10G_RX_DP8")
	)
	(segment
		(start 87.389462 -50.374804)
		(end 86.9061 -50.858166)
		(width 0.1016)
		(layer "In9.Cu")
		(net "P2E_CPU_ETH10G_RX_DP8")
	)
	(segment
		(start 32.03321 -10.545318)
		(end 32.32785 -10.250678)
		(width 0.1143)
		(layer "In9.Cu")
		(net "P2E_CPU_ETH10G_RX_DP8")
	)
	(segment
		(start 84.963 -54.3052)
		(end 84.963 -54.660546)
		(width 0.1016)
		(layer "In9.Cu")
		(net "P2E_CPU_ETH10G_RX_DP8")
	)
	(segment
		(start 46.0248 -32.064198)
		(end 41.1734 -27.212798)
		(width 0.1143)
		(layer "In9.Cu")
		(net "P2E_CPU_ETH10G_RX_DP8")
	)
	(segment
		(start 87.757 -48.387)
		(end 87.389462 -48.754538)
		(width 0.1016)
		(layer "In9.Cu")
		(net "P2E_CPU_ETH10G_RX_DP8")
	)
	(segment
		(start 32.03321 -15.804134)
		(end 32.03321 -10.545318)
		(width 0.1143)
		(layer "In9.Cu")
		(net "P2E_CPU_ETH10G_RX_DP8")
	)
	(segment
		(start 86.9061 -50.858166)
		(end 86.9061 -51.0667)
		(width 0.1016)
		(layer "In9.Cu")
		(net "P2E_CPU_ETH10G_RX_DP8")
	)
	(segment
		(start 56.48325 -47.245778)
		(end 56.48325 -45.368718)
		(width 0.1143)
		(layer "In9.Cu")
		(net "P2E_CPU_ETH10G_RX_DP8")
	)
	(segment
		(start 86.9061 -51.0667)
		(end 84.963 -53.0098)
		(width 0.1016)
		(layer "In9.Cu")
		(net "P2E_CPU_ETH10G_RX_DP8")
	)
	(segment
		(start 82.96656 -56.656986)
		(end 82.876898 -56.656986)
		(width 0.1016)
		(layer "In9.Cu")
		(net "P2E_CPU_ETH10G_RX_DP8")
	)
	(segment
		(start 56.48325 -45.368718)
		(end 55.143908 -44.029376)
		(width 0.1143)
		(layer "In9.Cu")
		(net "P2E_CPU_ETH10G_RX_DP8")
	)
	(segment
		(start 84.036154 -55.44693)
		(end 83.820762 -55.662322)
		(width 0.1016)
		(layer "In9.Cu")
		(net "P2E_CPU_ETH10G_RX_DP8")
	)
	(segment
		(start 83.820762 -55.80253)
		(end 82.96656 -56.656986)
		(width 0.1016)
		(layer "In9.Cu")
		(net "P2E_CPU_ETH10G_RX_DP8")
	)
	(segment
		(start 18.0213 -10.29716)
		(end 18.55724 -10.8331)
		(width 0.1397)
		(layer "B.Cu")
		(net "P2E_CPU_ETH10G_TX_DP11")
	)
	(segment
		(start 18.55724 -10.8331)
		(end 20.3581 -10.8331)
		(width 0.1397)
		(layer "B.Cu")
		(net "P2E_CPU_ETH10G_TX_DP11")
	)
	(segment
		(start 20.7518 -12.0396)
		(end 20.955 -12.2428)
		(width 0.1397)
		(layer "B.Cu")
		(net "P2E_CPU_ETH10G_TX_DP11")
	)
	(segment
		(start 20.3581 -10.8331)
		(end 20.7518 -11.2268)
		(width 0.1397)
		(layer "B.Cu")
		(net "P2E_CPU_ETH10G_TX_DP11")
	)
	(segment
		(start 18.349976 -8.447024)
		(end 18.0213 -8.7757)
		(width 0.1397)
		(layer "B.Cu")
		(net "P2E_CPU_ETH10G_TX_DP11")
	)
	(segment
		(start 18.349976 -5.814568)
		(end 18.349976 -8.447024)
		(width 0.1397)
		(layer "B.Cu")
		(net "P2E_CPU_ETH10G_TX_DP11")
	)
	(segment
		(start 20.7518 -11.2268)
		(end 20.7518 -12.0396)
		(width 0.1397)
		(layer "B.Cu")
		(net "P2E_CPU_ETH10G_TX_DP11")
	)
	(segment
		(start 18.0213 -8.7757)
		(end 18.0213 -10.29716)
		(width 0.1397)
		(layer "B.Cu")
		(net "P2E_CPU_ETH10G_TX_DP11")
	)
	(segment
		(start 18.415 -11.176)
		(end 20.21586 -11.176)
		(width 0.1397)
		(layer "B.Cu")
		(net "P2E_CPU_ETH10G_TX_DN11")
	)
	(segment
		(start 17.349978 -5.814568)
		(end 17.349978 -8.447278)
		(width 0.1397)
		(layer "B.Cu")
		(net "P2E_CPU_ETH10G_TX_DN11")
	)
	(segment
		(start 20.4089 -12.0269)
		(end 20.193 -12.2428)
		(width 0.1397)
		(layer "B.Cu")
		(net "P2E_CPU_ETH10G_TX_DN11")
	)
	(segment
		(start 20.21586 -11.176)
		(end 20.4089 -11.36904)
		(width 0.1397)
		(layer "B.Cu")
		(net "P2E_CPU_ETH10G_TX_DN11")
	)
	(segment
		(start 20.4089 -11.36904)
		(end 20.4089 -12.0269)
		(width 0.1397)
		(layer "B.Cu")
		(net "P2E_CPU_ETH10G_TX_DN11")
	)
	(segment
		(start 17.349978 -8.447278)
		(end 17.6784 -8.7757)
		(width 0.1397)
		(layer "B.Cu")
		(net "P2E_CPU_ETH10G_TX_DN11")
	)
	(segment
		(start 17.6784 -10.4394)
		(end 18.415 -11.176)
		(width 0.1397)
		(layer "B.Cu")
		(net "P2E_CPU_ETH10G_TX_DN11")
	)
	(segment
		(start 17.6784 -8.7757)
		(end 17.6784 -10.4394)
		(width 0.1397)
		(layer "B.Cu")
		(net "P2E_CPU_ETH10G_TX_DN11")
	)
	(segment
		(start 21.678392 -8.7757)
		(end 21.678392 -10.606532)
		(width 0.1397)
		(layer "B.Cu")
		(net "P2E_CPU_ETH10G_TX_DN10")
	)
	(segment
		(start 21.34997 -8.447278)
		(end 21.678392 -8.7757)
		(width 0.1397)
		(layer "B.Cu")
		(net "P2E_CPU_ETH10G_TX_DN10")
	)
	(segment
		(start 21.34997 -5.814568)
		(end 21.34997 -8.447278)
		(width 0.1397)
		(layer "B.Cu")
		(net "P2E_CPU_ETH10G_TX_DN10")
	)
	(segment
		(start 21.9329 -12.0269)
		(end 21.717 -12.2428)
		(width 0.1397)
		(layer "B.Cu")
		(net "P2E_CPU_ETH10G_TX_DN10")
	)
	(segment
		(start 21.9329 -10.86104)
		(end 21.9329 -12.0269)
		(width 0.1397)
		(layer "B.Cu")
		(net "P2E_CPU_ETH10G_TX_DN10")
	)
	(segment
		(start 21.678392 -10.606532)
		(end 21.9329 -10.86104)
		(width 0.1397)
		(layer "B.Cu")
		(net "P2E_CPU_ETH10G_TX_DN10")
	)
	(segment
		(start 22.2758 -12.0396)
		(end 22.479 -12.2428)
		(width 0.1397)
		(layer "B.Cu")
		(net "P2E_CPU_ETH10G_TX_DP10")
	)
	(segment
		(start 22.2758 -10.7188)
		(end 22.2758 -12.0396)
		(width 0.1397)
		(layer "B.Cu")
		(net "P2E_CPU_ETH10G_TX_DP10")
	)
	(segment
		(start 22.021292 -10.464292)
		(end 22.2758 -10.7188)
		(width 0.1397)
		(layer "B.Cu")
		(net "P2E_CPU_ETH10G_TX_DP10")
	)
	(segment
		(start 22.349968 -8.447024)
		(end 22.021292 -8.7757)
		(width 0.1397)
		(layer "B.Cu")
		(net "P2E_CPU_ETH10G_TX_DP10")
	)
	(segment
		(start 22.021292 -8.7757)
		(end 22.021292 -10.464292)
		(width 0.1397)
		(layer "B.Cu")
		(net "P2E_CPU_ETH10G_TX_DP10")
	)
	(segment
		(start 22.349968 -5.814568)
		(end 22.349968 -8.447024)
		(width 0.1397)
		(layer "B.Cu")
		(net "P2E_CPU_ETH10G_TX_DP10")
	)
	(segment
		(start 25.349962 -5.814568)
		(end 25.349962 -8.447278)
		(width 0.1397)
		(layer "B.Cu")
		(net "P2E_CPU_ETH10G_TX_DN9")
	)
	(segment
		(start 25.678384 -8.7757)
		(end 25.678384 -12.027916)
		(width 0.1397)
		(layer "B.Cu")
		(net "P2E_CPU_ETH10G_TX_DN9")
	)
	(segment
		(start 25.349962 -8.447278)
		(end 25.678384 -8.7757)
		(width 0.1397)
		(layer "B.Cu")
		(net "P2E_CPU_ETH10G_TX_DN9")
	)
	(segment
		(start 25.678384 -12.027916)
		(end 25.4635 -12.2428)
		(width 0.1397)
		(layer "B.Cu")
		(net "P2E_CPU_ETH10G_TX_DN9")
	)
	(segment
		(start 26.34996 -5.814568)
		(end 26.34996 -8.447024)
		(width 0.1397)
		(layer "B.Cu")
		(net "P2E_CPU_ETH10G_TX_DP9")
	)
	(segment
		(start 26.021284 -8.7757)
		(end 26.021284 -12.038584)
		(width 0.1397)
		(layer "B.Cu")
		(net "P2E_CPU_ETH10G_TX_DP9")
	)
	(segment
		(start 26.021284 -12.038584)
		(end 26.2255 -12.2428)
		(width 0.1397)
		(layer "B.Cu")
		(net "P2E_CPU_ETH10G_TX_DP9")
	)
	(segment
		(start 26.34996 -8.447024)
		(end 26.021284 -8.7757)
		(width 0.1397)
		(layer "B.Cu")
		(net "P2E_CPU_ETH10G_TX_DP9")
	)
	(segment
		(start 91.145614 -54.950614)
		(end 90.4494 -54.2544)
		(width 0.1016)
		(layer "F.Cu")
		(net "P2E_CPU_ETH10G_C_TX_DN11")
	)
	(segment
		(start 90.4494 -54.2544)
		(end 90.4494 -52.474114)
		(width 0.1016)
		(layer "F.Cu")
		(net "P2E_CPU_ETH10G_C_TX_DN11")
	)
	(segment
		(start 90.790268 -52.133246)
		(end 90.790268 -51.880262)
		(width 0.1016)
		(layer "F.Cu")
		(net "P2E_CPU_ETH10G_C_TX_DN11")
	)
	(segment
		(start 91.396058 -54.950614)
		(end 91.145614 -54.950614)
		(width 0.1016)
		(layer "F.Cu")
		(net "P2E_CPU_ETH10G_C_TX_DN11")
	)
	(segment
		(start 90.4494 -52.474114)
		(end 90.790268 -52.133246)
		(width 0.1016)
		(layer "F.Cu")
		(net "P2E_CPU_ETH10G_C_TX_DN11")
	)
	(segment
		(start 90.790268 -51.880262)
		(end 90.564208 -50.952654)
		(width 0.1016)
		(layer "F.Cu")
		(net "P2E_CPU_ETH10G_C_TX_DN11")
	)
	(via
		(at 91.396058 -54.950614)
		(size 0.4318)
		(drill 0.2032)
		(layers "F.Cu" "B.Cu")
		(net "P2E_CPU_ETH10G_C_TX_DN11")
	)
	(via
		(at 20.09521 -15.488666)
		(size 0.508)
		(drill 0.254)
		(layers "F.Cu" "B.Cu")
		(net "P2E_CPU_ETH10G_C_TX_DN11")
	)
	(segment
		(start 20.40255 -13.36675)
		(end 20.40255 -15.181326)
		(width 0.1397)
		(layer "B.Cu")
		(net "P2E_CPU_ETH10G_C_TX_DN11")
	)
	(segment
		(start 20.40255 -15.181326)
		(end 20.09521 -15.488666)
		(width 0.1397)
		(layer "B.Cu")
		(net "P2E_CPU_ETH10G_C_TX_DN11")
	)
	(segment
		(start 20.193 -13.1572)
		(end 20.40255 -13.36675)
		(width 0.1397)
		(layer "B.Cu")
		(net "P2E_CPU_ETH10G_C_TX_DN11")
	)
	(segment
		(start 48.627538 -43.574208)
		(end 46.14418 -41.09085)
		(width 0.1143)
		(layer "In2.Cu")
		(net "P2E_CPU_ETH10G_C_TX_DN11")
	)
	(segment
		(start 32.8295 -26.286206)
		(end 24.91232 -18.369026)
		(width 0.1143)
		(layer "In2.Cu")
		(net "P2E_CPU_ETH10G_C_TX_DN11")
	)
	(segment
		(start 92.1766 -60.096146)
		(end 89.750646 -62.5221)
		(width 0.1143)
		(layer "In2.Cu")
		(net "P2E_CPU_ETH10G_C_TX_DN11")
	)
	(segment
		(start 46.14418 -41.09085)
		(end 45.093128 -41.09085)
		(width 0.1143)
		(layer "In2.Cu")
		(net "P2E_CPU_ETH10G_C_TX_DN11")
	)
	(segment
		(start 91.396058 -54.950614)
		(end 91.396058 -55.064152)
		(width 0.1143)
		(layer "In2.Cu")
		(net "P2E_CPU_ETH10G_C_TX_DN11")
	)
	(segment
		(start 37.720778 -32.9311)
		(end 36.450778 -32.9311)
		(width 0.1143)
		(layer "In2.Cu")
		(net "P2E_CPU_ETH10G_C_TX_DN11")
	)
	(segment
		(start 22.42312 -18.369026)
		(end 20.3708 -16.316706)
		(width 0.1143)
		(layer "In2.Cu")
		(net "P2E_CPU_ETH10G_C_TX_DN11")
	)
	(segment
		(start 54.90464 -50.18405)
		(end 54.238144 -50.18405)
		(width 0.1143)
		(layer "In2.Cu")
		(net "P2E_CPU_ETH10G_C_TX_DN11")
	)
	(segment
		(start 92.1766 -57.3786)
		(end 92.1766 -60.096146)
		(width 0.1143)
		(layer "In2.Cu")
		(net "P2E_CPU_ETH10G_C_TX_DN11")
	)
	(segment
		(start 48.627538 -43.989244)
		(end 48.627538 -43.574208)
		(width 0.1143)
		(layer "In2.Cu")
		(net "P2E_CPU_ETH10G_C_TX_DN11")
	)
	(segment
		(start 54.238144 -50.18405)
		(end 53.272944 -49.21885)
		(width 0.1143)
		(layer "In2.Cu")
		(net "P2E_CPU_ETH10G_C_TX_DN11")
	)
	(segment
		(start 91.6559 -55.323994)
		(end 91.6559 -56.8579)
		(width 0.1143)
		(layer "In2.Cu")
		(net "P2E_CPU_ETH10G_C_TX_DN11")
	)
	(segment
		(start 53.272944 -49.21885)
		(end 53.272944 -47.107094)
		(width 0.1143)
		(layer "In2.Cu")
		(net "P2E_CPU_ETH10G_C_TX_DN11")
	)
	(segment
		(start 20.3708 -15.764256)
		(end 20.09521 -15.488666)
		(width 0.1143)
		(layer "In2.Cu")
		(net "P2E_CPU_ETH10G_C_TX_DN11")
	)
	(segment
		(start 24.91232 -18.369026)
		(end 22.42312 -18.369026)
		(width 0.1143)
		(layer "In2.Cu")
		(net "P2E_CPU_ETH10G_C_TX_DN11")
	)
	(segment
		(start 50.634138 -45.995844)
		(end 48.627538 -43.989244)
		(width 0.1143)
		(layer "In2.Cu")
		(net "P2E_CPU_ETH10G_C_TX_DN11")
	)
	(segment
		(start 20.3708 -16.316706)
		(end 20.3708 -15.764256)
		(width 0.1143)
		(layer "In2.Cu")
		(net "P2E_CPU_ETH10G_C_TX_DN11")
	)
	(segment
		(start 89.750646 -62.5221)
		(end 69.4309 -62.5221)
		(width 0.1143)
		(layer "In2.Cu")
		(net "P2E_CPU_ETH10G_C_TX_DN11")
	)
	(segment
		(start 53.272944 -47.107094)
		(end 52.161694 -45.995844)
		(width 0.1143)
		(layer "In2.Cu")
		(net "P2E_CPU_ETH10G_C_TX_DN11")
	)
	(segment
		(start 45.093128 -41.09085)
		(end 42.69613 -38.693852)
		(width 0.1143)
		(layer "In2.Cu")
		(net "P2E_CPU_ETH10G_C_TX_DN11")
	)
	(segment
		(start 32.8295 -29.309822)
		(end 32.8295 -26.286206)
		(width 0.1143)
		(layer "In2.Cu")
		(net "P2E_CPU_ETH10G_C_TX_DN11")
	)
	(segment
		(start 91.6559 -56.8579)
		(end 92.1766 -57.3786)
		(width 0.1143)
		(layer "In2.Cu")
		(net "P2E_CPU_ETH10G_C_TX_DN11")
	)
	(segment
		(start 36.450778 -32.9311)
		(end 32.8295 -29.309822)
		(width 0.1143)
		(layer "In2.Cu")
		(net "P2E_CPU_ETH10G_C_TX_DN11")
	)
	(segment
		(start 62.42939 -57.7088)
		(end 54.90464 -50.18405)
		(width 0.1143)
		(layer "In2.Cu")
		(net "P2E_CPU_ETH10G_C_TX_DN11")
	)
	(segment
		(start 42.69613 -38.693852)
		(end 42.69613 -37.906452)
		(width 0.1143)
		(layer "In2.Cu")
		(net "P2E_CPU_ETH10G_C_TX_DN11")
	)
	(segment
		(start 91.396058 -55.064152)
		(end 91.6559 -55.323994)
		(width 0.1143)
		(layer "In2.Cu")
		(net "P2E_CPU_ETH10G_C_TX_DN11")
	)
	(segment
		(start 42.69613 -37.906452)
		(end 37.720778 -32.9311)
		(width 0.1143)
		(layer "In2.Cu")
		(net "P2E_CPU_ETH10G_C_TX_DN11")
	)
	(segment
		(start 69.4309 -62.5221)
		(end 64.6176 -57.7088)
		(width 0.1143)
		(layer "In2.Cu")
		(net "P2E_CPU_ETH10G_C_TX_DN11")
	)
	(segment
		(start 52.161694 -45.995844)
		(end 50.634138 -45.995844)
		(width 0.1143)
		(layer "In2.Cu")
		(net "P2E_CPU_ETH10G_C_TX_DN11")
	)
	(segment
		(start 64.6176 -57.7088)
		(end 62.42939 -57.7088)
		(width 0.1143)
		(layer "In2.Cu")
		(net "P2E_CPU_ETH10G_C_TX_DN11")
	)
	(segment
		(start 90.923364 -55.249064)
		(end 90.923364 -55.015892)
		(width 0.1016)
		(layer "F.Cu")
		(net "P2E_CPU_ETH10G_C_TX_DP11")
	)
	(segment
		(start 90.2462 -52.389786)
		(end 90.485468 -52.150518)
		(width 0.1016)
		(layer "F.Cu")
		(net "P2E_CPU_ETH10G_C_TX_DP11")
	)
	(segment
		(start 90.485468 -52.150518)
		(end 90.485468 -52.006754)
		(width 0.1016)
		(layer "F.Cu")
		(net "P2E_CPU_ETH10G_C_TX_DP11")
	)
	(segment
		(start 90.923364 -55.015892)
		(end 90.2462 -54.338728)
		(width 0.1016)
		(layer "F.Cu")
		(net "P2E_CPU_ETH10G_C_TX_DP11")
	)
	(segment
		(start 90.2462 -54.338728)
		(end 90.2462 -52.389786)
		(width 0.1016)
		(layer "F.Cu")
		(net "P2E_CPU_ETH10G_C_TX_DP11")
	)
	(via
		(at 90.923364 -55.249064)
		(size 0.4318)
		(drill 0.2032)
		(layers "F.Cu" "B.Cu")
		(net "P2E_CPU_ETH10G_C_TX_DP11")
	)
	(via
		(at 21.05279 -15.488666)
		(size 0.508)
		(drill 0.254)
		(layers "F.Cu" "B.Cu")
		(net "P2E_CPU_ETH10G_C_TX_DP11")
	)
	(segment
		(start 20.74545 -15.181326)
		(end 21.05279 -15.488666)
		(width 0.1397)
		(layer "B.Cu")
		(net "P2E_CPU_ETH10G_C_TX_DP11")
	)
	(segment
		(start 20.74545 -13.36675)
		(end 20.74545 -15.181326)
		(width 0.1397)
		(layer "B.Cu")
		(net "P2E_CPU_ETH10G_C_TX_DP11")
	)
	(segment
		(start 20.955 -13.1572)
		(end 20.74545 -13.36675)
		(width 0.1397)
		(layer "B.Cu")
		(net "P2E_CPU_ETH10G_C_TX_DP11")
	)
	(segment
		(start 90.923364 -55.249064)
		(end 91.088464 -55.249064)
		(width 0.1143)
		(layer "In2.Cu")
		(net "P2E_CPU_ETH10G_C_TX_DP11")
	)
	(segment
		(start 91.11234 -56.38546)
		(end 91.3257 -56.59882)
		(width 0.1143)
		(layer "In2.Cu")
		(net "P2E_CPU_ETH10G_C_TX_DP11")
	)
	(segment
		(start 21.595842 -17.074642)
		(end 21.595842 -16.77289)
		(width 0.1143)
		(layer "In2.Cu")
		(net "P2E_CPU_ETH10G_C_TX_DP11")
	)
	(segment
		(start 48.957738 -43.852338)
		(end 48.957738 -43.437302)
		(width 0.1143)
		(layer "In2.Cu")
		(net "P2E_CPU_ETH10G_C_TX_DP11")
	)
	(segment
		(start 91.3257 -56.994806)
		(end 91.8464 -57.515506)
		(width 0.1143)
		(layer "In2.Cu")
		(net "P2E_CPU_ETH10G_C_TX_DP11")
	)
	(segment
		(start 25.049226 -18.038826)
		(end 22.560026 -18.038826)
		(width 0.1143)
		(layer "In2.Cu")
		(net "P2E_CPU_ETH10G_C_TX_DP11")
	)
	(segment
		(start 20.701 -16.1798)
		(end 20.701 -15.840456)
		(width 0.1143)
		(layer "In2.Cu")
		(net "P2E_CPU_ETH10G_C_TX_DP11")
	)
	(segment
		(start 79.146908 -61.97854)
		(end 78.933548 -62.1919)
		(width 0.1143)
		(layer "In2.Cu")
		(net "P2E_CPU_ETH10G_C_TX_DP11")
	)
	(segment
		(start 43.02633 -37.769546)
		(end 37.857684 -32.6009)
		(width 0.1143)
		(layer "In2.Cu")
		(net "P2E_CPU_ETH10G_C_TX_DP11")
	)
	(segment
		(start 52.2986 -45.665644)
		(end 50.771044 -45.665644)
		(width 0.1143)
		(layer "In2.Cu")
		(net "P2E_CPU_ETH10G_C_TX_DP11")
	)
	(segment
		(start 36.587684 -32.6009)
		(end 33.1597 -29.172916)
		(width 0.1143)
		(layer "In2.Cu")
		(net "P2E_CPU_ETH10G_C_TX_DP11")
	)
	(segment
		(start 89.61374 -62.1919)
		(end 88.80094 -62.1919)
		(width 0.1143)
		(layer "In2.Cu")
		(net "P2E_CPU_ETH10G_C_TX_DP11")
	)
	(segment
		(start 72.987154 -61.97854)
		(end 72.773794 -62.1919)
		(width 0.1143)
		(layer "In2.Cu")
		(net "P2E_CPU_ETH10G_C_TX_DP11")
	)
	(segment
		(start 20.701 -15.840456)
		(end 21.05279 -15.488666)
		(width 0.1143)
		(layer "In2.Cu")
		(net "P2E_CPU_ETH10G_C_TX_DP11")
	)
	(segment
		(start 72.773794 -62.1919)
		(end 72.430894 -62.1919)
		(width 0.1143)
		(layer "In2.Cu")
		(net "P2E_CPU_ETH10G_C_TX_DP11")
	)
	(segment
		(start 53.603144 -49.081944)
		(end 53.603144 -46.970188)
		(width 0.1143)
		(layer "In2.Cu")
		(net "P2E_CPU_ETH10G_C_TX_DP11")
	)
	(segment
		(start 88.80094 -62.1919)
		(end 88.58758 -61.97854)
		(width 0.1143)
		(layer "In2.Cu")
		(net "P2E_CPU_ETH10G_C_TX_DP11")
	)
	(segment
		(start 87.68842 -62.1919)
		(end 87.47506 -61.97854)
		(width 0.1143)
		(layer "In2.Cu")
		(net "P2E_CPU_ETH10G_C_TX_DP11")
	)
	(segment
		(start 78.377288 -61.97854)
		(end 78.034388 -61.97854)
		(width 0.1143)
		(layer "In2.Cu")
		(net "P2E_CPU_ETH10G_C_TX_DP11")
	)
	(segment
		(start 70.548754 -62.1919)
		(end 69.567806 -62.1919)
		(width 0.1143)
		(layer "In2.Cu")
		(net "P2E_CPU_ETH10G_C_TX_DP11")
	)
	(segment
		(start 83.58124 -62.1919)
		(end 79.703168 -62.1919)
		(width 0.1143)
		(layer "In2.Cu")
		(net "P2E_CPU_ETH10G_C_TX_DP11")
	)
	(segment
		(start 78.034388 -61.97854)
		(end 77.821028 -62.1919)
		(width 0.1143)
		(layer "In2.Cu")
		(net "P2E_CPU_ETH10G_C_TX_DP11")
	)
	(segment
		(start 87.47506 -61.97854)
		(end 87.13216 -61.97854)
		(width 0.1143)
		(layer "In2.Cu")
		(net "P2E_CPU_ETH10G_C_TX_DP11")
	)
	(segment
		(start 46.281086 -40.76065)
		(end 45.230034 -40.76065)
		(width 0.1143)
		(layer "In2.Cu")
		(net "P2E_CPU_ETH10G_C_TX_DP11")
	)
	(segment
		(start 55.041546 -49.85385)
		(end 54.37505 -49.85385)
		(width 0.1143)
		(layer "In2.Cu")
		(net "P2E_CPU_ETH10G_C_TX_DP11")
	)
	(segment
		(start 73.330054 -61.97854)
		(end 72.987154 -61.97854)
		(width 0.1143)
		(layer "In2.Cu")
		(net "P2E_CPU_ETH10G_C_TX_DP11")
	)
	(segment
		(start 91.3257 -55.4863)
		(end 91.3257 -55.8292)
		(width 0.1143)
		(layer "In2.Cu")
		(net "P2E_CPU_ETH10G_C_TX_DP11")
	)
	(segment
		(start 85.25002 -61.97854)
		(end 84.90712 -61.97854)
		(width 0.1143)
		(layer "In2.Cu")
		(net "P2E_CPU_ETH10G_C_TX_DP11")
	)
	(segment
		(start 84.69376 -62.1919)
		(end 84.35086 -62.1919)
		(width 0.1143)
		(layer "In2.Cu")
		(net "P2E_CPU_ETH10G_C_TX_DP11")
	)
	(segment
		(start 85.46338 -62.1919)
		(end 85.25002 -61.97854)
		(width 0.1143)
		(layer "In2.Cu")
		(net "P2E_CPU_ETH10G_C_TX_DP11")
	)
	(segment
		(start 87.13216 -61.97854)
		(end 86.9188 -62.1919)
		(width 0.1143)
		(layer "In2.Cu")
		(net "P2E_CPU_ETH10G_C_TX_DP11")
	)
	(segment
		(start 37.857684 -32.6009)
		(end 36.587684 -32.6009)
		(width 0.1143)
		(layer "In2.Cu")
		(net "P2E_CPU_ETH10G_C_TX_DP11")
	)
	(segment
		(start 71.874634 -61.97854)
		(end 71.661274 -62.1919)
		(width 0.1143)
		(layer "In2.Cu")
		(net "P2E_CPU_ETH10G_C_TX_DP11")
	)
	(segment
		(start 21.353526 -16.530574)
		(end 21.051774 -16.530574)
		(width 0.1143)
		(layer "In2.Cu")
		(net "P2E_CPU_ETH10G_C_TX_DP11")
	)
	(segment
		(start 88.24468 -61.97854)
		(end 88.03132 -62.1919)
		(width 0.1143)
		(layer "In2.Cu")
		(net "P2E_CPU_ETH10G_C_TX_DP11")
	)
	(segment
		(start 78.933548 -62.1919)
		(end 78.590648 -62.1919)
		(width 0.1143)
		(layer "In2.Cu")
		(net "P2E_CPU_ETH10G_C_TX_DP11")
	)
	(segment
		(start 54.37505 -49.85385)
		(end 53.603144 -49.081944)
		(width 0.1143)
		(layer "In2.Cu")
		(net "P2E_CPU_ETH10G_C_TX_DP11")
	)
	(segment
		(start 88.58758 -61.97854)
		(end 88.24468 -61.97854)
		(width 0.1143)
		(layer "In2.Cu")
		(net "P2E_CPU_ETH10G_C_TX_DP11")
	)
	(segment
		(start 71.105014 -61.97854)
		(end 70.762114 -61.97854)
		(width 0.1143)
		(layer "In2.Cu")
		(net "P2E_CPU_ETH10G_C_TX_DP11")
	)
	(segment
		(start 50.771044 -45.665644)
		(end 48.957738 -43.852338)
		(width 0.1143)
		(layer "In2.Cu")
		(net "P2E_CPU_ETH10G_C_TX_DP11")
	)
	(segment
		(start 84.90712 -61.97854)
		(end 84.69376 -62.1919)
		(width 0.1143)
		(layer "In2.Cu")
		(net "P2E_CPU_ETH10G_C_TX_DP11")
	)
	(segment
		(start 91.3257 -56.59882)
		(end 91.3257 -56.994806)
		(width 0.1143)
		(layer "In2.Cu")
		(net "P2E_CPU_ETH10G_C_TX_DP11")
	)
	(segment
		(start 72.430894 -62.1919)
		(end 72.217534 -61.97854)
		(width 0.1143)
		(layer "In2.Cu")
		(net "P2E_CPU_ETH10G_C_TX_DP11")
	)
	(segment
		(start 71.661274 -62.1919)
		(end 71.318374 -62.1919)
		(width 0.1143)
		(layer "In2.Cu")
		(net "P2E_CPU_ETH10G_C_TX_DP11")
	)
	(segment
		(start 86.9188 -62.1919)
		(end 86.5759 -62.1919)
		(width 0.1143)
		(layer "In2.Cu")
		(net "P2E_CPU_ETH10G_C_TX_DP11")
	)
	(segment
		(start 91.088464 -55.249064)
		(end 91.3257 -55.4863)
		(width 0.1143)
		(layer "In2.Cu")
		(net "P2E_CPU_ETH10G_C_TX_DP11")
	)
	(segment
		(start 43.02633 -38.556946)
		(end 43.02633 -37.769546)
		(width 0.1143)
		(layer "In2.Cu")
		(net "P2E_CPU_ETH10G_C_TX_DP11")
	)
	(segment
		(start 76.708508 -62.1919)
		(end 73.543414 -62.1919)
		(width 0.1143)
		(layer "In2.Cu")
		(net "P2E_CPU_ETH10G_C_TX_DP11")
	)
	(segment
		(start 85.80628 -62.1919)
		(end 85.46338 -62.1919)
		(width 0.1143)
		(layer "In2.Cu")
		(net "P2E_CPU_ETH10G_C_TX_DP11")
	)
	(segment
		(start 86.01964 -61.97854)
		(end 85.80628 -62.1919)
		(width 0.1143)
		(layer "In2.Cu")
		(net "P2E_CPU_ETH10G_C_TX_DP11")
	)
	(segment
		(start 21.595842 -16.77289)
		(end 21.353526 -16.530574)
		(width 0.1143)
		(layer "In2.Cu")
		(net "P2E_CPU_ETH10G_C_TX_DP11")
	)
	(segment
		(start 62.566296 -57.3786)
		(end 55.041546 -49.85385)
		(width 0.1143)
		(layer "In2.Cu")
		(net "P2E_CPU_ETH10G_C_TX_DP11")
	)
	(segment
		(start 73.543414 -62.1919)
		(end 73.330054 -61.97854)
		(width 0.1143)
		(layer "In2.Cu")
		(net "P2E_CPU_ETH10G_C_TX_DP11")
	)
	(segment
		(start 86.5759 -62.1919)
		(end 86.36254 -61.97854)
		(width 0.1143)
		(layer "In2.Cu")
		(net "P2E_CPU_ETH10G_C_TX_DP11")
	)
	(segment
		(start 45.230034 -40.76065)
		(end 43.02633 -38.556946)
		(width 0.1143)
		(layer "In2.Cu")
		(net "P2E_CPU_ETH10G_C_TX_DP11")
	)
	(segment
		(start 21.051774 -16.530574)
		(end 20.701 -16.1798)
		(width 0.1143)
		(layer "In2.Cu")
		(net "P2E_CPU_ETH10G_C_TX_DP11")
	)
	(segment
		(start 91.3257 -55.8292)
		(end 91.11234 -56.04256)
		(width 0.1143)
		(layer "In2.Cu")
		(net "P2E_CPU_ETH10G_C_TX_DP11")
	)
	(segment
		(start 77.478128 -62.1919)
		(end 77.264768 -61.97854)
		(width 0.1143)
		(layer "In2.Cu")
		(net "P2E_CPU_ETH10G_C_TX_DP11")
	)
	(segment
		(start 33.1597 -29.172916)
		(end 33.1597 -26.1493)
		(width 0.1143)
		(layer "In2.Cu")
		(net "P2E_CPU_ETH10G_C_TX_DP11")
	)
	(segment
		(start 86.36254 -61.97854)
		(end 86.01964 -61.97854)
		(width 0.1143)
		(layer "In2.Cu")
		(net "P2E_CPU_ETH10G_C_TX_DP11")
	)
	(segment
		(start 53.603144 -46.970188)
		(end 52.2986 -45.665644)
		(width 0.1143)
		(layer "In2.Cu")
		(net "P2E_CPU_ETH10G_C_TX_DP11")
	)
	(segment
		(start 48.957738 -43.437302)
		(end 46.281086 -40.76065)
		(width 0.1143)
		(layer "In2.Cu")
		(net "P2E_CPU_ETH10G_C_TX_DP11")
	)
	(segment
		(start 33.1597 -26.1493)
		(end 25.049226 -18.038826)
		(width 0.1143)
		(layer "In2.Cu")
		(net "P2E_CPU_ETH10G_C_TX_DP11")
	)
	(segment
		(start 64.754506 -57.3786)
		(end 62.566296 -57.3786)
		(width 0.1143)
		(layer "In2.Cu")
		(net "P2E_CPU_ETH10G_C_TX_DP11")
	)
	(segment
		(start 77.264768 -61.97854)
		(end 76.921868 -61.97854)
		(width 0.1143)
		(layer "In2.Cu")
		(net "P2E_CPU_ETH10G_C_TX_DP11")
	)
	(segment
		(start 78.590648 -62.1919)
		(end 78.377288 -61.97854)
		(width 0.1143)
		(layer "In2.Cu")
		(net "P2E_CPU_ETH10G_C_TX_DP11")
	)
	(segment
		(start 69.567806 -62.1919)
		(end 64.754506 -57.3786)
		(width 0.1143)
		(layer "In2.Cu")
		(net "P2E_CPU_ETH10G_C_TX_DP11")
	)
	(segment
		(start 91.8464 -59.95924)
		(end 89.61374 -62.1919)
		(width 0.1143)
		(layer "In2.Cu")
		(net "P2E_CPU_ETH10G_C_TX_DP11")
	)
	(segment
		(start 88.03132 -62.1919)
		(end 87.68842 -62.1919)
		(width 0.1143)
		(layer "In2.Cu")
		(net "P2E_CPU_ETH10G_C_TX_DP11")
	)
	(segment
		(start 83.7946 -61.97854)
		(end 83.58124 -62.1919)
		(width 0.1143)
		(layer "In2.Cu")
		(net "P2E_CPU_ETH10G_C_TX_DP11")
	)
	(segment
		(start 84.35086 -62.1919)
		(end 84.1375 -61.97854)
		(width 0.1143)
		(layer "In2.Cu")
		(net "P2E_CPU_ETH10G_C_TX_DP11")
	)
	(segment
		(start 72.217534 -61.97854)
		(end 71.874634 -61.97854)
		(width 0.1143)
		(layer "In2.Cu")
		(net "P2E_CPU_ETH10G_C_TX_DP11")
	)
	(segment
		(start 76.921868 -61.97854)
		(end 76.708508 -62.1919)
		(width 0.1143)
		(layer "In2.Cu")
		(net "P2E_CPU_ETH10G_C_TX_DP11")
	)
	(segment
		(start 77.821028 -62.1919)
		(end 77.478128 -62.1919)
		(width 0.1143)
		(layer "In2.Cu")
		(net "P2E_CPU_ETH10G_C_TX_DP11")
	)
	(segment
		(start 22.560026 -18.038826)
		(end 21.595842 -17.074642)
		(width 0.1143)
		(layer "In2.Cu")
		(net "P2E_CPU_ETH10G_C_TX_DP11")
	)
	(segment
		(start 84.1375 -61.97854)
		(end 83.7946 -61.97854)
		(width 0.1143)
		(layer "In2.Cu")
		(net "P2E_CPU_ETH10G_C_TX_DP11")
	)
	(segment
		(start 91.11234 -56.04256)
		(end 91.11234 -56.38546)
		(width 0.1143)
		(layer "In2.Cu")
		(net "P2E_CPU_ETH10G_C_TX_DP11")
	)
	(segment
		(start 71.318374 -62.1919)
		(end 71.105014 -61.97854)
		(width 0.1143)
		(layer "In2.Cu")
		(net "P2E_CPU_ETH10G_C_TX_DP11")
	)
	(segment
		(start 79.703168 -62.1919)
		(end 79.489808 -61.97854)
		(width 0.1143)
		(layer "In2.Cu")
		(net "P2E_CPU_ETH10G_C_TX_DP11")
	)
	(segment
		(start 79.489808 -61.97854)
		(end 79.146908 -61.97854)
		(width 0.1143)
		(layer "In2.Cu")
		(net "P2E_CPU_ETH10G_C_TX_DP11")
	)
	(segment
		(start 91.8464 -57.515506)
		(end 91.8464 -59.95924)
		(width 0.1143)
		(layer "In2.Cu")
		(net "P2E_CPU_ETH10G_C_TX_DP11")
	)
	(segment
		(start 70.762114 -61.97854)
		(end 70.548754 -62.1919)
		(width 0.1143)
		(layer "In2.Cu")
		(net "P2E_CPU_ETH10G_C_TX_DP11")
	)
	(segment
		(start 88.894412 -51.772566)
		(end 88.560148 -51.099974)
		(width 0.1016)
		(layer "F.Cu")
		(net "P2E_CPU_ETH10G_C_TX_DN9")
	)
	(segment
		(start 89.088468 -52.285138)
		(end 88.894412 -52.091082)
		(width 0.1016)
		(layer "F.Cu")
		(net "P2E_CPU_ETH10G_C_TX_DN9")
	)
	(segment
		(start 89.088468 -54.20106)
		(end 89.088468 -52.285138)
		(width 0.1016)
		(layer "F.Cu")
		(net "P2E_CPU_ETH10G_C_TX_DN9")
	)
	(segment
		(start 87.339932 -54.6735)
		(end 88.616028 -54.6735)
		(width 0.1016)
		(layer "F.Cu")
		(net "P2E_CPU_ETH10G_C_TX_DN9")
	)
	(segment
		(start 88.616028 -54.6735)
		(end 89.088468 -54.20106)
		(width 0.1016)
		(layer "F.Cu")
		(net "P2E_CPU_ETH10G_C_TX_DN9")
	)
	(segment
		(start 87.172292 -54.84114)
		(end 87.339932 -54.6735)
		(width 0.1016)
		(layer "F.Cu")
		(net "P2E_CPU_ETH10G_C_TX_DN9")
	)
	(segment
		(start 88.894412 -52.091082)
		(end 88.894412 -51.772566)
		(width 0.1016)
		(layer "F.Cu")
		(net "P2E_CPU_ETH10G_C_TX_DN9")
	)
	(via
		(at 87.172292 -54.84114)
		(size 0.4318)
		(drill 0.2032)
		(layers "F.Cu" "B.Cu")
		(net "P2E_CPU_ETH10G_C_TX_DN9")
	)
	(via
		(at 25.4127 -13.8176)
		(size 0.508)
		(drill 0.254)
		(layers "F.Cu" "B.Cu")
		(net "P2E_CPU_ETH10G_C_TX_DN9")
	)
	(segment
		(start 25.4635 -13.7668)
		(end 25.4127 -13.8176)
		(width 0.1397)
		(layer "B.Cu")
		(net "P2E_CPU_ETH10G_C_TX_DN9")
	)
	(segment
		(start 25.4635 -13.1572)
		(end 25.4635 -13.7668)
		(width 0.1397)
		(layer "B.Cu")
		(net "P2E_CPU_ETH10G_C_TX_DN9")
	)
	(segment
		(start 36.9824 -25.6286)
		(end 36.9824 -26.5176)
		(width 0.1143)
		(layer "In2.Cu")
		(net "P2E_CPU_ETH10G_C_TX_DN9")
	)
	(segment
		(start 28.653994 -18.7579)
		(end 31.651956 -18.7579)
		(width 0.1143)
		(layer "In2.Cu")
		(net "P2E_CPU_ETH10G_C_TX_DN9")
	)
	(segment
		(start 85.173058 -57.50687)
		(end 86.7156 -55.964328)
		(width 0.1016)
		(layer "In2.Cu")
		(net "P2E_CPU_ETH10G_C_TX_DN9")
	)
	(segment
		(start 46.956726 -37.774626)
		(end 47.95012 -37.774626)
		(width 0.1143)
		(layer "In2.Cu")
		(net "P2E_CPU_ETH10G_C_TX_DN9")
	)
	(segment
		(start 35.749484 -23.9522)
		(end 35.40379 -24.297894)
		(width 0.1143)
		(layer "In2.Cu")
		(net "P2E_CPU_ETH10G_C_TX_DN9")
	)
	(segment
		(start 86.954106 -54.622954)
		(end 87.172292 -54.84114)
		(width 0.1016)
		(layer "In2.Cu")
		(net "P2E_CPU_ETH10G_C_TX_DN9")
	)
	(segment
		(start 35.40379 -27.28341)
		(end 35.40379 -28.87599)
		(width 0.1143)
		(layer "In2.Cu")
		(net "P2E_CPU_ETH10G_C_TX_DN9")
	)
	(segment
		(start 36.322 -23.427944)
		(end 36.322 -23.749)
		(width 0.1143)
		(layer "In2.Cu")
		(net "P2E_CPU_ETH10G_C_TX_DN9")
	)
	(segment
		(start 53.99532 -42.778426)
		(end 53.99532 -44.59732)
		(width 0.1143)
		(layer "In2.Cu")
		(net "P2E_CPU_ETH10G_C_TX_DN9")
	)
	(segment
		(start 69.571616 -59.944)
		(end 82.825844 -59.944)
		(width 0.1143)
		(layer "In2.Cu")
		(net "P2E_CPU_ETH10G_C_TX_DN9")
	)
	(segment
		(start 51.196494 -39.9796)
		(end 53.99532 -42.778426)
		(width 0.1143)
		(layer "In2.Cu")
		(net "P2E_CPU_ETH10G_C_TX_DN9")
	)
	(segment
		(start 55.190644 -45.792644)
		(end 55.190644 -47.775622)
		(width 0.1143)
		(layer "In2.Cu")
		(net "P2E_CPU_ETH10G_C_TX_DN9")
	)
	(segment
		(start 38.97376 -30.677866)
		(end 39.8526 -31.556706)
		(width 0.1143)
		(layer "In2.Cu")
		(net "P2E_CPU_ETH10G_C_TX_DN9")
	)
	(segment
		(start 38.97376 -28.412186)
		(end 38.97376 -30.677866)
		(width 0.1143)
		(layer "In2.Cu")
		(net "P2E_CPU_ETH10G_C_TX_DN9")
	)
	(segment
		(start 82.825844 -59.944)
		(end 85.155024 -57.61482)
		(width 0.1143)
		(layer "In2.Cu")
		(net "P2E_CPU_ETH10G_C_TX_DN9")
	)
	(segment
		(start 35.40379 -28.87599)
		(end 36.3728 -29.845)
		(width 0.1143)
		(layer "In2.Cu")
		(net "P2E_CPU_ETH10G_C_TX_DN9")
	)
	(segment
		(start 36.7538 -25.4)
		(end 36.9824 -25.6286)
		(width 0.1143)
		(layer "In2.Cu")
		(net "P2E_CPU_ETH10G_C_TX_DN9")
	)
	(segment
		(start 53.99532 -44.59732)
		(end 55.190644 -45.792644)
		(width 0.1143)
		(layer "In2.Cu")
		(net "P2E_CPU_ETH10G_C_TX_DN9")
	)
	(segment
		(start 37.6428 -27.8892)
		(end 37.8206 -27.7114)
		(width 0.1143)
		(layer "In2.Cu")
		(net "P2E_CPU_ETH10G_C_TX_DN9")
	)
	(segment
		(start 59.202828 -51.350672)
		(end 61.685678 -53.833522)
		(width 0.1143)
		(layer "In2.Cu")
		(net "P2E_CPU_ETH10G_C_TX_DN9")
	)
	(segment
		(start 37.1348 -29.845)
		(end 37.6428 -29.337)
		(width 0.1143)
		(layer "In2.Cu")
		(net "P2E_CPU_ETH10G_C_TX_DN9")
	)
	(segment
		(start 36.322 -23.749)
		(end 36.1188 -23.9522)
		(width 0.1143)
		(layer "In2.Cu")
		(net "P2E_CPU_ETH10G_C_TX_DN9")
	)
	(segment
		(start 86.813898 -54.622954)
		(end 86.954106 -54.622954)
		(width 0.1016)
		(layer "In2.Cu")
		(net "P2E_CPU_ETH10G_C_TX_DN9")
	)
	(segment
		(start 25.7048 -14.1097)
		(end 25.7048 -15.808706)
		(width 0.1143)
		(layer "In2.Cu")
		(net "P2E_CPU_ETH10G_C_TX_DN9")
	)
	(segment
		(start 31.651956 -18.7579)
		(end 36.322 -23.427944)
		(width 0.1143)
		(layer "In2.Cu")
		(net "P2E_CPU_ETH10G_C_TX_DN9")
	)
	(segment
		(start 55.190644 -47.775622)
		(end 58.765694 -51.350672)
		(width 0.1143)
		(layer "In2.Cu")
		(net "P2E_CPU_ETH10G_C_TX_DN9")
	)
	(segment
		(start 62.871858 -55.456836)
		(end 65.084452 -55.456836)
		(width 0.1143)
		(layer "In2.Cu")
		(net "P2E_CPU_ETH10G_C_TX_DN9")
	)
	(segment
		(start 86.7156 -54.721252)
		(end 86.813898 -54.622954)
		(width 0.1016)
		(layer "In2.Cu")
		(net "P2E_CPU_ETH10G_C_TX_DN9")
	)
	(segment
		(start 43.663362 -35.7759)
		(end 44.958 -35.7759)
		(width 0.1143)
		(layer "In2.Cu")
		(net "P2E_CPU_ETH10G_C_TX_DN9")
	)
	(segment
		(start 61.685678 -53.833522)
		(end 61.685678 -54.270656)
		(width 0.1143)
		(layer "In2.Cu")
		(net "P2E_CPU_ETH10G_C_TX_DN9")
	)
	(segment
		(start 44.958 -35.7759)
		(end 46.956726 -37.774626)
		(width 0.1143)
		(layer "In2.Cu")
		(net "P2E_CPU_ETH10G_C_TX_DN9")
	)
	(segment
		(start 36.9824 -26.5176)
		(end 36.576 -26.924)
		(width 0.1143)
		(layer "In2.Cu")
		(net "P2E_CPU_ETH10G_C_TX_DN9")
	)
	(segment
		(start 58.765694 -51.350672)
		(end 59.202828 -51.350672)
		(width 0.1143)
		(layer "In2.Cu")
		(net "P2E_CPU_ETH10G_C_TX_DN9")
	)
	(segment
		(start 50.155094 -39.9796)
		(end 51.196494 -39.9796)
		(width 0.1143)
		(layer "In2.Cu")
		(net "P2E_CPU_ETH10G_C_TX_DN9")
	)
	(segment
		(start 65.084452 -55.456836)
		(end 69.571616 -59.944)
		(width 0.1143)
		(layer "In2.Cu")
		(net "P2E_CPU_ETH10G_C_TX_DN9")
	)
	(segment
		(start 36.576 -26.924)
		(end 35.7632 -26.924)
		(width 0.1143)
		(layer "In2.Cu")
		(net "P2E_CPU_ETH10G_C_TX_DN9")
	)
	(segment
		(start 35.927284 -25.4)
		(end 36.7538 -25.4)
		(width 0.1143)
		(layer "In2.Cu")
		(net "P2E_CPU_ETH10G_C_TX_DN9")
	)
	(segment
		(start 25.7048 -15.808706)
		(end 28.653994 -18.7579)
		(width 0.1143)
		(layer "In2.Cu")
		(net "P2E_CPU_ETH10G_C_TX_DN9")
	)
	(segment
		(start 85.173058 -57.596786)
		(end 85.173058 -57.50687)
		(width 0.1016)
		(layer "In2.Cu")
		(net "P2E_CPU_ETH10G_C_TX_DN9")
	)
	(segment
		(start 85.155024 -57.61482)
		(end 85.173058 -57.596786)
		(width 0.1016)
		(layer "In2.Cu")
		(net "P2E_CPU_ETH10G_C_TX_DN9")
	)
	(segment
		(start 39.8526 -31.556706)
		(end 39.8526 -31.965138)
		(width 0.1143)
		(layer "In2.Cu")
		(net "P2E_CPU_ETH10G_C_TX_DN9")
	)
	(segment
		(start 36.1188 -23.9522)
		(end 35.749484 -23.9522)
		(width 0.1143)
		(layer "In2.Cu")
		(net "P2E_CPU_ETH10G_C_TX_DN9")
	)
	(segment
		(start 37.6428 -29.337)
		(end 37.6428 -27.8892)
		(width 0.1143)
		(layer "In2.Cu")
		(net "P2E_CPU_ETH10G_C_TX_DN9")
	)
	(segment
		(start 37.8206 -27.7114)
		(end 38.272974 -27.7114)
		(width 0.1143)
		(layer "In2.Cu")
		(net "P2E_CPU_ETH10G_C_TX_DN9")
	)
	(segment
		(start 86.7156 -55.964328)
		(end 86.7156 -54.721252)
		(width 0.1016)
		(layer "In2.Cu")
		(net "P2E_CPU_ETH10G_C_TX_DN9")
	)
	(segment
		(start 36.3728 -29.845)
		(end 37.1348 -29.845)
		(width 0.1143)
		(layer "In2.Cu")
		(net "P2E_CPU_ETH10G_C_TX_DN9")
	)
	(segment
		(start 25.4127 -13.8176)
		(end 25.7048 -14.1097)
		(width 0.1143)
		(layer "In2.Cu")
		(net "P2E_CPU_ETH10G_C_TX_DN9")
	)
	(segment
		(start 39.8526 -31.965138)
		(end 43.663362 -35.7759)
		(width 0.1143)
		(layer "In2.Cu")
		(net "P2E_CPU_ETH10G_C_TX_DN9")
	)
	(segment
		(start 47.95012 -37.774626)
		(end 50.155094 -39.9796)
		(width 0.1143)
		(layer "In2.Cu")
		(net "P2E_CPU_ETH10G_C_TX_DN9")
	)
	(segment
		(start 35.40379 -24.876506)
		(end 35.927284 -25.4)
		(width 0.1143)
		(layer "In2.Cu")
		(net "P2E_CPU_ETH10G_C_TX_DN9")
	)
	(segment
		(start 35.40379 -24.297894)
		(end 35.40379 -24.876506)
		(width 0.1143)
		(layer "In2.Cu")
		(net "P2E_CPU_ETH10G_C_TX_DN9")
	)
	(segment
		(start 35.7632 -26.924)
		(end 35.40379 -27.28341)
		(width 0.1143)
		(layer "In2.Cu")
		(net "P2E_CPU_ETH10G_C_TX_DN9")
	)
	(segment
		(start 38.272974 -27.7114)
		(end 38.97376 -28.412186)
		(width 0.1143)
		(layer "In2.Cu")
		(net "P2E_CPU_ETH10G_C_TX_DN9")
	)
	(segment
		(start 61.685678 -54.270656)
		(end 62.871858 -55.456836)
		(width 0.1143)
		(layer "In2.Cu")
		(net "P2E_CPU_ETH10G_C_TX_DN9")
	)
	(segment
		(start 29.678376 -8.7757)
		(end 29.678376 -12.028424)
		(width 0.1397)
		(layer "B.Cu")
		(net "P2E_CPU_ETH10G_TX_DN8")
	)
	(segment
		(start 29.678376 -12.028424)
		(end 29.464 -12.2428)
		(width 0.1397)
		(layer "B.Cu")
		(net "P2E_CPU_ETH10G_TX_DN8")
	)
	(segment
		(start 29.349954 -8.447278)
		(end 29.678376 -8.7757)
		(width 0.1397)
		(layer "B.Cu")
		(net "P2E_CPU_ETH10G_TX_DN8")
	)
	(segment
		(start 29.349954 -5.814568)
		(end 29.349954 -8.447278)
		(width 0.1397)
		(layer "B.Cu")
		(net "P2E_CPU_ETH10G_TX_DN8")
	)
	(segment
		(start 30.349952 -5.814568)
		(end 30.349952 -8.447024)
		(width 0.1397)
		(layer "B.Cu")
		(net "P2E_CPU_ETH10G_TX_DP8")
	)
	(segment
		(start 30.021276 -8.7757)
		(end 30.021276 -12.038076)
		(width 0.1397)
		(layer "B.Cu")
		(net "P2E_CPU_ETH10G_TX_DP8")
	)
	(segment
		(start 30.021276 -12.038076)
		(end 30.226 -12.2428)
		(width 0.1397)
		(layer "B.Cu")
		(net "P2E_CPU_ETH10G_TX_DP8")
	)
	(segment
		(start 30.349952 -8.447024)
		(end 30.021276 -8.7757)
		(width 0.1397)
		(layer "B.Cu")
		(net "P2E_CPU_ETH10G_TX_DP8")
	)
	(segment
		(start 89.583006 -53.58384)
		(end 89.748614 -53.58384)
		(width 0.1016)
		(layer "F.Cu")
		(net "P2E_CPU_ETH10G_C_TX_DP10")
	)
	(segment
		(start 89.494868 -52.116482)
		(end 89.494868 -53.495702)
		(width 0.1016)
		(layer "F.Cu")
		(net "P2E_CPU_ETH10G_C_TX_DP10")
	)
	(segment
		(start 89.454228 -52.075842)
		(end 89.494868 -52.116482)
		(width 0.1016)
		(layer "F.Cu")
		(net "P2E_CPU_ETH10G_C_TX_DP10")
	)
	(segment
		(start 89.454228 -51.841654)
		(end 89.454228 -52.075842)
		(width 0.1016)
		(layer "F.Cu")
		(net "P2E_CPU_ETH10G_C_TX_DP10")
	)
	(segment
		(start 89.494868 -53.495702)
		(end 89.583006 -53.58384)
		(width 0.1016)
		(layer "F.Cu")
		(net "P2E_CPU_ETH10G_C_TX_DP10")
	)
	(segment
		(start 89.748614 -53.58384)
		(end 89.812876 -53.519578)
		(width 0.1016)
		(layer "F.Cu")
		(net "P2E_CPU_ETH10G_C_TX_DP10")
	)
	(via
		(at 89.812876 -53.519578)
		(size 0.4318)
		(drill 0.2032)
		(layers "F.Cu" "B.Cu")
		(net "P2E_CPU_ETH10G_C_TX_DP10")
	)
	(via
		(at 22.5298 -13.8176)
		(size 0.508)
		(drill 0.254)
		(layers "F.Cu" "B.Cu")
		(net "P2E_CPU_ETH10G_C_TX_DP10")
	)
	(segment
		(start 22.479 -13.1572)
		(end 22.479 -13.7668)
		(width 0.1397)
		(layer "B.Cu")
		(net "P2E_CPU_ETH10G_C_TX_DP10")
	)
	(segment
		(start 22.479 -13.7668)
		(end 22.5298 -13.8176)
		(width 0.1397)
		(layer "B.Cu")
		(net "P2E_CPU_ETH10G_C_TX_DP10")
	)
	(segment
		(start 42.32021 -35.414712)
		(end 42.018712 -35.414712)
		(width 0.1143)
		(layer "In2.Cu")
		(net "P2E_CPU_ETH10G_C_TX_DP10")
	)
	(segment
		(start 85.7758 -57.3532)
		(end 85.7758 -59.120532)
		(width 0.1016)
		(layer "In2.Cu")
		(net "P2E_CPU_ETH10G_C_TX_DP10")
	)
	(segment
		(start 85.570314 -59.326018)
		(end 85.480906 -59.326018)
		(width 0.1016)
		(layer "In2.Cu")
		(net "P2E_CPU_ETH10G_C_TX_DP10")
	)
	(segment
		(start 35.810698 -30.476698)
		(end 35.810698 -30.174946)
		(width 0.1143)
		(layer "In2.Cu")
		(net "P2E_CPU_ETH10G_C_TX_DP10")
	)
	(segment
		(start 42.018712 -35.414712)
		(end 40.94861 -34.34461)
		(width 0.1143)
		(layer "In2.Cu")
		(net "P2E_CPU_ETH10G_C_TX_DP10")
	)
	(segment
		(start 23.344632 -17.086326)
		(end 22.2377 -15.979394)
		(width 0.1143)
		(layer "In2.Cu")
		(net "P2E_CPU_ETH10G_C_TX_DP10")
	)
	(segment
		(start 35.810698 -30.174946)
		(end 35.568382 -29.93263)
		(width 0.1143)
		(layer "In2.Cu")
		(net "P2E_CPU_ETH10G_C_TX_DP10")
	)
	(segment
		(start 25.621742 -17.086326)
		(end 23.344632 -17.086326)
		(width 0.1143)
		(layer "In2.Cu")
		(net "P2E_CPU_ETH10G_C_TX_DP10")
	)
	(segment
		(start 36.597336 -31.263336)
		(end 36.597336 -30.961584)
		(width 0.1143)
		(layer "In2.Cu")
		(net "P2E_CPU_ETH10G_C_TX_DP10")
	)
	(segment
		(start 69.694806 -60.9473)
		(end 65.173606 -56.4261)
		(width 0.1143)
		(layer "In2.Cu")
		(net "P2E_CPU_ETH10G_C_TX_DP10")
	)
	(segment
		(start 61.049154 -54.514242)
		(end 61.049154 -54.21249)
		(width 0.1143)
		(layer "In2.Cu")
		(net "P2E_CPU_ETH10G_C_TX_DP10")
	)
	(segment
		(start 39.365428 -32.761428)
		(end 38.2524 -31.6484)
		(width 0.1143)
		(layer "In2.Cu")
		(net "P2E_CPU_ETH10G_C_TX_DP10")
	)
	(segment
		(start 64.08166 -56.21274)
		(end 63.73876 -56.21274)
		(width 0.1143)
		(layer "In2.Cu")
		(net "P2E_CPU_ETH10G_C_TX_DP10")
	)
	(segment
		(start 85.480906 -59.326018)
		(end 85.471508 -59.335416)
		(width 0.1016)
		(layer "In2.Cu")
		(net "P2E_CPU_ETH10G_C_TX_DP10")
	)
	(segment
		(start 39.66718 -32.761428)
		(end 39.365428 -32.761428)
		(width 0.1143)
		(layer "In2.Cu")
		(net "P2E_CPU_ETH10G_C_TX_DP10")
	)
	(segment
		(start 35.568382 -29.93263)
		(end 35.26663 -29.93263)
		(width 0.1143)
		(layer "In2.Cu")
		(net "P2E_CPU_ETH10G_C_TX_DP10")
	)
	(segment
		(start 65.173606 -56.4261)
		(end 64.29502 -56.4261)
		(width 0.1143)
		(layer "In2.Cu")
		(net "P2E_CPU_ETH10G_C_TX_DP10")
	)
	(segment
		(start 85.471508 -59.335416)
		(end 83.859624 -60.9473)
		(width 0.1143)
		(layer "In2.Cu")
		(net "P2E_CPU_ETH10G_C_TX_DP10")
	)
	(segment
		(start 36.597336 -30.961584)
		(end 36.35502 -30.719268)
		(width 0.1143)
		(layer "In2.Cu")
		(net "P2E_CPU_ETH10G_C_TX_DP10")
	)
	(segment
		(start 60.0202 -53.183536)
		(end 59.718448 -53.183536)
		(width 0.1143)
		(layer "In2.Cu")
		(net "P2E_CPU_ETH10G_C_TX_DP10")
	)
	(segment
		(start 34.112454 -25.577038)
		(end 33.026858 -24.491442)
		(width 0.1143)
		(layer "In2.Cu")
		(net "P2E_CPU_ETH10G_C_TX_DP10")
	)
	(segment
		(start 40.94861 -34.042858)
		(end 40.706294 -33.800542)
		(width 0.1143)
		(layer "In2.Cu")
		(net "P2E_CPU_ETH10G_C_TX_DP10")
	)
	(segment
		(start 32.24022 -23.403052)
		(end 31.99765 -23.160736)
		(width 0.1143)
		(layer "In2.Cu")
		(net "P2E_CPU_ETH10G_C_TX_DP10")
	)
	(segment
		(start 64.29502 -56.4261)
		(end 64.08166 -56.21274)
		(width 0.1143)
		(layer "In2.Cu")
		(net "P2E_CPU_ETH10G_C_TX_DP10")
	)
	(segment
		(start 76.8477 -60.5663)
		(end 76.4667 -60.9473)
		(width 0.1143)
		(layer "In2.Cu")
		(net "P2E_CPU_ETH10G_C_TX_DP10")
	)
	(segment
		(start 42.56278 -35.657028)
		(end 42.32021 -35.414712)
		(width 0.1143)
		(layer "In2.Cu")
		(net "P2E_CPU_ETH10G_C_TX_DP10")
	)
	(segment
		(start 39.909496 -33.305496)
		(end 39.909496 -33.003744)
		(width 0.1143)
		(layer "In2.Cu")
		(net "P2E_CPU_ETH10G_C_TX_DP10")
	)
	(segment
		(start 40.404542 -33.800542)
		(end 39.909496 -33.305496)
		(width 0.1143)
		(layer "In2.Cu")
		(net "P2E_CPU_ETH10G_C_TX_DP10")
	)
	(segment
		(start 32.48279 -23.947374)
		(end 32.24022 -23.704804)
		(width 0.1143)
		(layer "In2.Cu")
		(net "P2E_CPU_ETH10G_C_TX_DP10")
	)
	(segment
		(start 88.7857 -54.9021)
		(end 88.0872 -55.6006)
		(width 0.1016)
		(layer "In2.Cu")
		(net "P2E_CPU_ETH10G_C_TX_DP10")
	)
	(segment
		(start 54.555644 -46.575218)
		(end 50.057812 -42.077386)
		(width 0.1143)
		(layer "In2.Cu")
		(net "P2E_CPU_ETH10G_C_TX_DP10")
	)
	(segment
		(start 36.9824 -31.6484)
		(end 36.597336 -31.263336)
		(width 0.1143)
		(layer "In2.Cu")
		(net "P2E_CPU_ETH10G_C_TX_DP10")
	)
	(segment
		(start 39.909496 -33.003744)
		(end 39.66718 -32.761428)
		(width 0.1143)
		(layer "In2.Cu")
		(net "P2E_CPU_ETH10G_C_TX_DP10")
	)
	(segment
		(start 60.262516 -53.727604)
		(end 60.262516 -53.425852)
		(width 0.1143)
		(layer "In2.Cu")
		(net "P2E_CPU_ETH10G_C_TX_DP10")
	)
	(segment
		(start 36.053268 -30.719268)
		(end 35.810698 -30.476698)
		(width 0.1143)
		(layer "In2.Cu")
		(net "P2E_CPU_ETH10G_C_TX_DP10")
	)
	(segment
		(start 38.2524 -31.6484)
		(end 36.9824 -31.6484)
		(width 0.1143)
		(layer "In2.Cu")
		(net "P2E_CPU_ETH10G_C_TX_DP10")
	)
	(segment
		(start 34.112454 -28.778454)
		(end 34.112454 -25.577038)
		(width 0.1143)
		(layer "In2.Cu")
		(net "P2E_CPU_ETH10G_C_TX_DP10")
	)
	(segment
		(start 70.4088 -60.9473)
		(end 69.694806 -60.9473)
		(width 0.1143)
		(layer "In2.Cu")
		(net "P2E_CPU_ETH10G_C_TX_DP10")
	)
	(segment
		(start 83.859624 -60.9473)
		(end 78.965806 -60.9473)
		(width 0.1143)
		(layer "In2.Cu")
		(net "P2E_CPU_ETH10G_C_TX_DP10")
	)
	(segment
		(start 40.94861 -34.34461)
		(end 40.94861 -34.042858)
		(width 0.1143)
		(layer "In2.Cu")
		(net "P2E_CPU_ETH10G_C_TX_DP10")
	)
	(segment
		(start 45.085 -38.8874)
		(end 43.97883 -37.78123)
		(width 0.1143)
		(layer "In2.Cu")
		(net "P2E_CPU_ETH10G_C_TX_DP10")
	)
	(segment
		(start 60.505086 -53.970174)
		(end 60.262516 -53.727604)
		(width 0.1143)
		(layer "In2.Cu")
		(net "P2E_CPU_ETH10G_C_TX_DP10")
	)
	(segment
		(start 63.73876 -56.21274)
		(end 63.5254 -56.4261)
		(width 0.1143)
		(layer "In2.Cu")
		(net "P2E_CPU_ETH10G_C_TX_DP10")
	)
	(segment
		(start 76.4667 -60.9473)
		(end 72.755506 -60.9473)
		(width 0.1143)
		(layer "In2.Cu")
		(net "P2E_CPU_ETH10G_C_TX_DP10")
	)
	(segment
		(start 61.049154 -54.21249)
		(end 60.806838 -53.970174)
		(width 0.1143)
		(layer "In2.Cu")
		(net "P2E_CPU_ETH10G_C_TX_DP10")
	)
	(segment
		(start 72.374506 -60.5663)
		(end 70.7898 -60.5663)
		(width 0.1143)
		(layer "In2.Cu")
		(net "P2E_CPU_ETH10G_C_TX_DP10")
	)
	(segment
		(start 33.026858 -24.18969)
		(end 32.784542 -23.947374)
		(width 0.1143)
		(layer "In2.Cu")
		(net "P2E_CPU_ETH10G_C_TX_DP10")
	)
	(segment
		(start 59.718448 -53.183536)
		(end 54.555644 -48.020732)
		(width 0.1143)
		(layer "In2.Cu")
		(net "P2E_CPU_ETH10G_C_TX_DP10")
	)
	(segment
		(start 89.624154 -53.7083)
		(end 89.1667 -53.7083)
		(width 0.1016)
		(layer "In2.Cu")
		(net "P2E_CPU_ETH10G_C_TX_DP10")
	)
	(segment
		(start 85.7758 -59.120532)
		(end 85.570314 -59.326018)
		(width 0.1016)
		(layer "In2.Cu")
		(net "P2E_CPU_ETH10G_C_TX_DP10")
	)
	(segment
		(start 33.026858 -24.491442)
		(end 33.026858 -24.18969)
		(width 0.1143)
		(layer "In2.Cu")
		(net "P2E_CPU_ETH10G_C_TX_DP10")
	)
	(segment
		(start 22.2377 -14.1097)
		(end 22.5298 -13.8176)
		(width 0.1143)
		(layer "In2.Cu")
		(net "P2E_CPU_ETH10G_C_TX_DP10")
	)
	(segment
		(start 22.2377 -15.979394)
		(end 22.2377 -14.1097)
		(width 0.1143)
		(layer "In2.Cu")
		(net "P2E_CPU_ETH10G_C_TX_DP10")
	)
	(segment
		(start 89.812876 -53.519578)
		(end 89.624154 -53.7083)
		(width 0.1016)
		(layer "In2.Cu")
		(net "P2E_CPU_ETH10G_C_TX_DP10")
	)
	(segment
		(start 31.696152 -23.160736)
		(end 25.621742 -17.086326)
		(width 0.1143)
		(layer "In2.Cu")
		(net "P2E_CPU_ETH10G_C_TX_DP10")
	)
	(segment
		(start 60.262516 -53.425852)
		(end 60.0202 -53.183536)
		(width 0.1143)
		(layer "In2.Cu")
		(net "P2E_CPU_ETH10G_C_TX_DP10")
	)
	(segment
		(start 50.057812 -42.077386)
		(end 50.057812 -40.762428)
		(width 0.1143)
		(layer "In2.Cu")
		(net "P2E_CPU_ETH10G_C_TX_DP10")
	)
	(segment
		(start 60.806838 -53.970174)
		(end 60.505086 -53.970174)
		(width 0.1143)
		(layer "In2.Cu")
		(net "P2E_CPU_ETH10G_C_TX_DP10")
	)
	(segment
		(start 31.99765 -23.160736)
		(end 31.696152 -23.160736)
		(width 0.1143)
		(layer "In2.Cu")
		(net "P2E_CPU_ETH10G_C_TX_DP10")
	)
	(segment
		(start 89.1667 -53.7083)
		(end 88.7857 -54.0893)
		(width 0.1016)
		(layer "In2.Cu")
		(net "P2E_CPU_ETH10G_C_TX_DP10")
	)
	(segment
		(start 78.584806 -60.5663)
		(end 76.8477 -60.5663)
		(width 0.1143)
		(layer "In2.Cu")
		(net "P2E_CPU_ETH10G_C_TX_DP10")
	)
	(segment
		(start 32.784542 -23.947374)
		(end 32.48279 -23.947374)
		(width 0.1143)
		(layer "In2.Cu")
		(net "P2E_CPU_ETH10G_C_TX_DP10")
	)
	(segment
		(start 43.97883 -37.78123)
		(end 43.97883 -37.37483)
		(width 0.1143)
		(layer "In2.Cu")
		(net "P2E_CPU_ETH10G_C_TX_DP10")
	)
	(segment
		(start 63.5254 -56.4261)
		(end 62.961012 -56.4261)
		(width 0.1143)
		(layer "In2.Cu")
		(net "P2E_CPU_ETH10G_C_TX_DP10")
	)
	(segment
		(start 43.97883 -37.37483)
		(end 42.56278 -35.95878)
		(width 0.1143)
		(layer "In2.Cu")
		(net "P2E_CPU_ETH10G_C_TX_DP10")
	)
	(segment
		(start 40.706294 -33.800542)
		(end 40.404542 -33.800542)
		(width 0.1143)
		(layer "In2.Cu")
		(net "P2E_CPU_ETH10G_C_TX_DP10")
	)
	(segment
		(start 54.555644 -48.020732)
		(end 54.555644 -46.575218)
		(width 0.1143)
		(layer "In2.Cu")
		(net "P2E_CPU_ETH10G_C_TX_DP10")
	)
	(segment
		(start 78.965806 -60.9473)
		(end 78.584806 -60.5663)
		(width 0.1143)
		(layer "In2.Cu")
		(net "P2E_CPU_ETH10G_C_TX_DP10")
	)
	(segment
		(start 88.0872 -55.6006)
		(end 87.5284 -55.6006)
		(width 0.1016)
		(layer "In2.Cu")
		(net "P2E_CPU_ETH10G_C_TX_DP10")
	)
	(segment
		(start 32.24022 -23.704804)
		(end 32.24022 -23.403052)
		(width 0.1143)
		(layer "In2.Cu")
		(net "P2E_CPU_ETH10G_C_TX_DP10")
	)
	(segment
		(start 70.7898 -60.5663)
		(end 70.4088 -60.9473)
		(width 0.1143)
		(layer "In2.Cu")
		(net "P2E_CPU_ETH10G_C_TX_DP10")
	)
	(segment
		(start 50.057812 -40.762428)
		(end 48.182784 -38.8874)
		(width 0.1143)
		(layer "In2.Cu")
		(net "P2E_CPU_ETH10G_C_TX_DP10")
	)
	(segment
		(start 42.56278 -35.95878)
		(end 42.56278 -35.657028)
		(width 0.1143)
		(layer "In2.Cu")
		(net "P2E_CPU_ETH10G_C_TX_DP10")
	)
	(segment
		(start 36.35502 -30.719268)
		(end 36.053268 -30.719268)
		(width 0.1143)
		(layer "In2.Cu")
		(net "P2E_CPU_ETH10G_C_TX_DP10")
	)
	(segment
		(start 87.5284 -55.6006)
		(end 85.7758 -57.3532)
		(width 0.1016)
		(layer "In2.Cu")
		(net "P2E_CPU_ETH10G_C_TX_DP10")
	)
	(segment
		(start 35.26663 -29.93263)
		(end 34.112454 -28.778454)
		(width 0.1143)
		(layer "In2.Cu")
		(net "P2E_CPU_ETH10G_C_TX_DP10")
	)
	(segment
		(start 72.755506 -60.9473)
		(end 72.374506 -60.5663)
		(width 0.1143)
		(layer "In2.Cu")
		(net "P2E_CPU_ETH10G_C_TX_DP10")
	)
	(segment
		(start 88.7857 -54.0893)
		(end 88.7857 -54.9021)
		(width 0.1016)
		(layer "In2.Cu")
		(net "P2E_CPU_ETH10G_C_TX_DP10")
	)
	(segment
		(start 48.182784 -38.8874)
		(end 45.085 -38.8874)
		(width 0.1143)
		(layer "In2.Cu")
		(net "P2E_CPU_ETH10G_C_TX_DP10")
	)
	(segment
		(start 62.961012 -56.4261)
		(end 61.049154 -54.514242)
		(width 0.1143)
		(layer "In2.Cu")
		(net "P2E_CPU_ETH10G_C_TX_DP10")
	)
	(segment
		(start 88.885268 -54.116732)
		(end 88.5317 -54.4703)
		(width 0.1016)
		(layer "F.Cu")
		(net "P2E_CPU_ETH10G_C_TX_DP9")
	)
	(segment
		(start 88.529668 -51.839114)
		(end 88.529668 -52.013866)
		(width 0.1016)
		(layer "F.Cu")
		(net "P2E_CPU_ETH10G_C_TX_DP9")
	)
	(segment
		(start 87.376508 -54.4703)
		(end 87.183468 -54.27726)
		(width 0.1016)
		(layer "F.Cu")
		(net "P2E_CPU_ETH10G_C_TX_DP9")
	)
	(segment
		(start 88.529668 -52.013866)
		(end 88.885268 -52.369466)
		(width 0.1016)
		(layer "F.Cu")
		(net "P2E_CPU_ETH10G_C_TX_DP9")
	)
	(segment
		(start 88.5317 -54.4703)
		(end 87.376508 -54.4703)
		(width 0.1016)
		(layer "F.Cu")
		(net "P2E_CPU_ETH10G_C_TX_DP9")
	)
	(segment
		(start 88.885268 -52.369466)
		(end 88.885268 -54.116732)
		(width 0.1016)
		(layer "F.Cu")
		(net "P2E_CPU_ETH10G_C_TX_DP9")
	)
	(via
		(at 26.2763 -13.8176)
		(size 0.508)
		(drill 0.254)
		(layers "F.Cu" "B.Cu")
		(net "P2E_CPU_ETH10G_C_TX_DP9")
	)
	(via
		(at 87.183468 -54.27726)
		(size 0.4318)
		(drill 0.2032)
		(layers "F.Cu" "B.Cu")
		(net "P2E_CPU_ETH10G_C_TX_DP9")
	)
	(segment
		(start 26.2255 -13.7668)
		(end 26.2763 -13.8176)
		(width 0.1397)
		(layer "B.Cu")
		(net "P2E_CPU_ETH10G_C_TX_DP9")
	)
	(segment
		(start 26.2255 -13.1572)
		(end 26.2255 -13.7668)
		(width 0.1397)
		(layer "B.Cu")
		(net "P2E_CPU_ETH10G_C_TX_DP9")
	)
	(segment
		(start 37.3126 -29.200094)
		(end 37.3126 -27.752294)
		(width 0.1143)
		(layer "In2.Cu")
		(net "P2E_CPU_ETH10G_C_TX_DP9")
	)
	(segment
		(start 26.380186 -16.016986)
		(end 26.681938 -16.016986)
		(width 0.1143)
		(layer "In2.Cu")
		(net "P2E_CPU_ETH10G_C_TX_DP9")
	)
	(segment
		(start 28.49753 -17.832578)
		(end 28.49753 -18.13433)
		(width 0.1143)
		(layer "In2.Cu")
		(net "P2E_CPU_ETH10G_C_TX_DP9")
	)
	(segment
		(start 55.520844 -45.655738)
		(end 55.520844 -47.638716)
		(width 0.1143)
		(layer "In2.Cu")
		(net "P2E_CPU_ETH10G_C_TX_DP9")
	)
	(segment
		(start 35.73399 -27.420316)
		(end 35.73399 -28.739084)
		(width 0.1143)
		(layer "In2.Cu")
		(net "P2E_CPU_ETH10G_C_TX_DP9")
	)
	(segment
		(start 54.32552 -44.460414)
		(end 55.520844 -45.655738)
		(width 0.1143)
		(layer "In2.Cu")
		(net "P2E_CPU_ETH10G_C_TX_DP9")
	)
	(segment
		(start 58.9026 -51.020472)
		(end 59.339734 -51.020472)
		(width 0.1143)
		(layer "In2.Cu")
		(net "P2E_CPU_ETH10G_C_TX_DP9")
	)
	(segment
		(start 62.015878 -53.696616)
		(end 62.015878 -54.13375)
		(width 0.1143)
		(layer "In2.Cu")
		(net "P2E_CPU_ETH10G_C_TX_DP9")
	)
	(segment
		(start 37.3126 -26.654506)
		(end 36.712906 -27.2542)
		(width 0.1143)
		(layer "In2.Cu")
		(net "P2E_CPU_ETH10G_C_TX_DP9")
	)
	(segment
		(start 69.708522 -59.6138)
		(end 82.688938 -59.6138)
		(width 0.1143)
		(layer "In2.Cu")
		(net "P2E_CPU_ETH10G_C_TX_DP9")
	)
	(segment
		(start 51.3334 -39.6494)
		(end 52.123086 -40.439086)
		(width 0.1143)
		(layer "In2.Cu")
		(net "P2E_CPU_ETH10G_C_TX_DP9")
	)
	(segment
		(start 27.468576 -16.803624)
		(end 27.710892 -17.04594)
		(width 0.1143)
		(layer "In2.Cu")
		(net "P2E_CPU_ETH10G_C_TX_DP9")
	)
	(segment
		(start 36.6522 -23.291038)
		(end 36.6522 -23.885906)
		(width 0.1143)
		(layer "In2.Cu")
		(net "P2E_CPU_ETH10G_C_TX_DP9")
	)
	(segment
		(start 86.72957 -54.419754)
		(end 87.040974 -54.419754)
		(width 0.1016)
		(layer "In2.Cu")
		(net "P2E_CPU_ETH10G_C_TX_DP9")
	)
	(segment
		(start 86.5124 -54.636924)
		(end 86.72957 -54.419754)
		(width 0.1016)
		(layer "In2.Cu")
		(net "P2E_CPU_ETH10G_C_TX_DP9")
	)
	(segment
		(start 35.73399 -24.7396)
		(end 36.06419 -25.0698)
		(width 0.1143)
		(layer "In2.Cu")
		(net "P2E_CPU_ETH10G_C_TX_DP9")
	)
	(segment
		(start 40.539162 -32.184594)
		(end 40.840914 -32.184594)
		(width 0.1143)
		(layer "In2.Cu")
		(net "P2E_CPU_ETH10G_C_TX_DP9")
	)
	(segment
		(start 42.65676 -34.00044)
		(end 42.65676 -34.302192)
		(width 0.1143)
		(layer "In2.Cu")
		(net "P2E_CPU_ETH10G_C_TX_DP9")
	)
	(segment
		(start 45.094906 -35.4457)
		(end 46.306232 -36.657026)
		(width 0.1143)
		(layer "In2.Cu")
		(net "P2E_CPU_ETH10G_C_TX_DP9")
	)
	(segment
		(start 52.909724 -41.225724)
		(end 53.211476 -41.225724)
		(width 0.1143)
		(layer "In2.Cu")
		(net "P2E_CPU_ETH10G_C_TX_DP9")
	)
	(segment
		(start 52.123086 -40.439086)
		(end 52.424838 -40.439086)
		(width 0.1143)
		(layer "In2.Cu")
		(net "P2E_CPU_ETH10G_C_TX_DP9")
	)
	(segment
		(start 84.921598 -57.38114)
		(end 84.939632 -57.363106)
		(width 0.1016)
		(layer "In2.Cu")
		(net "P2E_CPU_ETH10G_C_TX_DP9")
	)
	(segment
		(start 56.736996 -48.553116)
		(end 56.979566 -48.795686)
		(width 0.1143)
		(layer "In2.Cu")
		(net "P2E_CPU_ETH10G_C_TX_DP9")
	)
	(segment
		(start 65.221358 -55.126636)
		(end 69.708522 -59.6138)
		(width 0.1143)
		(layer "In2.Cu")
		(net "P2E_CPU_ETH10G_C_TX_DP9")
	)
	(segment
		(start 55.520844 -47.638716)
		(end 56.435244 -48.553116)
		(width 0.1143)
		(layer "In2.Cu")
		(net "P2E_CPU_ETH10G_C_TX_DP9")
	)
	(segment
		(start 41.627552 -32.971232)
		(end 41.870122 -33.213802)
		(width 0.1143)
		(layer "In2.Cu")
		(net "P2E_CPU_ETH10G_C_TX_DP9")
	)
	(segment
		(start 26.924254 -16.259302)
		(end 26.924254 -16.561054)
		(width 0.1143)
		(layer "In2.Cu")
		(net "P2E_CPU_ETH10G_C_TX_DP9")
	)
	(segment
		(start 26.924254 -16.561054)
		(end 27.166824 -16.803624)
		(width 0.1143)
		(layer "In2.Cu")
		(net "P2E_CPU_ETH10G_C_TX_DP9")
	)
	(segment
		(start 36.712906 -27.2542)
		(end 35.900106 -27.2542)
		(width 0.1143)
		(layer "In2.Cu")
		(net "P2E_CPU_ETH10G_C_TX_DP9")
	)
	(segment
		(start 35.900106 -27.2542)
		(end 35.73399 -27.420316)
		(width 0.1143)
		(layer "In2.Cu")
		(net "P2E_CPU_ETH10G_C_TX_DP9")
	)
	(segment
		(start 42.65676 -34.302192)
		(end 43.800268 -35.4457)
		(width 0.1143)
		(layer "In2.Cu")
		(net "P2E_CPU_ETH10G_C_TX_DP9")
	)
	(segment
		(start 41.083484 -32.427164)
		(end 41.083484 -32.728916)
		(width 0.1143)
		(layer "In2.Cu")
		(net "P2E_CPU_ETH10G_C_TX_DP9")
	)
	(segment
		(start 28.7909 -18.4277)
		(end 31.788862 -18.4277)
		(width 0.1143)
		(layer "In2.Cu")
		(net "P2E_CPU_ETH10G_C_TX_DP9")
	)
	(segment
		(start 53.211476 -41.225724)
		(end 53.454046 -41.468294)
		(width 0.1143)
		(layer "In2.Cu")
		(net "P2E_CPU_ETH10G_C_TX_DP9")
	)
	(segment
		(start 39.30396 -28.27528)
		(end 39.30396 -30.54096)
		(width 0.1143)
		(layer "In2.Cu")
		(net "P2E_CPU_ETH10G_C_TX_DP9")
	)
	(segment
		(start 59.339734 -51.020472)
		(end 62.015878 -53.696616)
		(width 0.1143)
		(layer "In2.Cu")
		(net "P2E_CPU_ETH10G_C_TX_DP9")
	)
	(segment
		(start 26.035 -14.0589)
		(end 26.035 -15.6718)
		(width 0.1143)
		(layer "In2.Cu")
		(net "P2E_CPU_ETH10G_C_TX_DP9")
	)
	(segment
		(start 36.255706 -24.2824)
		(end 35.88639 -24.2824)
		(width 0.1143)
		(layer "In2.Cu")
		(net "P2E_CPU_ETH10G_C_TX_DP9")
	)
	(segment
		(start 27.166824 -16.803624)
		(end 27.468576 -16.803624)
		(width 0.1143)
		(layer "In2.Cu")
		(net "P2E_CPU_ETH10G_C_TX_DP9")
	)
	(segment
		(start 56.979566 -48.795686)
		(end 56.979566 -49.097438)
		(width 0.1143)
		(layer "In2.Cu")
		(net "P2E_CPU_ETH10G_C_TX_DP9")
	)
	(segment
		(start 53.454046 -41.468294)
		(end 53.454046 -41.770046)
		(width 0.1143)
		(layer "In2.Cu")
		(net "P2E_CPU_ETH10G_C_TX_DP9")
	)
	(segment
		(start 36.509706 -29.5148)
		(end 36.997894 -29.5148)
		(width 0.1143)
		(layer "In2.Cu")
		(net "P2E_CPU_ETH10G_C_TX_DP9")
	)
	(segment
		(start 41.083484 -32.728916)
		(end 41.3258 -32.971232)
		(width 0.1143)
		(layer "In2.Cu")
		(net "P2E_CPU_ETH10G_C_TX_DP9")
	)
	(segment
		(start 35.88639 -24.2824)
		(end 35.73399 -24.4348)
		(width 0.1143)
		(layer "In2.Cu")
		(net "P2E_CPU_ETH10G_C_TX_DP9")
	)
	(segment
		(start 47.093632 -37.444426)
		(end 48.087026 -37.444426)
		(width 0.1143)
		(layer "In2.Cu")
		(net "P2E_CPU_ETH10G_C_TX_DP9")
	)
	(segment
		(start 63.008764 -55.126636)
		(end 65.221358 -55.126636)
		(width 0.1143)
		(layer "In2.Cu")
		(net "P2E_CPU_ETH10G_C_TX_DP9")
	)
	(segment
		(start 27.953462 -17.590262)
		(end 28.255214 -17.590262)
		(width 0.1143)
		(layer "In2.Cu")
		(net "P2E_CPU_ETH10G_C_TX_DP9")
	)
	(segment
		(start 56.979566 -49.097438)
		(end 58.9026 -51.020472)
		(width 0.1143)
		(layer "In2.Cu")
		(net "P2E_CPU_ETH10G_C_TX_DP9")
	)
	(segment
		(start 54.32552 -42.64152)
		(end 54.32552 -44.460414)
		(width 0.1143)
		(layer "In2.Cu")
		(net "P2E_CPU_ETH10G_C_TX_DP9")
	)
	(segment
		(start 39.30396 -30.54096)
		(end 40.1828 -31.4198)
		(width 0.1143)
		(layer "In2.Cu")
		(net "P2E_CPU_ETH10G_C_TX_DP9")
	)
	(segment
		(start 52.424838 -40.439086)
		(end 52.667408 -40.681656)
		(width 0.1143)
		(layer "In2.Cu")
		(net "P2E_CPU_ETH10G_C_TX_DP9")
	)
	(segment
		(start 35.73399 -28.739084)
		(end 36.509706 -29.5148)
		(width 0.1143)
		(layer "In2.Cu")
		(net "P2E_CPU_ETH10G_C_TX_DP9")
	)
	(segment
		(start 36.890706 -25.0698)
		(end 37.3126 -25.491694)
		(width 0.1143)
		(layer "In2.Cu")
		(net "P2E_CPU_ETH10G_C_TX_DP9")
	)
	(segment
		(start 42.112438 -33.75787)
		(end 42.41419 -33.75787)
		(width 0.1143)
		(layer "In2.Cu")
		(net "P2E_CPU_ETH10G_C_TX_DP9")
	)
	(segment
		(start 26.035 -15.6718)
		(end 26.380186 -16.016986)
		(width 0.1143)
		(layer "In2.Cu")
		(net "P2E_CPU_ETH10G_C_TX_DP9")
	)
	(segment
		(start 84.939632 -57.363106)
		(end 85.029294 -57.363106)
		(width 0.1016)
		(layer "In2.Cu")
		(net "P2E_CPU_ETH10G_C_TX_DP9")
	)
	(segment
		(start 28.49753 -18.13433)
		(end 28.7909 -18.4277)
		(width 0.1143)
		(layer "In2.Cu")
		(net "P2E_CPU_ETH10G_C_TX_DP9")
	)
	(segment
		(start 37.3126 -27.752294)
		(end 37.683694 -27.3812)
		(width 0.1143)
		(layer "In2.Cu")
		(net "P2E_CPU_ETH10G_C_TX_DP9")
	)
	(segment
		(start 38.40988 -27.3812)
		(end 39.30396 -28.27528)
		(width 0.1143)
		(layer "In2.Cu")
		(net "P2E_CPU_ETH10G_C_TX_DP9")
	)
	(segment
		(start 40.1828 -31.828232)
		(end 40.539162 -32.184594)
		(width 0.1143)
		(layer "In2.Cu")
		(net "P2E_CPU_ETH10G_C_TX_DP9")
	)
	(segment
		(start 52.667408 -40.983408)
		(end 52.909724 -41.225724)
		(width 0.1143)
		(layer "In2.Cu")
		(net "P2E_CPU_ETH10G_C_TX_DP9")
	)
	(segment
		(start 82.688938 -59.6138)
		(end 84.921598 -57.38114)
		(width 0.1143)
		(layer "In2.Cu")
		(net "P2E_CPU_ETH10G_C_TX_DP9")
	)
	(segment
		(start 36.06419 -25.0698)
		(end 36.890706 -25.0698)
		(width 0.1143)
		(layer "In2.Cu")
		(net "P2E_CPU_ETH10G_C_TX_DP9")
	)
	(segment
		(start 41.3258 -32.971232)
		(end 41.627552 -32.971232)
		(width 0.1143)
		(layer "In2.Cu")
		(net "P2E_CPU_ETH10G_C_TX_DP9")
	)
	(segment
		(start 26.2763 -13.8176)
		(end 26.035 -14.0589)
		(width 0.1143)
		(layer "In2.Cu")
		(net "P2E_CPU_ETH10G_C_TX_DP9")
	)
	(segment
		(start 40.1828 -31.4198)
		(end 40.1828 -31.828232)
		(width 0.1143)
		(layer "In2.Cu")
		(net "P2E_CPU_ETH10G_C_TX_DP9")
	)
	(segment
		(start 36.6522 -23.885906)
		(end 36.255706 -24.2824)
		(width 0.1143)
		(layer "In2.Cu")
		(net "P2E_CPU_ETH10G_C_TX_DP9")
	)
	(segment
		(start 31.788862 -18.4277)
		(end 36.6522 -23.291038)
		(width 0.1143)
		(layer "In2.Cu")
		(net "P2E_CPU_ETH10G_C_TX_DP9")
	)
	(segment
		(start 41.870122 -33.515554)
		(end 42.112438 -33.75787)
		(width 0.1143)
		(layer "In2.Cu")
		(net "P2E_CPU_ETH10G_C_TX_DP9")
	)
	(segment
		(start 50.292 -39.6494)
		(end 51.3334 -39.6494)
		(width 0.1143)
		(layer "In2.Cu")
		(net "P2E_CPU_ETH10G_C_TX_DP9")
	)
	(segment
		(start 37.3126 -25.491694)
		(end 37.3126 -26.654506)
		(width 0.1143)
		(layer "In2.Cu")
		(net "P2E_CPU_ETH10G_C_TX_DP9")
	)
	(segment
		(start 35.73399 -24.4348)
		(end 35.73399 -24.7396)
		(width 0.1143)
		(layer "In2.Cu")
		(net "P2E_CPU_ETH10G_C_TX_DP9")
	)
	(segment
		(start 48.087026 -37.444426)
		(end 50.292 -39.6494)
		(width 0.1143)
		(layer "In2.Cu")
		(net "P2E_CPU_ETH10G_C_TX_DP9")
	)
	(segment
		(start 52.667408 -40.681656)
		(end 52.667408 -40.983408)
		(width 0.1143)
		(layer "In2.Cu")
		(net "P2E_CPU_ETH10G_C_TX_DP9")
	)
	(segment
		(start 46.8503 -37.201094)
		(end 47.093632 -37.444426)
		(width 0.1143)
		(layer "In2.Cu")
		(net "P2E_CPU_ETH10G_C_TX_DP9")
	)
	(segment
		(start 46.306232 -36.657026)
		(end 46.607984 -36.657026)
		(width 0.1143)
		(layer "In2.Cu")
		(net "P2E_CPU_ETH10G_C_TX_DP9")
	)
	(segment
		(start 46.607984 -36.657026)
		(end 46.8503 -36.899596)
		(width 0.1143)
		(layer "In2.Cu")
		(net "P2E_CPU_ETH10G_C_TX_DP9")
	)
	(segment
		(start 87.040974 -54.419754)
		(end 87.183468 -54.27726)
		(width 0.1016)
		(layer "In2.Cu")
		(net "P2E_CPU_ETH10G_C_TX_DP9")
	)
	(segment
		(start 46.8503 -36.899596)
		(end 46.8503 -37.201094)
		(width 0.1143)
		(layer "In2.Cu")
		(net "P2E_CPU_ETH10G_C_TX_DP9")
	)
	(segment
		(start 41.870122 -33.213802)
		(end 41.870122 -33.515554)
		(width 0.1143)
		(layer "In2.Cu")
		(net "P2E_CPU_ETH10G_C_TX_DP9")
	)
	(segment
		(start 40.840914 -32.184594)
		(end 41.083484 -32.427164)
		(width 0.1143)
		(layer "In2.Cu")
		(net "P2E_CPU_ETH10G_C_TX_DP9")
	)
	(segment
		(start 56.435244 -48.553116)
		(end 56.736996 -48.553116)
		(width 0.1143)
		(layer "In2.Cu")
		(net "P2E_CPU_ETH10G_C_TX_DP9")
	)
	(segment
		(start 42.41419 -33.75787)
		(end 42.65676 -34.00044)
		(width 0.1143)
		(layer "In2.Cu")
		(net "P2E_CPU_ETH10G_C_TX_DP9")
	)
	(segment
		(start 28.255214 -17.590262)
		(end 28.49753 -17.832578)
		(width 0.1143)
		(layer "In2.Cu")
		(net "P2E_CPU_ETH10G_C_TX_DP9")
	)
	(segment
		(start 53.454046 -41.770046)
		(end 54.32552 -42.64152)
		(width 0.1143)
		(layer "In2.Cu")
		(net "P2E_CPU_ETH10G_C_TX_DP9")
	)
	(segment
		(start 26.681938 -16.016986)
		(end 26.924254 -16.259302)
		(width 0.1143)
		(layer "In2.Cu")
		(net "P2E_CPU_ETH10G_C_TX_DP9")
	)
	(segment
		(start 62.015878 -54.13375)
		(end 63.008764 -55.126636)
		(width 0.1143)
		(layer "In2.Cu")
		(net "P2E_CPU_ETH10G_C_TX_DP9")
	)
	(segment
		(start 86.5124 -55.88)
		(end 86.5124 -54.636924)
		(width 0.1016)
		(layer "In2.Cu")
		(net "P2E_CPU_ETH10G_C_TX_DP9")
	)
	(segment
		(start 27.710892 -17.04594)
		(end 27.710892 -17.347692)
		(width 0.1143)
		(layer "In2.Cu")
		(net "P2E_CPU_ETH10G_C_TX_DP9")
	)
	(segment
		(start 27.710892 -17.347692)
		(end 27.953462 -17.590262)
		(width 0.1143)
		(layer "In2.Cu")
		(net "P2E_CPU_ETH10G_C_TX_DP9")
	)
	(segment
		(start 85.029294 -57.363106)
		(end 86.5124 -55.88)
		(width 0.1016)
		(layer "In2.Cu")
		(net "P2E_CPU_ETH10G_C_TX_DP9")
	)
	(segment
		(start 37.683694 -27.3812)
		(end 38.40988 -27.3812)
		(width 0.1143)
		(layer "In2.Cu")
		(net "P2E_CPU_ETH10G_C_TX_DP9")
	)
	(segment
		(start 43.800268 -35.4457)
		(end 45.094906 -35.4457)
		(width 0.1143)
		(layer "In2.Cu")
		(net "P2E_CPU_ETH10G_C_TX_DP9")
	)
	(segment
		(start 36.997894 -29.5148)
		(end 37.3126 -29.200094)
		(width 0.1143)
		(layer "In2.Cu")
		(net "P2E_CPU_ETH10G_C_TX_DP9")
	)
	(segment
		(start 89.149428 -51.7398)
		(end 89.449148 -51.099974)
		(width 0.1016)
		(layer "F.Cu")
		(net "P2E_CPU_ETH10G_C_TX_DN10")
	)
	(segment
		(start 89.75979 -54.076092)
		(end 89.291668 -53.60797)
		(width 0.1016)
		(layer "F.Cu")
		(net "P2E_CPU_ETH10G_C_TX_DN10")
	)
	(segment
		(start 89.291668 -52.20081)
		(end 89.149428 -52.05857)
		(width 0.1016)
		(layer "F.Cu")
		(net "P2E_CPU_ETH10G_C_TX_DN10")
	)
	(segment
		(start 89.149428 -52.05857)
		(end 89.149428 -51.7398)
		(width 0.1016)
		(layer "F.Cu")
		(net "P2E_CPU_ETH10G_C_TX_DN10")
	)
	(segment
		(start 89.291668 -53.60797)
		(end 89.291668 -52.20081)
		(width 0.1016)
		(layer "F.Cu")
		(net "P2E_CPU_ETH10G_C_TX_DN10")
	)
	(via
		(at 89.75979 -54.076092)
		(size 0.4318)
		(drill 0.2032)
		(layers "F.Cu" "B.Cu")
		(net "P2E_CPU_ETH10G_C_TX_DN10")
	)
	(via
		(at 21.6662 -13.8176)
		(size 0.508)
		(drill 0.254)
		(layers "F.Cu" "B.Cu")
		(net "P2E_CPU_ETH10G_C_TX_DN10")
	)
	(segment
		(start 21.717 -13.1572)
		(end 21.717 -13.7668)
		(width 0.1397)
		(layer "B.Cu")
		(net "P2E_CPU_ETH10G_C_TX_DN10")
	)
	(segment
		(start 21.717 -13.7668)
		(end 21.6662 -13.8176)
		(width 0.1397)
		(layer "B.Cu")
		(net "P2E_CPU_ETH10G_C_TX_DN10")
	)
	(segment
		(start 88.9889 -54.986428)
		(end 88.171528 -55.8038)
		(width 0.1016)
		(layer "In2.Cu")
		(net "P2E_CPU_ETH10G_C_TX_DN10")
	)
	(segment
		(start 36.845494 -31.9786)
		(end 33.782254 -28.91536)
		(width 0.1143)
		(layer "In2.Cu")
		(net "P2E_CPU_ETH10G_C_TX_DN10")
	)
	(segment
		(start 70.926706 -60.8965)
		(end 70.545706 -61.2775)
		(width 0.1143)
		(layer "In2.Cu")
		(net "P2E_CPU_ETH10G_C_TX_DN10")
	)
	(segment
		(start 87.612728 -55.8038)
		(end 85.979 -57.437528)
		(width 0.1016)
		(layer "In2.Cu")
		(net "P2E_CPU_ETH10G_C_TX_DN10")
	)
	(segment
		(start 85.723222 -59.460638)
		(end 85.723222 -59.550808)
		(width 0.1016)
		(layer "In2.Cu")
		(net "P2E_CPU_ETH10G_C_TX_DN10")
	)
	(segment
		(start 48.045878 -39.2176)
		(end 44.948094 -39.2176)
		(width 0.1143)
		(layer "In2.Cu")
		(net "P2E_CPU_ETH10G_C_TX_DN10")
	)
	(segment
		(start 25.484836 -17.416526)
		(end 23.207726 -17.416526)
		(width 0.1143)
		(layer "In2.Cu")
		(net "P2E_CPU_ETH10G_C_TX_DN10")
	)
	(segment
		(start 83.99653 -61.2775)
		(end 78.8289 -61.2775)
		(width 0.1143)
		(layer "In2.Cu")
		(net "P2E_CPU_ETH10G_C_TX_DN10")
	)
	(segment
		(start 62.824106 -56.7563)
		(end 54.225444 -48.157638)
		(width 0.1143)
		(layer "In2.Cu")
		(net "P2E_CPU_ETH10G_C_TX_DN10")
	)
	(segment
		(start 78.8289 -61.2775)
		(end 78.4479 -60.8965)
		(width 0.1143)
		(layer "In2.Cu")
		(net "P2E_CPU_ETH10G_C_TX_DN10")
	)
	(segment
		(start 49.727612 -40.899334)
		(end 48.045878 -39.2176)
		(width 0.1143)
		(layer "In2.Cu")
		(net "P2E_CPU_ETH10G_C_TX_DN10")
	)
	(segment
		(start 85.979 -57.437528)
		(end 85.979 -59.20486)
		(width 0.1016)
		(layer "In2.Cu")
		(net "P2E_CPU_ETH10G_C_TX_DN10")
	)
	(segment
		(start 21.9075 -14.0589)
		(end 21.6662 -13.8176)
		(width 0.1143)
		(layer "In2.Cu")
		(net "P2E_CPU_ETH10G_C_TX_DN10")
	)
	(segment
		(start 23.207726 -17.416526)
		(end 21.9075 -16.1163)
		(width 0.1143)
		(layer "In2.Cu")
		(net "P2E_CPU_ETH10G_C_TX_DN10")
	)
	(segment
		(start 89.251028 -53.9115)
		(end 88.9889 -54.173628)
		(width 0.1016)
		(layer "In2.Cu")
		(net "P2E_CPU_ETH10G_C_TX_DN10")
	)
	(segment
		(start 89.75979 -54.076092)
		(end 89.595198 -53.9115)
		(width 0.1016)
		(layer "In2.Cu")
		(net "P2E_CPU_ETH10G_C_TX_DN10")
	)
	(segment
		(start 49.727612 -42.214292)
		(end 49.727612 -40.899334)
		(width 0.1143)
		(layer "In2.Cu")
		(net "P2E_CPU_ETH10G_C_TX_DN10")
	)
	(segment
		(start 89.595198 -53.9115)
		(end 89.251028 -53.9115)
		(width 0.1016)
		(layer "In2.Cu")
		(net "P2E_CPU_ETH10G_C_TX_DN10")
	)
	(segment
		(start 33.782254 -28.91536)
		(end 33.782254 -25.713944)
		(width 0.1143)
		(layer "In2.Cu")
		(net "P2E_CPU_ETH10G_C_TX_DN10")
	)
	(segment
		(start 85.723222 -59.550808)
		(end 85.704934 -59.569096)
		(width 0.1016)
		(layer "In2.Cu")
		(net "P2E_CPU_ETH10G_C_TX_DN10")
	)
	(segment
		(start 43.64863 -37.918136)
		(end 43.64863 -37.511736)
		(width 0.1143)
		(layer "In2.Cu")
		(net "P2E_CPU_ETH10G_C_TX_DN10")
	)
	(segment
		(start 38.115494 -31.9786)
		(end 36.845494 -31.9786)
		(width 0.1143)
		(layer "In2.Cu")
		(net "P2E_CPU_ETH10G_C_TX_DN10")
	)
	(segment
		(start 76.984606 -60.8965)
		(end 76.603606 -61.2775)
		(width 0.1143)
		(layer "In2.Cu")
		(net "P2E_CPU_ETH10G_C_TX_DN10")
	)
	(segment
		(start 33.782254 -25.713944)
		(end 25.484836 -17.416526)
		(width 0.1143)
		(layer "In2.Cu")
		(net "P2E_CPU_ETH10G_C_TX_DN10")
	)
	(segment
		(start 88.9889 -54.173628)
		(end 88.9889 -54.986428)
		(width 0.1016)
		(layer "In2.Cu")
		(net "P2E_CPU_ETH10G_C_TX_DN10")
	)
	(segment
		(start 65.0367 -56.7563)
		(end 62.824106 -56.7563)
		(width 0.1143)
		(layer "In2.Cu")
		(net "P2E_CPU_ETH10G_C_TX_DN10")
	)
	(segment
		(start 70.545706 -61.2775)
		(end 69.5579 -61.2775)
		(width 0.1143)
		(layer "In2.Cu")
		(net "P2E_CPU_ETH10G_C_TX_DN10")
	)
	(segment
		(start 54.225444 -48.157638)
		(end 54.225444 -46.712124)
		(width 0.1143)
		(layer "In2.Cu")
		(net "P2E_CPU_ETH10G_C_TX_DN10")
	)
	(segment
		(start 43.64863 -37.511736)
		(end 38.115494 -31.9786)
		(width 0.1143)
		(layer "In2.Cu")
		(net "P2E_CPU_ETH10G_C_TX_DN10")
	)
	(segment
		(start 72.2376 -60.8965)
		(end 70.926706 -60.8965)
		(width 0.1143)
		(layer "In2.Cu")
		(net "P2E_CPU_ETH10G_C_TX_DN10")
	)
	(segment
		(start 85.704934 -59.569096)
		(end 83.99653 -61.2775)
		(width 0.1143)
		(layer "In2.Cu")
		(net "P2E_CPU_ETH10G_C_TX_DN10")
	)
	(segment
		(start 78.4479 -60.8965)
		(end 76.984606 -60.8965)
		(width 0.1143)
		(layer "In2.Cu")
		(net "P2E_CPU_ETH10G_C_TX_DN10")
	)
	(segment
		(start 21.9075 -16.1163)
		(end 21.9075 -14.0589)
		(width 0.1143)
		(layer "In2.Cu")
		(net "P2E_CPU_ETH10G_C_TX_DN10")
	)
	(segment
		(start 88.171528 -55.8038)
		(end 87.612728 -55.8038)
		(width 0.1016)
		(layer "In2.Cu")
		(net "P2E_CPU_ETH10G_C_TX_DN10")
	)
	(segment
		(start 44.948094 -39.2176)
		(end 43.64863 -37.918136)
		(width 0.1143)
		(layer "In2.Cu")
		(net "P2E_CPU_ETH10G_C_TX_DN10")
	)
	(segment
		(start 72.6186 -61.2775)
		(end 72.2376 -60.8965)
		(width 0.1143)
		(layer "In2.Cu")
		(net "P2E_CPU_ETH10G_C_TX_DN10")
	)
	(segment
		(start 76.603606 -61.2775)
		(end 72.6186 -61.2775)
		(width 0.1143)
		(layer "In2.Cu")
		(net "P2E_CPU_ETH10G_C_TX_DN10")
	)
	(segment
		(start 54.225444 -46.712124)
		(end 49.727612 -42.214292)
		(width 0.1143)
		(layer "In2.Cu")
		(net "P2E_CPU_ETH10G_C_TX_DN10")
	)
	(segment
		(start 85.979 -59.20486)
		(end 85.723222 -59.460638)
		(width 0.1016)
		(layer "In2.Cu")
		(net "P2E_CPU_ETH10G_C_TX_DN10")
	)
	(segment
		(start 69.5579 -61.2775)
		(end 65.0367 -56.7563)
		(width 0.1143)
		(layer "In2.Cu")
		(net "P2E_CPU_ETH10G_C_TX_DN10")
	)
	(segment
		(start 88.671908 -53.603652)
		(end 88.671908 -52.443634)
		(width 0.1016)
		(layer "F.Cu")
		(net "P2E_CPU_ETH10G_C_TX_DN8")
	)
	(segment
		(start 88.671908 -52.443634)
		(end 88.21801 -51.989736)
		(width 0.1016)
		(layer "F.Cu")
		(net "P2E_CPU_ETH10G_C_TX_DN8")
	)
	(segment
		(start 88.21801 -51.989736)
		(end 87.948008 -51.442874)
		(width 0.1016)
		(layer "F.Cu")
		(net "P2E_CPU_ETH10G_C_TX_DN8")
	)
	(segment
		(start 88.306656 -53.968904)
		(end 88.671908 -53.603652)
		(width 0.1016)
		(layer "F.Cu")
		(net "P2E_CPU_ETH10G_C_TX_DN8")
	)
	(via
		(at 88.306656 -53.968904)
		(size 0.4318)
		(drill 0.2032)
		(layers "F.Cu" "B.Cu")
		(net "P2E_CPU_ETH10G_C_TX_DN8")
	)
	(via
		(at 29.4132 -14.5796)
		(size 0.508)
		(drill 0.254)
		(layers "F.Cu" "B.Cu")
		(net "P2E_CPU_ETH10G_C_TX_DN8")
	)
	(segment
		(start 29.67355 -14.31925)
		(end 29.4132 -14.5796)
		(width 0.1397)
		(layer "B.Cu")
		(net "P2E_CPU_ETH10G_C_TX_DN8")
	)
	(segment
		(start 29.67355 -13.36675)
		(end 29.67355 -14.31925)
		(width 0.1397)
		(layer "B.Cu")
		(net "P2E_CPU_ETH10G_C_TX_DN8")
	)
	(segment
		(start 29.464 -13.1572)
		(end 29.67355 -13.36675)
		(width 0.1397)
		(layer "B.Cu")
		(net "P2E_CPU_ETH10G_C_TX_DN8")
	)
	(segment
		(start 48.901604 -36.822126)
		(end 48.377094 -36.822126)
		(width 0.1143)
		(layer "In2.Cu")
		(net "P2E_CPU_ETH10G_C_TX_DN8")
	)
	(segment
		(start 48.377094 -36.822126)
		(end 47.962312 -36.407344)
		(width 0.1143)
		(layer "In2.Cu")
		(net "P2E_CPU_ETH10G_C_TX_DN8")
	)
	(segment
		(start 45.844206 -33.5153)
		(end 44.769786 -34.58972)
		(width 0.1143)
		(layer "In2.Cu")
		(net "P2E_CPU_ETH10G_C_TX_DN8")
	)
	(segment
		(start 65.4558 -53.594)
		(end 62.793372 -53.594)
		(width 0.1143)
		(layer "In2.Cu")
		(net "P2E_CPU_ETH10G_C_TX_DN8")
	)
	(segment
		(start 59.124596 -50.362358)
		(end 57.776872 -49.014634)
		(width 0.1143)
		(layer "In2.Cu")
		(net "P2E_CPU_ETH10G_C_TX_DN8")
	)
	(segment
		(start 46.0502 -35.520884)
		(end 46.0502 -34.6964)
		(width 0.1143)
		(layer "In2.Cu")
		(net "P2E_CPU_ETH10G_C_TX_DN8")
	)
	(segment
		(start 29.6799 -16.6243)
		(end 29.6799 -14.8463)
		(width 0.1143)
		(layer "In2.Cu")
		(net "P2E_CPU_ETH10G_C_TX_DN8")
	)
	(segment
		(start 40.792908 -26.517092)
		(end 31.954216 -17.6784)
		(width 0.1143)
		(layer "In2.Cu")
		(net "P2E_CPU_ETH10G_C_TX_DN8")
	)
	(segment
		(start 46.484794 -33.5153)
		(end 45.844206 -33.5153)
		(width 0.1143)
		(layer "In2.Cu")
		(net "P2E_CPU_ETH10G_C_TX_DN8")
	)
	(segment
		(start 59.56173 -50.362358)
		(end 59.124596 -50.362358)
		(width 0.1143)
		(layer "In2.Cu")
		(net "P2E_CPU_ETH10G_C_TX_DN8")
	)
	(segment
		(start 56.143144 -45.397928)
		(end 54.94782 -44.202604)
		(width 0.1143)
		(layer "In2.Cu")
		(net "P2E_CPU_ETH10G_C_TX_DN8")
	)
	(segment
		(start 52.0192 -38.354)
		(end 51.7906 -38.5826)
		(width 0.1143)
		(layer "In2.Cu")
		(net "P2E_CPU_ETH10G_C_TX_DN8")
	)
	(segment
		(start 46.0502 -34.6964)
		(end 46.6852 -34.0614)
		(width 0.1143)
		(layer "In2.Cu")
		(net "P2E_CPU_ETH10G_C_TX_DN8")
	)
	(segment
		(start 88.306656 -53.968904)
		(end 88.071452 -53.7337)
		(width 0.1016)
		(layer "In2.Cu")
		(net "P2E_CPU_ETH10G_C_TX_DN8")
	)
	(segment
		(start 84.354416 -57.33034)
		(end 82.693256 -58.9915)
		(width 0.1143)
		(layer "In2.Cu")
		(net "P2E_CPU_ETH10G_C_TX_DN8")
	)
	(segment
		(start 84.365084 -57.222644)
		(end 84.365084 -57.319672)
		(width 0.1016)
		(layer "In2.Cu")
		(net "P2E_CPU_ETH10G_C_TX_DN8")
	)
	(segment
		(start 46.526958 -35.997642)
		(end 46.0502 -35.520884)
		(width 0.1143)
		(layer "In2.Cu")
		(net "P2E_CPU_ETH10G_C_TX_DN8")
	)
	(segment
		(start 57.144412 -47.849028)
		(end 56.611266 -47.849028)
		(width 0.1143)
		(layer "In2.Cu")
		(net "P2E_CPU_ETH10G_C_TX_DN8")
	)
	(segment
		(start 86.3092 -55.735728)
		(end 85.428328 -56.6166)
		(width 0.1016)
		(layer "In2.Cu")
		(net "P2E_CPU_ETH10G_C_TX_DN8")
	)
	(segment
		(start 57.776872 -49.014634)
		(end 57.776872 -48.481488)
		(width 0.1143)
		(layer "In2.Cu")
		(net "P2E_CPU_ETH10G_C_TX_DN8")
	)
	(segment
		(start 46.6852 -34.0614)
		(end 46.6852 -33.715706)
		(width 0.1143)
		(layer "In2.Cu")
		(net "P2E_CPU_ETH10G_C_TX_DN8")
	)
	(segment
		(start 84.971128 -56.6166)
		(end 84.365084 -57.222644)
		(width 0.1016)
		(layer "In2.Cu")
		(net "P2E_CPU_ETH10G_C_TX_DN8")
	)
	(segment
		(start 44.769786 -34.58972)
		(end 44.11472 -34.58972)
		(width 0.1143)
		(layer "In2.Cu")
		(net "P2E_CPU_ETH10G_C_TX_DN8")
	)
	(segment
		(start 47.962312 -35.882834)
		(end 47.786798 -35.70732)
		(width 0.1143)
		(layer "In2.Cu")
		(net "P2E_CPU_ETH10G_C_TX_DN8")
	)
	(segment
		(start 87.1093 -53.7337)
		(end 86.3092 -54.5338)
		(width 0.1016)
		(layer "In2.Cu")
		(net "P2E_CPU_ETH10G_C_TX_DN8")
	)
	(segment
		(start 56.611266 -47.849028)
		(end 56.143144 -47.380906)
		(width 0.1143)
		(layer "In2.Cu")
		(net "P2E_CPU_ETH10G_C_TX_DN8")
	)
	(segment
		(start 51.2318 -38.5826)
		(end 50.816002 -38.166802)
		(width 0.1143)
		(layer "In2.Cu")
		(net "P2E_CPU_ETH10G_C_TX_DN8")
	)
	(segment
		(start 70.386194 -58.9915)
		(end 69.977 -58.582306)
		(width 0.1143)
		(layer "In2.Cu")
		(net "P2E_CPU_ETH10G_C_TX_DN8")
	)
	(segment
		(start 29.6799 -14.8463)
		(end 29.4132 -14.5796)
		(width 0.1143)
		(layer "In2.Cu")
		(net "P2E_CPU_ETH10G_C_TX_DN8")
	)
	(segment
		(start 47.962312 -36.407344)
		(end 47.962312 -35.882834)
		(width 0.1143)
		(layer "In2.Cu")
		(net "P2E_CPU_ETH10G_C_TX_DN8")
	)
	(segment
		(start 47.786798 -35.70732)
		(end 47.432214 -35.70732)
		(width 0.1143)
		(layer "In2.Cu")
		(net "P2E_CPU_ETH10G_C_TX_DN8")
	)
	(segment
		(start 47.141892 -35.997642)
		(end 46.526958 -35.997642)
		(width 0.1143)
		(layer "In2.Cu")
		(net "P2E_CPU_ETH10G_C_TX_DN8")
	)
	(segment
		(start 88.071452 -53.7337)
		(end 87.1093 -53.7337)
		(width 0.1016)
		(layer "In2.Cu")
		(net "P2E_CPU_ETH10G_C_TX_DN8")
	)
	(segment
		(start 51.7906 -38.5826)
		(end 51.2318 -38.5826)
		(width 0.1143)
		(layer "In2.Cu")
		(net "P2E_CPU_ETH10G_C_TX_DN8")
	)
	(segment
		(start 53.922168 -38.354)
		(end 52.0192 -38.354)
		(width 0.1143)
		(layer "In2.Cu")
		(net "P2E_CPU_ETH10G_C_TX_DN8")
	)
	(segment
		(start 40.792908 -30.655006)
		(end 40.792908 -26.517092)
		(width 0.1143)
		(layer "In2.Cu")
		(net "P2E_CPU_ETH10G_C_TX_DN8")
	)
	(segment
		(start 69.977 -58.582306)
		(end 69.977 -57.642506)
		(width 0.1143)
		(layer "In2.Cu")
		(net "P2E_CPU_ETH10G_C_TX_DN8")
	)
	(segment
		(start 57.776872 -48.481488)
		(end 57.144412 -47.849028)
		(width 0.1143)
		(layer "In2.Cu")
		(net "P2E_CPU_ETH10G_C_TX_DN8")
	)
	(segment
		(start 65.914778 -54.933596)
		(end 65.914778 -54.052978)
		(width 0.1143)
		(layer "In2.Cu")
		(net "P2E_CPU_ETH10G_C_TX_DN8")
	)
	(segment
		(start 86.3092 -54.5338)
		(end 86.3092 -55.735728)
		(width 0.1016)
		(layer "In2.Cu")
		(net "P2E_CPU_ETH10G_C_TX_DN8")
	)
	(segment
		(start 68.376038 -57.394856)
		(end 65.914778 -54.933596)
		(width 0.1143)
		(layer "In2.Cu")
		(net "P2E_CPU_ETH10G_C_TX_DN8")
	)
	(segment
		(start 43.740324 -33.602422)
		(end 40.792908 -30.655006)
		(width 0.1143)
		(layer "In2.Cu")
		(net "P2E_CPU_ETH10G_C_TX_DN8")
	)
	(segment
		(start 85.428328 -56.6166)
		(end 84.971128 -56.6166)
		(width 0.1016)
		(layer "In2.Cu")
		(net "P2E_CPU_ETH10G_C_TX_DN8")
	)
	(segment
		(start 65.914778 -54.052978)
		(end 65.4558 -53.594)
		(width 0.1143)
		(layer "In2.Cu")
		(net "P2E_CPU_ETH10G_C_TX_DN8")
	)
	(segment
		(start 54.94782 -44.202604)
		(end 54.94782 -39.379652)
		(width 0.1143)
		(layer "In2.Cu")
		(net "P2E_CPU_ETH10G_C_TX_DN8")
	)
	(segment
		(start 82.693256 -58.9915)
		(end 70.386194 -58.9915)
		(width 0.1143)
		(layer "In2.Cu")
		(net "P2E_CPU_ETH10G_C_TX_DN8")
	)
	(segment
		(start 46.6852 -33.715706)
		(end 46.484794 -33.5153)
		(width 0.1143)
		(layer "In2.Cu")
		(net "P2E_CPU_ETH10G_C_TX_DN8")
	)
	(segment
		(start 84.365084 -57.319672)
		(end 84.354416 -57.33034)
		(width 0.1016)
		(layer "In2.Cu")
		(net "P2E_CPU_ETH10G_C_TX_DN8")
	)
	(segment
		(start 50.24628 -38.166802)
		(end 48.901604 -36.822126)
		(width 0.1143)
		(layer "In2.Cu")
		(net "P2E_CPU_ETH10G_C_TX_DN8")
	)
	(segment
		(start 54.94782 -39.379652)
		(end 53.922168 -38.354)
		(width 0.1143)
		(layer "In2.Cu")
		(net "P2E_CPU_ETH10G_C_TX_DN8")
	)
	(segment
		(start 30.734 -17.6784)
		(end 29.6799 -16.6243)
		(width 0.1143)
		(layer "In2.Cu")
		(net "P2E_CPU_ETH10G_C_TX_DN8")
	)
	(segment
		(start 44.11472 -34.58972)
		(end 43.740324 -34.215324)
		(width 0.1143)
		(layer "In2.Cu")
		(net "P2E_CPU_ETH10G_C_TX_DN8")
	)
	(segment
		(start 50.816002 -38.166802)
		(end 50.24628 -38.166802)
		(width 0.1143)
		(layer "In2.Cu")
		(net "P2E_CPU_ETH10G_C_TX_DN8")
	)
	(segment
		(start 56.143144 -47.380906)
		(end 56.143144 -45.397928)
		(width 0.1143)
		(layer "In2.Cu")
		(net "P2E_CPU_ETH10G_C_TX_DN8")
	)
	(segment
		(start 47.432214 -35.70732)
		(end 47.141892 -35.997642)
		(width 0.1143)
		(layer "In2.Cu")
		(net "P2E_CPU_ETH10G_C_TX_DN8")
	)
	(segment
		(start 31.954216 -17.6784)
		(end 30.734 -17.6784)
		(width 0.1143)
		(layer "In2.Cu")
		(net "P2E_CPU_ETH10G_C_TX_DN8")
	)
	(segment
		(start 43.740324 -34.215324)
		(end 43.740324 -33.602422)
		(width 0.1143)
		(layer "In2.Cu")
		(net "P2E_CPU_ETH10G_C_TX_DN8")
	)
	(segment
		(start 69.977 -57.642506)
		(end 69.72935 -57.394856)
		(width 0.1143)
		(layer "In2.Cu")
		(net "P2E_CPU_ETH10G_C_TX_DN8")
	)
	(segment
		(start 69.72935 -57.394856)
		(end 68.376038 -57.394856)
		(width 0.1143)
		(layer "In2.Cu")
		(net "P2E_CPU_ETH10G_C_TX_DN8")
	)
	(segment
		(start 62.793372 -53.594)
		(end 59.56173 -50.362358)
		(width 0.1143)
		(layer "In2.Cu")
		(net "P2E_CPU_ETH10G_C_TX_DN8")
	)
	(segment
		(start 88.288622 -53.402738)
		(end 88.468708 -53.222652)
		(width 0.1016)
		(layer "F.Cu")
		(net "P2E_CPU_ETH10G_C_TX_DP8")
	)
	(segment
		(start 88.468708 -53.222652)
		(end 88.468708 -52.738274)
		(width 0.1016)
		(layer "F.Cu")
		(net "P2E_CPU_ETH10G_C_TX_DP8")
	)
	(segment
		(start 88.468708 -52.738274)
		(end 88.179148 -52.448714)
		(width 0.1016)
		(layer "F.Cu")
		(net "P2E_CPU_ETH10G_C_TX_DP8")
	)
	(segment
		(start 88.288622 -53.410358)
		(end 88.288622 -53.402738)
		(width 0.1016)
		(layer "F.Cu")
		(net "P2E_CPU_ETH10G_C_TX_DP8")
	)
	(via
		(at 88.288622 -53.410358)
		(size 0.4318)
		(drill 0.2032)
		(layers "F.Cu" "B.Cu")
		(net "P2E_CPU_ETH10G_C_TX_DP8")
	)
	(via
		(at 30.2768 -14.5796)
		(size 0.508)
		(drill 0.254)
		(layers "F.Cu" "B.Cu")
		(net "P2E_CPU_ETH10G_C_TX_DP8")
	)
	(segment
		(start 30.226 -13.1572)
		(end 30.01645 -13.36675)
		(width 0.1397)
		(layer "B.Cu")
		(net "P2E_CPU_ETH10G_C_TX_DP8")
	)
	(segment
		(start 30.01645 -13.36675)
		(end 30.01645 -14.31925)
		(width 0.1397)
		(layer "B.Cu")
		(net "P2E_CPU_ETH10G_C_TX_DP8")
	)
	(segment
		(start 30.01645 -14.31925)
		(end 30.2768 -14.5796)
		(width 0.1397)
		(layer "B.Cu")
		(net "P2E_CPU_ETH10G_C_TX_DP8")
	)
	(segment
		(start 50.383186 -37.836602)
		(end 49.03851 -36.491926)
		(width 0.1143)
		(layer "In2.Cu")
		(net "P2E_CPU_ETH10G_C_TX_DP8")
	)
	(segment
		(start 30.870906 -17.3482)
		(end 30.0101 -16.487394)
		(width 0.1143)
		(layer "In2.Cu")
		(net "P2E_CPU_ETH10G_C_TX_DP8")
	)
	(segment
		(start 46.663864 -35.667442)
		(end 46.3804 -35.383978)
		(width 0.1143)
		(layer "In2.Cu")
		(net "P2E_CPU_ETH10G_C_TX_DP8")
	)
	(segment
		(start 47.923704 -35.37712)
		(end 47.295308 -35.37712)
		(width 0.1143)
		(layer "In2.Cu")
		(net "P2E_CPU_ETH10G_C_TX_DP8")
	)
	(segment
		(start 82.55635 -58.6613)
		(end 71.63562 -58.6613)
		(width 0.1143)
		(layer "In2.Cu")
		(net "P2E_CPU_ETH10G_C_TX_DP8")
	)
	(segment
		(start 67.701922 -55.951882)
		(end 67.40017 -55.951882)
		(width 0.1143)
		(layer "In2.Cu")
		(net "P2E_CPU_ETH10G_C_TX_DP8")
	)
	(segment
		(start 44.070524 -33.465516)
		(end 43.915838 -33.31083)
		(width 0.1143)
		(layer "In2.Cu")
		(net "P2E_CPU_ETH10G_C_TX_DP8")
	)
	(segment
		(start 49.03851 -36.491926)
		(end 48.514 -36.491926)
		(width 0.1143)
		(layer "In2.Cu")
		(net "P2E_CPU_ETH10G_C_TX_DP8")
	)
	(segment
		(start 41.123108 -28.945332)
		(end 41.123108 -28.602432)
		(width 0.1143)
		(layer "In2.Cu")
		(net "P2E_CPU_ETH10G_C_TX_DP8")
	)
	(segment
		(start 51.882294 -38.0238)
		(end 51.653694 -38.2524)
		(width 0.1143)
		(layer "In2.Cu")
		(net "P2E_CPU_ETH10G_C_TX_DP8")
	)
	(segment
		(start 61.88964 -52.223162)
		(end 61.64707 -51.980592)
		(width 0.1143)
		(layer "In2.Cu")
		(net "P2E_CPU_ETH10G_C_TX_DP8")
	)
	(segment
		(start 56.473344 -47.244)
		(end 56.473344 -45.261022)
		(width 0.1143)
		(layer "In2.Cu")
		(net "P2E_CPU_ETH10G_C_TX_DP8")
	)
	(segment
		(start 65.592706 -53.2638)
		(end 62.930278 -53.2638)
		(width 0.1143)
		(layer "In2.Cu")
		(net "P2E_CPU_ETH10G_C_TX_DP8")
	)
	(segment
		(start 37.326062 -22.58314)
		(end 37.083492 -22.34057)
		(width 0.1143)
		(layer "In2.Cu")
		(net "P2E_CPU_ETH10G_C_TX_DP8")
	)
	(segment
		(start 84.203286 -57.096914)
		(end 84.120736 -57.096914)
		(width 0.1016)
		(layer "In2.Cu")
		(net "P2E_CPU_ETH10G_C_TX_DP8")
	)
	(segment
		(start 62.433708 -52.465478)
		(end 62.191392 -52.223162)
		(width 0.1143)
		(layer "In2.Cu")
		(net "P2E_CPU_ETH10G_C_TX_DP8")
	)
	(segment
		(start 37.083492 -22.34057)
		(end 37.083492 -22.038818)
		(width 0.1143)
		(layer "In2.Cu")
		(net "P2E_CPU_ETH10G_C_TX_DP8")
	)
	(segment
		(start 32.091122 -17.3482)
		(end 30.870906 -17.3482)
		(width 0.1143)
		(layer "In2.Cu")
		(net "P2E_CPU_ETH10G_C_TX_DP8")
	)
	(segment
		(start 60.860432 -50.892202)
		(end 60.618116 -50.649886)
		(width 0.1143)
		(layer "In2.Cu")
		(net "P2E_CPU_ETH10G_C_TX_DP8")
	)
	(segment
		(start 41.123108 -28.602432)
		(end 41.336468 -28.389072)
		(width 0.1143)
		(layer "In2.Cu")
		(net "P2E_CPU_ETH10G_C_TX_DP8")
	)
	(segment
		(start 70.5231 -58.6613)
		(end 70.3072 -58.4454)
		(width 0.1143)
		(layer "In2.Cu")
		(net "P2E_CPU_ETH10G_C_TX_DP8")
	)
	(segment
		(start 67.944238 -56.194198)
		(end 67.701922 -55.951882)
		(width 0.1143)
		(layer "In2.Cu")
		(net "P2E_CPU_ETH10G_C_TX_DP8")
	)
	(segment
		(start 42.585132 -31.980124)
		(end 42.342562 -31.737554)
		(width 0.1143)
		(layer "In2.Cu")
		(net "P2E_CPU_ETH10G_C_TX_DP8")
	)
	(segment
		(start 41.336468 -28.389072)
		(end 41.336468 -28.046172)
		(width 0.1143)
		(layer "In2.Cu")
		(net "P2E_CPU_ETH10G_C_TX_DP8")
	)
	(segment
		(start 42.342562 -31.435802)
		(end 42.100246 -31.193486)
		(width 0.1143)
		(layer "In2.Cu")
		(net "P2E_CPU_ETH10G_C_TX_DP8")
	)
	(segment
		(start 44.63288 -34.25952)
		(end 44.251626 -34.25952)
		(width 0.1143)
		(layer "In2.Cu")
		(net "P2E_CPU_ETH10G_C_TX_DP8")
	)
	(segment
		(start 30.0101 -14.8463)
		(end 30.2768 -14.5796)
		(width 0.1143)
		(layer "In2.Cu")
		(net "P2E_CPU_ETH10G_C_TX_DP8")
	)
	(segment
		(start 68.512944 -57.064656)
		(end 67.944238 -56.49595)
		(width 0.1143)
		(layer "In2.Cu")
		(net "P2E_CPU_ETH10G_C_TX_DP8")
	)
	(segment
		(start 44.070524 -34.078418)
		(end 44.070524 -33.465516)
		(width 0.1143)
		(layer "In2.Cu")
		(net "P2E_CPU_ETH10G_C_TX_DP8")
	)
	(segment
		(start 59.261502 -50.032158)
		(end 58.107072 -48.877728)
		(width 0.1143)
		(layer "In2.Cu")
		(net "P2E_CPU_ETH10G_C_TX_DP8")
	)
	(segment
		(start 61.64707 -51.980592)
		(end 61.64707 -51.67884)
		(width 0.1143)
		(layer "In2.Cu")
		(net "P2E_CPU_ETH10G_C_TX_DP8")
	)
	(segment
		(start 48.292512 -36.270438)
		(end 48.292512 -35.745928)
		(width 0.1143)
		(layer "In2.Cu")
		(net "P2E_CPU_ETH10G_C_TX_DP8")
	)
	(segment
		(start 36.054538 -21.009864)
		(end 35.752786 -21.009864)
		(width 0.1143)
		(layer "In2.Cu")
		(net "P2E_CPU_ETH10G_C_TX_DP8")
	)
	(segment
		(start 35.752786 -21.009864)
		(end 32.091122 -17.3482)
		(width 0.1143)
		(layer "In2.Cu")
		(net "P2E_CPU_ETH10G_C_TX_DP8")
	)
	(segment
		(start 48.292512 -35.745928)
		(end 47.923704 -35.37712)
		(width 0.1143)
		(layer "In2.Cu")
		(net "P2E_CPU_ETH10G_C_TX_DP8")
	)
	(segment
		(start 88.288622 -53.410358)
		(end 88.16848 -53.5305)
		(width 0.1016)
		(layer "In2.Cu")
		(net "P2E_CPU_ETH10G_C_TX_DP8")
	)
	(segment
		(start 58.107072 -48.344582)
		(end 57.281318 -47.518828)
		(width 0.1143)
		(layer "In2.Cu")
		(net "P2E_CPU_ETH10G_C_TX_DP8")
	)
	(segment
		(start 62.191392 -52.223162)
		(end 61.88964 -52.223162)
		(width 0.1143)
		(layer "In2.Cu")
		(net "P2E_CPU_ETH10G_C_TX_DP8")
	)
	(segment
		(start 47.004986 -35.667442)
		(end 46.663864 -35.667442)
		(width 0.1143)
		(layer "In2.Cu")
		(net "P2E_CPU_ETH10G_C_TX_DP8")
	)
	(segment
		(start 41.123108 -27.832812)
		(end 41.123108 -26.380186)
		(width 0.1143)
		(layer "In2.Cu")
		(net "P2E_CPU_ETH10G_C_TX_DP8")
	)
	(segment
		(start 47.0154 -34.198306)
		(end 47.0154 -33.5788)
		(width 0.1143)
		(layer "In2.Cu")
		(net "P2E_CPU_ETH10G_C_TX_DP8")
	)
	(segment
		(start 46.3804 -34.833306)
		(end 47.0154 -34.198306)
		(width 0.1143)
		(layer "In2.Cu")
		(net "P2E_CPU_ETH10G_C_TX_DP8")
	)
	(segment
		(start 44.251626 -34.25952)
		(end 44.070524 -34.078418)
		(width 0.1143)
		(layer "In2.Cu")
		(net "P2E_CPU_ETH10G_C_TX_DP8")
	)
	(segment
		(start 59.698636 -50.032158)
		(end 59.261502 -50.032158)
		(width 0.1143)
		(layer "In2.Cu")
		(net "P2E_CPU_ETH10G_C_TX_DP8")
	)
	(segment
		(start 61.103002 -51.436524)
		(end 60.860432 -51.193954)
		(width 0.1143)
		(layer "In2.Cu")
		(net "P2E_CPU_ETH10G_C_TX_DP8")
	)
	(segment
		(start 41.336468 -28.046172)
		(end 41.123108 -27.832812)
		(width 0.1143)
		(layer "In2.Cu")
		(net "P2E_CPU_ETH10G_C_TX_DP8")
	)
	(segment
		(start 66.244978 -53.916072)
		(end 65.592706 -53.2638)
		(width 0.1143)
		(layer "In2.Cu")
		(net "P2E_CPU_ETH10G_C_TX_DP8")
	)
	(segment
		(start 60.618116 -50.649886)
		(end 60.316364 -50.649886)
		(width 0.1143)
		(layer "In2.Cu")
		(net "P2E_CPU_ETH10G_C_TX_DP8")
	)
	(segment
		(start 30.0101 -16.487394)
		(end 30.0101 -14.8463)
		(width 0.1143)
		(layer "In2.Cu")
		(net "P2E_CPU_ETH10G_C_TX_DP8")
	)
	(segment
		(start 60.316364 -50.649886)
		(end 59.698636 -50.032158)
		(width 0.1143)
		(layer "In2.Cu")
		(net "P2E_CPU_ETH10G_C_TX_DP8")
	)
	(segment
		(start 88.16848 -53.5305)
		(end 87.024972 -53.5305)
		(width 0.1016)
		(layer "In2.Cu")
		(net "P2E_CPU_ETH10G_C_TX_DP8")
	)
	(segment
		(start 57.281318 -47.518828)
		(end 56.748172 -47.518828)
		(width 0.1143)
		(layer "In2.Cu")
		(net "P2E_CPU_ETH10G_C_TX_DP8")
	)
	(segment
		(start 36.296854 -21.25218)
		(end 36.054538 -21.009864)
		(width 0.1143)
		(layer "In2.Cu")
		(net "P2E_CPU_ETH10G_C_TX_DP8")
	)
	(segment
		(start 40.638222 -25.593548)
		(end 40.33647 -25.593548)
		(width 0.1143)
		(layer "In2.Cu")
		(net "P2E_CPU_ETH10G_C_TX_DP8")
	)
	(segment
		(start 45.7073 -33.1851)
		(end 44.63288 -34.25952)
		(width 0.1143)
		(layer "In2.Cu")
		(net "P2E_CPU_ETH10G_C_TX_DP8")
	)
	(segment
		(start 42.886884 -31.980124)
		(end 42.585132 -31.980124)
		(width 0.1143)
		(layer "In2.Cu")
		(net "P2E_CPU_ETH10G_C_TX_DP8")
	)
	(segment
		(start 56.473344 -45.261022)
		(end 55.27802 -44.065698)
		(width 0.1143)
		(layer "In2.Cu")
		(net "P2E_CPU_ETH10G_C_TX_DP8")
	)
	(segment
		(start 37.627814 -22.58314)
		(end 37.326062 -22.58314)
		(width 0.1143)
		(layer "In2.Cu")
		(net "P2E_CPU_ETH10G_C_TX_DP8")
	)
	(segment
		(start 67.944238 -56.49595)
		(end 67.944238 -56.194198)
		(width 0.1143)
		(layer "In2.Cu")
		(net "P2E_CPU_ETH10G_C_TX_DP8")
	)
	(segment
		(start 43.37177 -32.766762)
		(end 43.1292 -32.524192)
		(width 0.1143)
		(layer "In2.Cu")
		(net "P2E_CPU_ETH10G_C_TX_DP8")
	)
	(segment
		(start 51.653694 -38.2524)
		(end 51.368706 -38.2524)
		(width 0.1143)
		(layer "In2.Cu")
		(net "P2E_CPU_ETH10G_C_TX_DP8")
	)
	(segment
		(start 41.123108 -30.5181)
		(end 41.123108 -29.714952)
		(width 0.1143)
		(layer "In2.Cu")
		(net "P2E_CPU_ETH10G_C_TX_DP8")
	)
	(segment
		(start 37.87013 -22.825456)
		(end 37.627814 -22.58314)
		(width 0.1143)
		(layer "In2.Cu")
		(net "P2E_CPU_ETH10G_C_TX_DP8")
	)
	(segment
		(start 37.083492 -22.038818)
		(end 36.841176 -21.796502)
		(width 0.1143)
		(layer "In2.Cu")
		(net "P2E_CPU_ETH10G_C_TX_DP8")
	)
	(segment
		(start 70.866 -58.6613)
		(end 70.5231 -58.6613)
		(width 0.1143)
		(layer "In2.Cu")
		(net "P2E_CPU_ETH10G_C_TX_DP8")
	)
	(segment
		(start 40.880538 -26.137616)
		(end 40.880538 -25.835864)
		(width 0.1143)
		(layer "In2.Cu")
		(net "P2E_CPU_ETH10G_C_TX_DP8")
	)
	(segment
		(start 43.915838 -33.009078)
		(end 43.673522 -32.766762)
		(width 0.1143)
		(layer "In2.Cu")
		(net "P2E_CPU_ETH10G_C_TX_DP8")
	)
	(segment
		(start 62.930278 -53.2638)
		(end 62.433708 -52.76723)
		(width 0.1143)
		(layer "In2.Cu")
		(net "P2E_CPU_ETH10G_C_TX_DP8")
	)
	(segment
		(start 86.106 -54.449472)
		(end 86.106 -55.6514)
		(width 0.1016)
		(layer "In2.Cu")
		(net "P2E_CPU_ETH10G_C_TX_DP8")
	)
	(segment
		(start 36.539424 -21.796502)
		(end 36.296854 -21.553932)
		(width 0.1143)
		(layer "In2.Cu")
		(net "P2E_CPU_ETH10G_C_TX_DP8")
	)
	(segment
		(start 51.368706 -38.2524)
		(end 50.952908 -37.836602)
		(width 0.1143)
		(layer "In2.Cu")
		(net "P2E_CPU_ETH10G_C_TX_DP8")
	)
	(segment
		(start 46.3804 -35.383978)
		(end 46.3804 -34.833306)
		(width 0.1143)
		(layer "In2.Cu")
		(net "P2E_CPU_ETH10G_C_TX_DP8")
	)
	(segment
		(start 41.336468 -29.158692)
		(end 41.123108 -28.945332)
		(width 0.1143)
		(layer "In2.Cu")
		(net "P2E_CPU_ETH10G_C_TX_DP8")
	)
	(segment
		(start 43.915838 -33.31083)
		(end 43.915838 -33.009078)
		(width 0.1143)
		(layer "In2.Cu")
		(net "P2E_CPU_ETH10G_C_TX_DP8")
	)
	(segment
		(start 61.404754 -51.436524)
		(end 61.103002 -51.436524)
		(width 0.1143)
		(layer "In2.Cu")
		(net "P2E_CPU_ETH10G_C_TX_DP8")
	)
	(segment
		(start 86.106 -55.6514)
		(end 85.344 -56.4134)
		(width 0.1016)
		(layer "In2.Cu")
		(net "P2E_CPU_ETH10G_C_TX_DP8")
	)
	(segment
		(start 36.841176 -21.796502)
		(end 36.539424 -21.796502)
		(width 0.1143)
		(layer "In2.Cu")
		(net "P2E_CPU_ETH10G_C_TX_DP8")
	)
	(segment
		(start 43.1292 -32.22244)
		(end 42.886884 -31.980124)
		(width 0.1143)
		(layer "In2.Cu")
		(net "P2E_CPU_ETH10G_C_TX_DP8")
	)
	(segment
		(start 47.295308 -35.37712)
		(end 47.004986 -35.667442)
		(width 0.1143)
		(layer "In2.Cu")
		(net "P2E_CPU_ETH10G_C_TX_DP8")
	)
	(segment
		(start 46.6217 -33.1851)
		(end 45.7073 -33.1851)
		(width 0.1143)
		(layer "In2.Cu")
		(net "P2E_CPU_ETH10G_C_TX_DP8")
	)
	(segment
		(start 71.07936 -58.44794)
		(end 70.866 -58.6613)
		(width 0.1143)
		(layer "In2.Cu")
		(net "P2E_CPU_ETH10G_C_TX_DP8")
	)
	(segment
		(start 61.64707 -51.67884)
		(end 61.404754 -51.436524)
		(width 0.1143)
		(layer "In2.Cu")
		(net "P2E_CPU_ETH10G_C_TX_DP8")
	)
	(segment
		(start 36.296854 -21.553932)
		(end 36.296854 -21.25218)
		(width 0.1143)
		(layer "In2.Cu")
		(net "P2E_CPU_ETH10G_C_TX_DP8")
	)
	(segment
		(start 55.27802 -44.065698)
		(end 55.27802 -39.242746)
		(width 0.1143)
		(layer "In2.Cu")
		(net "P2E_CPU_ETH10G_C_TX_DP8")
	)
	(segment
		(start 84.120736 -57.096914)
		(end 82.55635 -58.6613)
		(width 0.1143)
		(layer "In2.Cu")
		(net "P2E_CPU_ETH10G_C_TX_DP8")
	)
	(segment
		(start 40.33647 -25.593548)
		(end 37.87013 -23.127208)
		(width 0.1143)
		(layer "In2.Cu")
		(net "P2E_CPU_ETH10G_C_TX_DP8")
	)
	(segment
		(start 41.336468 -29.501592)
		(end 41.336468 -29.158692)
		(width 0.1143)
		(layer "In2.Cu")
		(net "P2E_CPU_ETH10G_C_TX_DP8")
	)
	(segment
		(start 67.40017 -55.951882)
		(end 66.244978 -54.79669)
		(width 0.1143)
		(layer "In2.Cu")
		(net "P2E_CPU_ETH10G_C_TX_DP8")
	)
	(segment
		(start 41.123108 -29.714952)
		(end 41.336468 -29.501592)
		(width 0.1143)
		(layer "In2.Cu")
		(net "P2E_CPU_ETH10G_C_TX_DP8")
	)
	(segment
		(start 43.1292 -32.524192)
		(end 43.1292 -32.22244)
		(width 0.1143)
		(layer "In2.Cu")
		(net "P2E_CPU_ETH10G_C_TX_DP8")
	)
	(segment
		(start 71.42226 -58.44794)
		(end 71.07936 -58.44794)
		(width 0.1143)
		(layer "In2.Cu")
		(net "P2E_CPU_ETH10G_C_TX_DP8")
	)
	(segment
		(start 48.514 -36.491926)
		(end 48.292512 -36.270438)
		(width 0.1143)
		(layer "In2.Cu")
		(net "P2E_CPU_ETH10G_C_TX_DP8")
	)
	(segment
		(start 85.344 -56.4134)
		(end 84.8868 -56.4134)
		(width 0.1016)
		(layer "In2.Cu")
		(net "P2E_CPU_ETH10G_C_TX_DP8")
	)
	(segment
		(start 41.798494 -31.193486)
		(end 41.123108 -30.5181)
		(width 0.1143)
		(layer "In2.Cu")
		(net "P2E_CPU_ETH10G_C_TX_DP8")
	)
	(segment
		(start 69.866256 -57.064656)
		(end 68.512944 -57.064656)
		(width 0.1143)
		(layer "In2.Cu")
		(net "P2E_CPU_ETH10G_C_TX_DP8")
	)
	(segment
		(start 62.433708 -52.76723)
		(end 62.433708 -52.465478)
		(width 0.1143)
		(layer "In2.Cu")
		(net "P2E_CPU_ETH10G_C_TX_DP8")
	)
	(segment
		(start 55.27802 -39.242746)
		(end 54.059074 -38.0238)
		(width 0.1143)
		(layer "In2.Cu")
		(net "P2E_CPU_ETH10G_C_TX_DP8")
	)
	(segment
		(start 58.107072 -48.877728)
		(end 58.107072 -48.344582)
		(width 0.1143)
		(layer "In2.Cu")
		(net "P2E_CPU_ETH10G_C_TX_DP8")
	)
	(segment
		(start 60.860432 -51.193954)
		(end 60.860432 -50.892202)
		(width 0.1143)
		(layer "In2.Cu")
		(net "P2E_CPU_ETH10G_C_TX_DP8")
	)
	(segment
		(start 42.100246 -31.193486)
		(end 41.798494 -31.193486)
		(width 0.1143)
		(layer "In2.Cu")
		(net "P2E_CPU_ETH10G_C_TX_DP8")
	)
	(segment
		(start 56.748172 -47.518828)
		(end 56.473344 -47.244)
		(width 0.1143)
		(layer "In2.Cu")
		(net "P2E_CPU_ETH10G_C_TX_DP8")
	)
	(segment
		(start 70.3072 -58.4454)
		(end 70.3072 -57.5056)
		(width 0.1143)
		(layer "In2.Cu")
		(net "P2E_CPU_ETH10G_C_TX_DP8")
	)
	(segment
		(start 40.880538 -25.835864)
		(end 40.638222 -25.593548)
		(width 0.1143)
		(layer "In2.Cu")
		(net "P2E_CPU_ETH10G_C_TX_DP8")
	)
	(segment
		(start 41.123108 -26.380186)
		(end 40.880538 -26.137616)
		(width 0.1143)
		(layer "In2.Cu")
		(net "P2E_CPU_ETH10G_C_TX_DP8")
	)
	(segment
		(start 37.87013 -23.127208)
		(end 37.87013 -22.825456)
		(width 0.1143)
		(layer "In2.Cu")
		(net "P2E_CPU_ETH10G_C_TX_DP8")
	)
	(segment
		(start 42.342562 -31.737554)
		(end 42.342562 -31.435802)
		(width 0.1143)
		(layer "In2.Cu")
		(net "P2E_CPU_ETH10G_C_TX_DP8")
	)
	(segment
		(start 54.059074 -38.0238)
		(end 51.882294 -38.0238)
		(width 0.1143)
		(layer "In2.Cu")
		(net "P2E_CPU_ETH10G_C_TX_DP8")
	)
	(segment
		(start 87.024972 -53.5305)
		(end 86.106 -54.449472)
		(width 0.1016)
		(layer "In2.Cu")
		(net "P2E_CPU_ETH10G_C_TX_DP8")
	)
	(segment
		(start 43.673522 -32.766762)
		(end 43.37177 -32.766762)
		(width 0.1143)
		(layer "In2.Cu")
		(net "P2E_CPU_ETH10G_C_TX_DP8")
	)
	(segment
		(start 50.952908 -37.836602)
		(end 50.383186 -37.836602)
		(width 0.1143)
		(layer "In2.Cu")
		(net "P2E_CPU_ETH10G_C_TX_DP8")
	)
	(segment
		(start 71.63562 -58.6613)
		(end 71.42226 -58.44794)
		(width 0.1143)
		(layer "In2.Cu")
		(net "P2E_CPU_ETH10G_C_TX_DP8")
	)
	(segment
		(start 84.8868 -56.4134)
		(end 84.203286 -57.096914)
		(width 0.1016)
		(layer "In2.Cu")
		(net "P2E_CPU_ETH10G_C_TX_DP8")
	)
	(segment
		(start 47.0154 -33.5788)
		(end 46.6217 -33.1851)
		(width 0.1143)
		(layer "In2.Cu")
		(net "P2E_CPU_ETH10G_C_TX_DP8")
	)
	(segment
		(start 70.3072 -57.5056)
		(end 69.866256 -57.064656)
		(width 0.1143)
		(layer "In2.Cu")
		(net "P2E_CPU_ETH10G_C_TX_DP8")
	)
	(segment
		(start 66.244978 -54.79669)
		(end 66.244978 -53.916072)
		(width 0.1143)
		(layer "In2.Cu")
		(net "P2E_CPU_ETH10G_C_TX_DP8")
	)
	(segment
		(start 86.792308 -51.772312)
		(end 86.792308 -51.503834)
		(width 0.1016)
		(layer "F.Cu")
		(net "P2E_CPU_SAS_C_TX_DN6")
	)
	(segment
		(start 87.224108 -52.204112)
		(end 86.792308 -51.772312)
		(width 0.1016)
		(layer "F.Cu")
		(net "P2E_CPU_SAS_C_TX_DN6")
	)
	(segment
		(start 87.224108 -52.91582)
		(end 87.224108 -52.204112)
		(width 0.1016)
		(layer "F.Cu")
		(net "P2E_CPU_SAS_C_TX_DN6")
	)
	(segment
		(start 86.3092 -53.5432)
		(end 86.596728 -53.5432)
		(width 0.1016)
		(layer "F.Cu")
		(net "P2E_CPU_SAS_C_TX_DN6")
	)
	(segment
		(start 86.087204 -53.765196)
		(end 86.3092 -53.5432)
		(width 0.1016)
		(layer "F.Cu")
		(net "P2E_CPU_SAS_C_TX_DN6")
	)
	(segment
		(start 86.596728 -53.5432)
		(end 87.224108 -52.91582)
		(width 0.1016)
		(layer "F.Cu")
		(net "P2E_CPU_SAS_C_TX_DN6")
	)
	(via
		(at 37.41801 -13.8176)
		(size 0.508)
		(drill 0.254)
		(layers "F.Cu" "B.Cu")
		(net "P2E_CPU_SAS_C_TX_DN6")
	)
	(via
		(at 86.087204 -53.765196)
		(size 0.4318)
		(drill 0.2032)
		(layers "F.Cu" "B.Cu")
		(net "P2E_CPU_SAS_C_TX_DN6")
	)
	(segment
		(start 37.46881 -13.7668)
		(end 37.41801 -13.8176)
		(width 0.1397)
		(layer "B.Cu")
		(net "P2E_CPU_SAS_C_TX_DN6")
	)
	(segment
		(start 37.46881 -13.1572)
		(end 37.46881 -13.7668)
		(width 0.1397)
		(layer "B.Cu")
		(net "P2E_CPU_SAS_C_TX_DN6")
	)
	(segment
		(start 75.226418 -56.4388)
		(end 74.661268 -55.87365)
		(width 0.1143)
		(layer "In2.Cu")
		(net "P2E_CPU_SAS_C_TX_DN6")
	)
	(segment
		(start 58.048144 -44.8691)
		(end 58.048144 -44.608496)
		(width 0.1143)
		(layer "In2.Cu")
		(net "P2E_CPU_SAS_C_TX_DN6")
	)
	(segment
		(start 54.07152 -27.460194)
		(end 51.9049 -25.293574)
		(width 0.1143)
		(layer "In2.Cu")
		(net "P2E_CPU_SAS_C_TX_DN6")
	)
	(segment
		(start 85.377528 -53.5686)
		(end 84.963 -53.983128)
		(width 0.1016)
		(layer "In2.Cu")
		(net "P2E_CPU_SAS_C_TX_DN6")
	)
	(segment
		(start 74.661268 -55.87365)
		(end 72.585834 -55.87365)
		(width 0.1143)
		(layer "In2.Cu")
		(net "P2E_CPU_SAS_C_TX_DN6")
	)
	(segment
		(start 54.07152 -35.80892)
		(end 54.07152 -27.460194)
		(width 0.1143)
		(layer "In2.Cu")
		(net "P2E_CPU_SAS_C_TX_DN6")
	)
	(segment
		(start 50.372518 -19.8755)
		(end 47.60595 -19.8755)
		(width 0.1143)
		(layer "In2.Cu")
		(net "P2E_CPU_SAS_C_TX_DN6")
	)
	(segment
		(start 79.542894 -57.15)
		(end 78.831694 -56.4388)
		(width 0.1143)
		(layer "In2.Cu")
		(net "P2E_CPU_SAS_C_TX_DN6")
	)
	(segment
		(start 56.871108 -38.608508)
		(end 54.07152 -35.80892)
		(width 0.1143)
		(layer "In2.Cu")
		(net "P2E_CPU_SAS_C_TX_DN6")
	)
	(segment
		(start 67.298062 -52.0065)
		(end 66.980562 -51.689)
		(width 0.1143)
		(layer "In2.Cu")
		(net "P2E_CPU_SAS_C_TX_DN6")
	)
	(segment
		(start 37.6809 -14.754606)
		(end 37.6809 -14.08049)
		(width 0.1143)
		(layer "In2.Cu")
		(net "P2E_CPU_SAS_C_TX_DN6")
	)
	(segment
		(start 56.871108 -43.43146)
		(end 56.871108 -38.608508)
		(width 0.1143)
		(layer "In2.Cu")
		(net "P2E_CPU_SAS_C_TX_DN6")
	)
	(segment
		(start 84.963 -54.872128)
		(end 83.014566 -56.820562)
		(width 0.1016)
		(layer "In2.Cu")
		(net "P2E_CPU_SAS_C_TX_DN6")
	)
	(segment
		(start 58.048144 -44.608496)
		(end 56.871108 -43.43146)
		(width 0.1143)
		(layer "In2.Cu")
		(net "P2E_CPU_SAS_C_TX_DN6")
	)
	(segment
		(start 83.005422 -56.919622)
		(end 82.97164 -56.95315)
		(width 0.1143)
		(layer "In2.Cu")
		(net "P2E_CPU_SAS_C_TX_DN6")
	)
	(segment
		(start 41.595294 -18.669)
		(end 37.6809 -14.754606)
		(width 0.1143)
		(layer "In2.Cu")
		(net "P2E_CPU_SAS_C_TX_DN6")
	)
	(segment
		(start 51.9049 -21.407882)
		(end 50.372518 -19.8755)
		(width 0.1143)
		(layer "In2.Cu")
		(net "P2E_CPU_SAS_C_TX_DN6")
	)
	(segment
		(start 51.9049 -25.293574)
		(end 51.9049 -21.407882)
		(width 0.1143)
		(layer "In2.Cu")
		(net "P2E_CPU_SAS_C_TX_DN6")
	)
	(segment
		(start 60.021216 -48.0314)
		(end 58.36285 -46.373034)
		(width 0.1143)
		(layer "In2.Cu")
		(net "P2E_CPU_SAS_C_TX_DN6")
	)
	(segment
		(start 83.014566 -56.910478)
		(end 83.005422 -56.919622)
		(width 0.1016)
		(layer "In2.Cu")
		(net "P2E_CPU_SAS_C_TX_DN6")
	)
	(segment
		(start 82.97164 -56.95315)
		(end 82.77479 -57.15)
		(width 0.1143)
		(layer "In2.Cu")
		(net "P2E_CPU_SAS_C_TX_DN6")
	)
	(segment
		(start 68.718684 -52.0065)
		(end 67.298062 -52.0065)
		(width 0.1143)
		(layer "In2.Cu")
		(net "P2E_CPU_SAS_C_TX_DN6")
	)
	(segment
		(start 46.39945 -18.669)
		(end 41.595294 -18.669)
		(width 0.1143)
		(layer "In2.Cu")
		(net "P2E_CPU_SAS_C_TX_DN6")
	)
	(segment
		(start 85.890608 -53.5686)
		(end 85.377528 -53.5686)
		(width 0.1016)
		(layer "In2.Cu")
		(net "P2E_CPU_SAS_C_TX_DN6")
	)
	(segment
		(start 47.60595 -19.8755)
		(end 46.39945 -18.669)
		(width 0.1143)
		(layer "In2.Cu")
		(net "P2E_CPU_SAS_C_TX_DN6")
	)
	(segment
		(start 86.087204 -53.765196)
		(end 85.890608 -53.5686)
		(width 0.1016)
		(layer "In2.Cu")
		(net "P2E_CPU_SAS_C_TX_DN6")
	)
	(segment
		(start 65.190878 -51.689)
		(end 61.533278 -48.0314)
		(width 0.1143)
		(layer "In2.Cu")
		(net "P2E_CPU_SAS_C_TX_DN6")
	)
	(segment
		(start 82.77479 -57.15)
		(end 79.542894 -57.15)
		(width 0.1143)
		(layer "In2.Cu")
		(net "P2E_CPU_SAS_C_TX_DN6")
	)
	(segment
		(start 84.963 -53.983128)
		(end 84.963 -54.872128)
		(width 0.1016)
		(layer "In2.Cu")
		(net "P2E_CPU_SAS_C_TX_DN6")
	)
	(segment
		(start 83.014566 -56.820562)
		(end 83.014566 -56.910478)
		(width 0.1016)
		(layer "In2.Cu")
		(net "P2E_CPU_SAS_C_TX_DN6")
	)
	(segment
		(start 37.6809 -14.08049)
		(end 37.41801 -13.8176)
		(width 0.1143)
		(layer "In2.Cu")
		(net "P2E_CPU_SAS_C_TX_DN6")
	)
	(segment
		(start 78.831694 -56.4388)
		(end 75.226418 -56.4388)
		(width 0.1143)
		(layer "In2.Cu")
		(net "P2E_CPU_SAS_C_TX_DN6")
	)
	(segment
		(start 72.585834 -55.87365)
		(end 68.718684 -52.0065)
		(width 0.1143)
		(layer "In2.Cu")
		(net "P2E_CPU_SAS_C_TX_DN6")
	)
	(segment
		(start 58.36285 -46.373034)
		(end 58.36285 -45.183806)
		(width 0.1143)
		(layer "In2.Cu")
		(net "P2E_CPU_SAS_C_TX_DN6")
	)
	(segment
		(start 66.980562 -51.689)
		(end 65.190878 -51.689)
		(width 0.1143)
		(layer "In2.Cu")
		(net "P2E_CPU_SAS_C_TX_DN6")
	)
	(segment
		(start 58.36285 -45.183806)
		(end 58.048144 -44.8691)
		(width 0.1143)
		(layer "In2.Cu")
		(net "P2E_CPU_SAS_C_TX_DN6")
	)
	(segment
		(start 61.533278 -48.0314)
		(end 60.021216 -48.0314)
		(width 0.1143)
		(layer "In2.Cu")
		(net "P2E_CPU_SAS_C_TX_DN6")
	)
	(segment
		(start 86.236048 -53.34)
		(end 86.097618 -53.20157)
		(width 0.1016)
		(layer "F.Cu")
		(net "P2E_CPU_SAS_C_TX_DP6")
	)
	(segment
		(start 86.487508 -51.75504)
		(end 87.018368 -52.2859)
		(width 0.1016)
		(layer "F.Cu")
		(net "P2E_CPU_SAS_C_TX_DP6")
	)
	(segment
		(start 87.018368 -52.305458)
		(end 87.020908 -52.307998)
		(width 0.1016)
		(layer "F.Cu")
		(net "P2E_CPU_SAS_C_TX_DP6")
	)
	(segment
		(start 86.487508 -51.3842)
		(end 86.487508 -51.75504)
		(width 0.1016)
		(layer "F.Cu")
		(net "P2E_CPU_SAS_C_TX_DP6")
	)
	(segment
		(start 87.020908 -52.831492)
		(end 86.5124 -53.34)
		(width 0.1016)
		(layer "F.Cu")
		(net "P2E_CPU_SAS_C_TX_DP6")
	)
	(segment
		(start 86.5124 -53.34)
		(end 86.236048 -53.34)
		(width 0.1016)
		(layer "F.Cu")
		(net "P2E_CPU_SAS_C_TX_DP6")
	)
	(segment
		(start 87.020908 -52.307998)
		(end 87.020908 -52.831492)
		(width 0.1016)
		(layer "F.Cu")
		(net "P2E_CPU_SAS_C_TX_DP6")
	)
	(segment
		(start 86.741508 -50.741834)
		(end 86.487508 -51.3842)
		(width 0.1016)
		(layer "F.Cu")
		(net "P2E_CPU_SAS_C_TX_DP6")
	)
	(segment
		(start 87.018368 -52.2859)
		(end 87.018368 -52.305458)
		(width 0.1016)
		(layer "F.Cu")
		(net "P2E_CPU_SAS_C_TX_DP6")
	)
	(via
		(at 38.28161 -13.8176)
		(size 0.508)
		(drill 0.254)
		(layers "F.Cu" "B.Cu")
		(net "P2E_CPU_SAS_C_TX_DP6")
	)
	(via
		(at 86.097618 -53.20157)
		(size 0.4318)
		(drill 0.2032)
		(layers "F.Cu" "B.Cu")
		(net "P2E_CPU_SAS_C_TX_DP6")
	)
	(segment
		(start 38.23081 -13.1572)
		(end 38.23081 -13.7668)
		(width 0.1397)
		(layer "B.Cu")
		(net "P2E_CPU_SAS_C_TX_DP6")
	)
	(segment
		(start 38.23081 -13.7668)
		(end 38.28161 -13.8176)
		(width 0.1397)
		(layer "B.Cu")
		(net "P2E_CPU_SAS_C_TX_DP6")
	)
	(segment
		(start 47.500286 -19.30273)
		(end 47.500286 -19.000978)
		(width 0.1143)
		(layer "In2.Cu")
		(net "P2E_CPU_SAS_C_TX_DP6")
	)
	(segment
		(start 82.637884 -56.8198)
		(end 79.6798 -56.8198)
		(width 0.1143)
		(layer "In2.Cu")
		(net "P2E_CPU_SAS_C_TX_DP6")
	)
	(segment
		(start 52.2351 -25.156668)
		(end 52.2351 -21.270976)
		(width 0.1143)
		(layer "In2.Cu")
		(net "P2E_CPU_SAS_C_TX_DP6")
	)
	(segment
		(start 74.798174 -55.54345)
		(end 72.72274 -55.54345)
		(width 0.1143)
		(layer "In2.Cu")
		(net "P2E_CPU_SAS_C_TX_DP6")
	)
	(segment
		(start 68.85559 -51.6763)
		(end 67.434968 -51.6763)
		(width 0.1143)
		(layer "In2.Cu")
		(net "P2E_CPU_SAS_C_TX_DP6")
	)
	(segment
		(start 47.500286 -19.000978)
		(end 47.25797 -18.758662)
		(width 0.1143)
		(layer "In2.Cu")
		(net "P2E_CPU_SAS_C_TX_DP6")
	)
	(segment
		(start 46.536356 -18.3388)
		(end 41.7322 -18.3388)
		(width 0.1143)
		(layer "In2.Cu")
		(net "P2E_CPU_SAS_C_TX_DP6")
	)
	(segment
		(start 46.956218 -18.758662)
		(end 46.536356 -18.3388)
		(width 0.1143)
		(layer "In2.Cu")
		(net "P2E_CPU_SAS_C_TX_DP6")
	)
	(segment
		(start 52.2351 -21.270976)
		(end 50.509424 -19.5453)
		(width 0.1143)
		(layer "In2.Cu")
		(net "P2E_CPU_SAS_C_TX_DP6")
	)
	(segment
		(start 78.9686 -56.1086)
		(end 75.363324 -56.1086)
		(width 0.1143)
		(layer "In2.Cu")
		(net "P2E_CPU_SAS_C_TX_DP6")
	)
	(segment
		(start 58.69305 -46.236128)
		(end 58.69305 -45.0469)
		(width 0.1143)
		(layer "In2.Cu")
		(net "P2E_CPU_SAS_C_TX_DP6")
	)
	(segment
		(start 41.7322 -18.3388)
		(end 38.0111 -14.6177)
		(width 0.1143)
		(layer "In2.Cu")
		(net "P2E_CPU_SAS_C_TX_DP6")
	)
	(segment
		(start 72.72274 -55.54345)
		(end 68.85559 -51.6763)
		(width 0.1143)
		(layer "In2.Cu")
		(net "P2E_CPU_SAS_C_TX_DP6")
	)
	(segment
		(start 84.7598 -54.7878)
		(end 82.861658 -56.685942)
		(width 0.1016)
		(layer "In2.Cu")
		(net "P2E_CPU_SAS_C_TX_DP6")
	)
	(segment
		(start 38.0111 -14.08811)
		(end 38.28161 -13.8176)
		(width 0.1143)
		(layer "In2.Cu")
		(net "P2E_CPU_SAS_C_TX_DP6")
	)
	(segment
		(start 57.201308 -38.471602)
		(end 54.40172 -35.672014)
		(width 0.1143)
		(layer "In2.Cu")
		(net "P2E_CPU_SAS_C_TX_DP6")
	)
	(segment
		(start 50.509424 -19.5453)
		(end 47.742856 -19.5453)
		(width 0.1143)
		(layer "In2.Cu")
		(net "P2E_CPU_SAS_C_TX_DP6")
	)
	(segment
		(start 58.69305 -45.0469)
		(end 58.378344 -44.732194)
		(width 0.1143)
		(layer "In2.Cu")
		(net "P2E_CPU_SAS_C_TX_DP6")
	)
	(segment
		(start 47.742856 -19.5453)
		(end 47.500286 -19.30273)
		(width 0.1143)
		(layer "In2.Cu")
		(net "P2E_CPU_SAS_C_TX_DP6")
	)
	(segment
		(start 58.378344 -44.732194)
		(end 58.378344 -44.47159)
		(width 0.1143)
		(layer "In2.Cu")
		(net "P2E_CPU_SAS_C_TX_DP6")
	)
	(segment
		(start 60.158122 -47.7012)
		(end 58.69305 -46.236128)
		(width 0.1143)
		(layer "In2.Cu")
		(net "P2E_CPU_SAS_C_TX_DP6")
	)
	(segment
		(start 86.097618 -53.20157)
		(end 85.933788 -53.3654)
		(width 0.1016)
		(layer "In2.Cu")
		(net "P2E_CPU_SAS_C_TX_DP6")
	)
	(segment
		(start 67.117468 -51.3588)
		(end 65.327784 -51.3588)
		(width 0.1143)
		(layer "In2.Cu")
		(net "P2E_CPU_SAS_C_TX_DP6")
	)
	(segment
		(start 57.201308 -43.294554)
		(end 57.201308 -38.471602)
		(width 0.1143)
		(layer "In2.Cu")
		(net "P2E_CPU_SAS_C_TX_DP6")
	)
	(segment
		(start 75.363324 -56.1086)
		(end 74.798174 -55.54345)
		(width 0.1143)
		(layer "In2.Cu")
		(net "P2E_CPU_SAS_C_TX_DP6")
	)
	(segment
		(start 84.7598 -53.8988)
		(end 84.7598 -54.7878)
		(width 0.1016)
		(layer "In2.Cu")
		(net "P2E_CPU_SAS_C_TX_DP6")
	)
	(segment
		(start 79.6798 -56.8198)
		(end 78.9686 -56.1086)
		(width 0.1143)
		(layer "In2.Cu")
		(net "P2E_CPU_SAS_C_TX_DP6")
	)
	(segment
		(start 54.40172 -27.323288)
		(end 52.2351 -25.156668)
		(width 0.1143)
		(layer "In2.Cu")
		(net "P2E_CPU_SAS_C_TX_DP6")
	)
	(segment
		(start 67.434968 -51.6763)
		(end 67.117468 -51.3588)
		(width 0.1143)
		(layer "In2.Cu")
		(net "P2E_CPU_SAS_C_TX_DP6")
	)
	(segment
		(start 85.2932 -53.3654)
		(end 84.7598 -53.8988)
		(width 0.1016)
		(layer "In2.Cu")
		(net "P2E_CPU_SAS_C_TX_DP6")
	)
	(segment
		(start 58.378344 -44.47159)
		(end 57.201308 -43.294554)
		(width 0.1143)
		(layer "In2.Cu")
		(net "P2E_CPU_SAS_C_TX_DP6")
	)
	(segment
		(start 61.670184 -47.7012)
		(end 60.158122 -47.7012)
		(width 0.1143)
		(layer "In2.Cu")
		(net "P2E_CPU_SAS_C_TX_DP6")
	)
	(segment
		(start 54.40172 -35.672014)
		(end 54.40172 -27.323288)
		(width 0.1143)
		(layer "In2.Cu")
		(net "P2E_CPU_SAS_C_TX_DP6")
	)
	(segment
		(start 47.25797 -18.758662)
		(end 46.956218 -18.758662)
		(width 0.1143)
		(layer "In2.Cu")
		(net "P2E_CPU_SAS_C_TX_DP6")
	)
	(segment
		(start 65.327784 -51.3588)
		(end 61.670184 -47.7012)
		(width 0.1143)
		(layer "In2.Cu")
		(net "P2E_CPU_SAS_C_TX_DP6")
	)
	(segment
		(start 38.0111 -14.6177)
		(end 38.0111 -14.08811)
		(width 0.1143)
		(layer "In2.Cu")
		(net "P2E_CPU_SAS_C_TX_DP6")
	)
	(segment
		(start 82.771742 -56.685942)
		(end 82.637884 -56.8198)
		(width 0.1143)
		(layer "In2.Cu")
		(net "P2E_CPU_SAS_C_TX_DP6")
	)
	(segment
		(start 82.861658 -56.685942)
		(end 82.771742 -56.685942)
		(width 0.1016)
		(layer "In2.Cu")
		(net "P2E_CPU_SAS_C_TX_DP6")
	)
	(segment
		(start 85.933788 -53.3654)
		(end 85.2932 -53.3654)
		(width 0.1016)
		(layer "In2.Cu")
		(net "P2E_CPU_SAS_C_TX_DP6")
	)
	(segment
		(start 87.767668 -52.465732)
		(end 87.767668 -51.826922)
		(width 0.1016)
		(layer "F.Cu")
		(net "P2E_CPU_SAS_C_TX_DN7")
	)
	(segment
		(start 85.675978 -55.362094)
		(end 85.874352 -55.16372)
		(width 0.1016)
		(layer "F.Cu")
		(net "P2E_CPU_SAS_C_TX_DN7")
	)
	(segment
		(start 87.630508 -52.602892)
		(end 87.767668 -52.465732)
		(width 0.1016)
		(layer "F.Cu")
		(net "P2E_CPU_SAS_C_TX_DN7")
	)
	(segment
		(start 86.4362 -54.89194)
		(end 86.4362 -54.347872)
		(width 0.1016)
		(layer "F.Cu")
		(net "P2E_CPU_SAS_C_TX_DN7")
	)
	(segment
		(start 87.630508 -53.153564)
		(end 87.630508 -52.602892)
		(width 0.1016)
		(layer "F.Cu")
		(net "P2E_CPU_SAS_C_TX_DN7")
	)
	(segment
		(start 85.874352 -55.16372)
		(end 86.16442 -55.16372)
		(width 0.1016)
		(layer "F.Cu")
		(net "P2E_CPU_SAS_C_TX_DN7")
	)
	(segment
		(start 86.4362 -54.347872)
		(end 87.630508 -53.153564)
		(width 0.1016)
		(layer "F.Cu")
		(net "P2E_CPU_SAS_C_TX_DN7")
	)
	(segment
		(start 87.767668 -51.826922)
		(end 87.409528 -50.995834)
		(width 0.1016)
		(layer "F.Cu")
		(net "P2E_CPU_SAS_C_TX_DN7")
	)
	(segment
		(start 86.16442 -55.16372)
		(end 86.4362 -54.89194)
		(width 0.1016)
		(layer "F.Cu")
		(net "P2E_CPU_SAS_C_TX_DN7")
	)
	(via
		(at 85.675978 -55.362094)
		(size 0.4318)
		(drill 0.2032)
		(layers "F.Cu" "B.Cu")
		(net "P2E_CPU_SAS_C_TX_DN7")
	)
	(via
		(at 33.4264 -14.5796)
		(size 0.508)
		(drill 0.254)
		(layers "F.Cu" "B.Cu")
		(net "P2E_CPU_SAS_C_TX_DN7")
	)
	(segment
		(start 33.4772 -13.1572)
		(end 33.68675 -13.36675)
		(width 0.1397)
		(layer "B.Cu")
		(net "P2E_CPU_SAS_C_TX_DN7")
	)
	(segment
		(start 33.68675 -13.36675)
		(end 33.68675 -14.31925)
		(width 0.1397)
		(layer "B.Cu")
		(net "P2E_CPU_SAS_C_TX_DN7")
	)
	(segment
		(start 33.68675 -14.31925)
		(end 33.4264 -14.5796)
		(width 0.1397)
		(layer "B.Cu")
		(net "P2E_CPU_SAS_C_TX_DN7")
	)
	(segment
		(start 49.149 -34.789364)
		(end 42.926 -28.566364)
		(width 0.1143)
		(layer "In2.Cu")
		(net "P2E_CPU_SAS_C_TX_DN7")
	)
	(segment
		(start 63.782194 -52.6415)
		(end 61.7601 -50.619406)
		(width 0.1143)
		(layer "In2.Cu")
		(net "P2E_CPU_SAS_C_TX_DN7")
	)
	(segment
		(start 66.585846 -52.6415)
		(end 63.782194 -52.6415)
		(width 0.1143)
		(layer "In2.Cu")
		(net "P2E_CPU_SAS_C_TX_DN7")
	)
	(segment
		(start 69.890894 -55.8038)
		(end 69.194426 -55.8038)
		(width 0.1143)
		(layer "In2.Cu")
		(net "P2E_CPU_SAS_C_TX_DN7")
	)
	(segment
		(start 85.675978 -55.362094)
		(end 85.469984 -55.1561)
		(width 0.1016)
		(layer "In2.Cu")
		(net "P2E_CPU_SAS_C_TX_DN7")
	)
	(segment
		(start 54.129686 -37.214302)
		(end 50.640996 -37.214302)
		(width 0.1143)
		(layer "In2.Cu")
		(net "P2E_CPU_SAS_C_TX_DN7")
	)
	(segment
		(start 40.2209 -24.1173)
		(end 33.655 -17.5514)
		(width 0.1143)
		(layer "In2.Cu")
		(net "P2E_CPU_SAS_C_TX_DN7")
	)
	(segment
		(start 72.126094 -58.039)
		(end 69.890894 -55.8038)
		(width 0.1143)
		(layer "In2.Cu")
		(net "P2E_CPU_SAS_C_TX_DN7")
	)
	(segment
		(start 85.469984 -55.1561)
		(end 85.263228 -55.1561)
		(width 0.1016)
		(layer "In2.Cu")
		(net "P2E_CPU_SAS_C_TX_DN7")
	)
	(segment
		(start 55.918608 -39.003224)
		(end 54.129686 -37.214302)
		(width 0.1143)
		(layer "In2.Cu")
		(net "P2E_CPU_SAS_C_TX_DN7")
	)
	(segment
		(start 61.7601 -50.619406)
		(end 61.7601 -49.788572)
		(width 0.1143)
		(layer "In2.Cu")
		(net "P2E_CPU_SAS_C_TX_DN7")
	)
	(segment
		(start 33.655 -17.5514)
		(end 33.655 -14.8082)
		(width 0.1143)
		(layer "In2.Cu")
		(net "P2E_CPU_SAS_C_TX_DN7")
	)
	(segment
		(start 60.0964 -49.4538)
		(end 57.41035 -46.76775)
		(width 0.1143)
		(layer "In2.Cu")
		(net "P2E_CPU_SAS_C_TX_DN7")
	)
	(segment
		(start 50.640996 -37.214302)
		(end 49.149 -35.722306)
		(width 0.1143)
		(layer "In2.Cu")
		(net "P2E_CPU_SAS_C_TX_DN7")
	)
	(segment
		(start 33.655 -14.8082)
		(end 33.4264 -14.5796)
		(width 0.1143)
		(layer "In2.Cu")
		(net "P2E_CPU_SAS_C_TX_DN7")
	)
	(segment
		(start 40.350694 -24.1173)
		(end 40.2209 -24.1173)
		(width 0.1143)
		(layer "In2.Cu")
		(net "P2E_CPU_SAS_C_TX_DN7")
	)
	(segment
		(start 49.149 -35.722306)
		(end 49.149 -34.789364)
		(width 0.1143)
		(layer "In2.Cu")
		(net "P2E_CPU_SAS_C_TX_DN7")
	)
	(segment
		(start 85.263228 -55.1561)
		(end 85.098636 -55.320692)
		(width 0.1016)
		(layer "In2.Cu")
		(net "P2E_CPU_SAS_C_TX_DN7")
	)
	(segment
		(start 85.098636 -55.320692)
		(end 85.098636 -55.490364)
		(width 0.1016)
		(layer "In2.Cu")
		(net "P2E_CPU_SAS_C_TX_DN7")
	)
	(segment
		(start 61.425328 -49.4538)
		(end 60.0964 -49.4538)
		(width 0.1143)
		(layer "In2.Cu")
		(net "P2E_CPU_SAS_C_TX_DN7")
	)
	(segment
		(start 55.918608 -43.826176)
		(end 55.918608 -39.003224)
		(width 0.1143)
		(layer "In2.Cu")
		(net "P2E_CPU_SAS_C_TX_DN7")
	)
	(segment
		(start 82.89036 -57.788556)
		(end 82.639916 -58.039)
		(width 0.1143)
		(layer "In2.Cu")
		(net "P2E_CPU_SAS_C_TX_DN7")
	)
	(segment
		(start 82.639916 -58.039)
		(end 72.126094 -58.039)
		(width 0.1143)
		(layer "In2.Cu")
		(net "P2E_CPU_SAS_C_TX_DN7")
	)
	(segment
		(start 67.1322 -53.187854)
		(end 66.585846 -52.6415)
		(width 0.1143)
		(layer "In2.Cu")
		(net "P2E_CPU_SAS_C_TX_DN7")
	)
	(segment
		(start 82.908394 -57.770522)
		(end 82.89036 -57.788556)
		(width 0.1016)
		(layer "In2.Cu")
		(net "P2E_CPU_SAS_C_TX_DN7")
	)
	(segment
		(start 85.098636 -55.490364)
		(end 82.908394 -57.680606)
		(width 0.1016)
		(layer "In2.Cu")
		(net "P2E_CPU_SAS_C_TX_DN7")
	)
	(segment
		(start 42.926 -26.692606)
		(end 40.350694 -24.1173)
		(width 0.1143)
		(layer "In2.Cu")
		(net "P2E_CPU_SAS_C_TX_DN7")
	)
	(segment
		(start 69.194426 -55.8038)
		(end 67.1322 -53.741574)
		(width 0.1143)
		(layer "In2.Cu")
		(net "P2E_CPU_SAS_C_TX_DN7")
	)
	(segment
		(start 82.908394 -57.680606)
		(end 82.908394 -57.770522)
		(width 0.1016)
		(layer "In2.Cu")
		(net "P2E_CPU_SAS_C_TX_DN7")
	)
	(segment
		(start 57.095644 -45.263816)
		(end 57.095644 -45.003212)
		(width 0.1143)
		(layer "In2.Cu")
		(net "P2E_CPU_SAS_C_TX_DN7")
	)
	(segment
		(start 57.41035 -46.76775)
		(end 57.41035 -45.578522)
		(width 0.1143)
		(layer "In2.Cu")
		(net "P2E_CPU_SAS_C_TX_DN7")
	)
	(segment
		(start 57.41035 -45.578522)
		(end 57.095644 -45.263816)
		(width 0.1143)
		(layer "In2.Cu")
		(net "P2E_CPU_SAS_C_TX_DN7")
	)
	(segment
		(start 42.926 -28.566364)
		(end 42.926 -26.692606)
		(width 0.1143)
		(layer "In2.Cu")
		(net "P2E_CPU_SAS_C_TX_DN7")
	)
	(segment
		(start 61.7601 -49.788572)
		(end 61.425328 -49.4538)
		(width 0.1143)
		(layer "In2.Cu")
		(net "P2E_CPU_SAS_C_TX_DN7")
	)
	(segment
		(start 67.1322 -53.741574)
		(end 67.1322 -53.187854)
		(width 0.1143)
		(layer "In2.Cu")
		(net "P2E_CPU_SAS_C_TX_DN7")
	)
	(segment
		(start 57.095644 -45.003212)
		(end 55.918608 -43.826176)
		(width 0.1143)
		(layer "In2.Cu")
		(net "P2E_CPU_SAS_C_TX_DN7")
	)
	(segment
		(start 87.564468 -52.381404)
		(end 87.427308 -52.518564)
		(width 0.1016)
		(layer "F.Cu")
		(net "P2E_CPU_SAS_C_TX_DP7")
	)
	(segment
		(start 87.564468 -52.055014)
		(end 87.564468 -52.381404)
		(width 0.1016)
		(layer "F.Cu")
		(net "P2E_CPU_SAS_C_TX_DP7")
	)
	(segment
		(start 87.427308 -53.069236)
		(end 86.233 -54.263544)
		(width 0.1016)
		(layer "F.Cu")
		(net "P2E_CPU_SAS_C_TX_DP7")
	)
	(segment
		(start 85.84946 -54.96052)
		(end 85.684614 -54.795674)
		(width 0.1016)
		(layer "F.Cu")
		(net "P2E_CPU_SAS_C_TX_DP7")
	)
	(segment
		(start 86.080092 -54.96052)
		(end 85.84946 -54.96052)
		(width 0.1016)
		(layer "F.Cu")
		(net "P2E_CPU_SAS_C_TX_DP7")
	)
	(segment
		(start 86.233 -54.263544)
		(end 86.233 -54.807612)
		(width 0.1016)
		(layer "F.Cu")
		(net "P2E_CPU_SAS_C_TX_DP7")
	)
	(segment
		(start 87.427308 -52.518564)
		(end 87.427308 -53.069236)
		(width 0.1016)
		(layer "F.Cu")
		(net "P2E_CPU_SAS_C_TX_DP7")
	)
	(segment
		(start 86.233 -54.807612)
		(end 86.080092 -54.96052)
		(width 0.1016)
		(layer "F.Cu")
		(net "P2E_CPU_SAS_C_TX_DP7")
	)
	(segment
		(start 87.462868 -51.953414)
		(end 87.564468 -52.055014)
		(width 0.1016)
		(layer "F.Cu")
		(net "P2E_CPU_SAS_C_TX_DP7")
	)
	(via
		(at 34.29 -14.5796)
		(size 0.508)
		(drill 0.254)
		(layers "F.Cu" "B.Cu")
		(net "P2E_CPU_SAS_C_TX_DP7")
	)
	(via
		(at 85.684614 -54.795674)
		(size 0.4318)
		(drill 0.2032)
		(layers "F.Cu" "B.Cu")
		(net "P2E_CPU_SAS_C_TX_DP7")
	)
	(segment
		(start 34.02965 -13.36675)
		(end 34.02965 -14.31925)
		(width 0.1397)
		(layer "B.Cu")
		(net "P2E_CPU_SAS_C_TX_DP7")
	)
	(segment
		(start 34.2392 -13.1572)
		(end 34.02965 -13.36675)
		(width 0.1397)
		(layer "B.Cu")
		(net "P2E_CPU_SAS_C_TX_DP7")
	)
	(segment
		(start 34.02965 -14.31925)
		(end 34.29 -14.5796)
		(width 0.1397)
		(layer "B.Cu")
		(net "P2E_CPU_SAS_C_TX_DP7")
	)
	(segment
		(start 34.529522 -17.657064)
		(end 34.22777 -17.657064)
		(width 0.1143)
		(layer "In2.Cu")
		(net "P2E_CPU_SAS_C_TX_DP7")
	)
	(segment
		(start 82.50301 -57.7088)
		(end 72.263 -57.7088)
		(width 0.1143)
		(layer "In2.Cu")
		(net "P2E_CPU_SAS_C_TX_DP7")
	)
	(segment
		(start 69.331332 -55.4736)
		(end 67.4624 -53.604668)
		(width 0.1143)
		(layer "In2.Cu")
		(net "P2E_CPU_SAS_C_TX_DP7")
	)
	(segment
		(start 42.771314 -25.769062)
		(end 42.469562 -25.769062)
		(width 0.1143)
		(layer "In2.Cu")
		(net "P2E_CPU_SAS_C_TX_DP7")
	)
	(segment
		(start 85.684614 -54.795674)
		(end 85.527388 -54.9529)
		(width 0.1016)
		(layer "In2.Cu")
		(net "P2E_CPU_SAS_C_TX_DP7")
	)
	(segment
		(start 34.771838 -17.89938)
		(end 34.529522 -17.657064)
		(width 0.1143)
		(layer "In2.Cu")
		(net "P2E_CPU_SAS_C_TX_DP7")
	)
	(segment
		(start 61.562234 -49.1236)
		(end 60.233306 -49.1236)
		(width 0.1143)
		(layer "In2.Cu")
		(net "P2E_CPU_SAS_C_TX_DP7")
	)
	(segment
		(start 49.4792 -34.652458)
		(end 49.160684 -34.333942)
		(width 0.1143)
		(layer "In2.Cu")
		(net "P2E_CPU_SAS_C_TX_DP7")
	)
	(segment
		(start 43.2562 -28.429458)
		(end 43.2562 -26.5557)
		(width 0.1143)
		(layer "In2.Cu")
		(net "P2E_CPU_SAS_C_TX_DP7")
	)
	(segment
		(start 46.035468 -30.906974)
		(end 45.733716 -30.906974)
		(width 0.1143)
		(layer "In2.Cu")
		(net "P2E_CPU_SAS_C_TX_DP7")
	)
	(segment
		(start 44.160186 -29.333444)
		(end 43.2562 -28.429458)
		(width 0.1143)
		(layer "In2.Cu")
		(net "P2E_CPU_SAS_C_TX_DP7")
	)
	(segment
		(start 39.571168 -23.000462)
		(end 39.328598 -22.757892)
		(width 0.1143)
		(layer "In2.Cu")
		(net "P2E_CPU_SAS_C_TX_DP7")
	)
	(segment
		(start 39.87292 -23.000462)
		(end 39.571168 -23.000462)
		(width 0.1143)
		(layer "In2.Cu")
		(net "P2E_CPU_SAS_C_TX_DP7")
	)
	(segment
		(start 33.9852 -14.8844)
		(end 34.29 -14.5796)
		(width 0.1143)
		(layer "In2.Cu")
		(net "P2E_CPU_SAS_C_TX_DP7")
	)
	(segment
		(start 45.733716 -30.906974)
		(end 45.491146 -30.664404)
		(width 0.1143)
		(layer "In2.Cu")
		(net "P2E_CPU_SAS_C_TX_DP7")
	)
	(segment
		(start 44.461938 -29.333444)
		(end 44.160186 -29.333444)
		(width 0.1143)
		(layer "In2.Cu")
		(net "P2E_CPU_SAS_C_TX_DP7")
	)
	(segment
		(start 57.74055 -46.630844)
		(end 57.74055 -45.441616)
		(width 0.1143)
		(layer "In2.Cu")
		(net "P2E_CPU_SAS_C_TX_DP7")
	)
	(segment
		(start 82.656934 -57.554876)
		(end 82.50301 -57.7088)
		(width 0.1143)
		(layer "In2.Cu")
		(net "P2E_CPU_SAS_C_TX_DP7")
	)
	(segment
		(start 41.682924 -24.982424)
		(end 40.4876 -23.7871)
		(width 0.1143)
		(layer "In2.Cu")
		(net "P2E_CPU_SAS_C_TX_DP7")
	)
	(segment
		(start 45.491146 -30.362652)
		(end 45.248576 -30.120082)
		(width 0.1143)
		(layer "In2.Cu")
		(net "P2E_CPU_SAS_C_TX_DP7")
	)
	(segment
		(start 43.01363 -26.31313)
		(end 43.01363 -26.011378)
		(width 0.1143)
		(layer "In2.Cu")
		(net "P2E_CPU_SAS_C_TX_DP7")
	)
	(segment
		(start 57.425844 -44.866306)
		(end 56.248808 -43.68927)
		(width 0.1143)
		(layer "In2.Cu")
		(net "P2E_CPU_SAS_C_TX_DP7")
	)
	(segment
		(start 42.469562 -25.769062)
		(end 42.226992 -25.526492)
		(width 0.1143)
		(layer "In2.Cu")
		(net "P2E_CPU_SAS_C_TX_DP7")
	)
	(segment
		(start 40.115236 -23.242778)
		(end 39.87292 -23.000462)
		(width 0.1143)
		(layer "In2.Cu")
		(net "P2E_CPU_SAS_C_TX_DP7")
	)
	(segment
		(start 46.277784 -31.451042)
		(end 46.277784 -31.14929)
		(width 0.1143)
		(layer "In2.Cu")
		(net "P2E_CPU_SAS_C_TX_DP7")
	)
	(segment
		(start 44.704508 -29.877766)
		(end 44.704508 -29.576014)
		(width 0.1143)
		(layer "In2.Cu")
		(net "P2E_CPU_SAS_C_TX_DP7")
	)
	(segment
		(start 84.895436 -55.236364)
		(end 84.895436 -55.406036)
		(width 0.1016)
		(layer "In2.Cu")
		(net "P2E_CPU_SAS_C_TX_DP7")
	)
	(segment
		(start 41.984676 -24.982424)
		(end 41.682924 -24.982424)
		(width 0.1143)
		(layer "In2.Cu")
		(net "P2E_CPU_SAS_C_TX_DP7")
	)
	(segment
		(start 60.233306 -49.1236)
		(end 57.74055 -46.630844)
		(width 0.1143)
		(layer "In2.Cu")
		(net "P2E_CPU_SAS_C_TX_DP7")
	)
	(segment
		(start 35.801046 -19.23034)
		(end 35.558476 -18.98777)
		(width 0.1143)
		(layer "In2.Cu")
		(net "P2E_CPU_SAS_C_TX_DP7")
	)
	(segment
		(start 49.160684 -34.03219)
		(end 48.918368 -33.789874)
		(width 0.1143)
		(layer "In2.Cu")
		(net "P2E_CPU_SAS_C_TX_DP7")
	)
	(segment
		(start 85.1789 -54.9529)
		(end 84.895436 -55.236364)
		(width 0.1016)
		(layer "In2.Cu")
		(net "P2E_CPU_SAS_C_TX_DP7")
	)
	(segment
		(start 43.2562 -26.5557)
		(end 43.01363 -26.31313)
		(width 0.1143)
		(layer "In2.Cu")
		(net "P2E_CPU_SAS_C_TX_DP7")
	)
	(segment
		(start 39.086282 -22.213824)
		(end 38.78453 -22.213824)
		(width 0.1143)
		(layer "In2.Cu")
		(net "P2E_CPU_SAS_C_TX_DP7")
	)
	(segment
		(start 48.616616 -33.789874)
		(end 46.277784 -31.451042)
		(width 0.1143)
		(layer "In2.Cu")
		(net "P2E_CPU_SAS_C_TX_DP7")
	)
	(segment
		(start 45.248576 -30.120082)
		(end 44.946824 -30.120082)
		(width 0.1143)
		(layer "In2.Cu")
		(net "P2E_CPU_SAS_C_TX_DP7")
	)
	(segment
		(start 34.771838 -18.201132)
		(end 34.771838 -17.89938)
		(width 0.1143)
		(layer "In2.Cu")
		(net "P2E_CPU_SAS_C_TX_DP7")
	)
	(segment
		(start 85.527388 -54.9529)
		(end 85.1789 -54.9529)
		(width 0.1016)
		(layer "In2.Cu")
		(net "P2E_CPU_SAS_C_TX_DP7")
	)
	(segment
		(start 67.4624 -53.050948)
		(end 66.722752 -52.3113)
		(width 0.1143)
		(layer "In2.Cu")
		(net "P2E_CPU_SAS_C_TX_DP7")
	)
	(segment
		(start 33.9852 -17.414494)
		(end 33.9852 -14.8844)
		(width 0.1143)
		(layer "In2.Cu")
		(net "P2E_CPU_SAS_C_TX_DP7")
	)
	(segment
		(start 82.674714 -57.537096)
		(end 82.656934 -57.554876)
		(width 0.1016)
		(layer "In2.Cu")
		(net "P2E_CPU_SAS_C_TX_DP7")
	)
	(segment
		(start 82.764376 -57.537096)
		(end 82.674714 -57.537096)
		(width 0.1016)
		(layer "In2.Cu")
		(net "P2E_CPU_SAS_C_TX_DP7")
	)
	(segment
		(start 36.345114 -19.774408)
		(end 36.345114 -19.472656)
		(width 0.1143)
		(layer "In2.Cu")
		(net "P2E_CPU_SAS_C_TX_DP7")
	)
	(segment
		(start 54.266592 -36.884102)
		(end 50.777902 -36.884102)
		(width 0.1143)
		(layer "In2.Cu")
		(net "P2E_CPU_SAS_C_TX_DP7")
	)
	(segment
		(start 40.357806 -23.7871)
		(end 40.115236 -23.54453)
		(width 0.1143)
		(layer "In2.Cu")
		(net "P2E_CPU_SAS_C_TX_DP7")
	)
	(segment
		(start 36.102798 -19.23034)
		(end 35.801046 -19.23034)
		(width 0.1143)
		(layer "In2.Cu")
		(net "P2E_CPU_SAS_C_TX_DP7")
	)
	(segment
		(start 40.115236 -23.54453)
		(end 40.115236 -23.242778)
		(width 0.1143)
		(layer "In2.Cu")
		(net "P2E_CPU_SAS_C_TX_DP7")
	)
	(segment
		(start 84.895436 -55.406036)
		(end 82.764376 -57.537096)
		(width 0.1016)
		(layer "In2.Cu")
		(net "P2E_CPU_SAS_C_TX_DP7")
	)
	(segment
		(start 38.78453 -22.213824)
		(end 36.345114 -19.774408)
		(width 0.1143)
		(layer "In2.Cu")
		(net "P2E_CPU_SAS_C_TX_DP7")
	)
	(segment
		(start 56.248808 -38.866318)
		(end 54.266592 -36.884102)
		(width 0.1143)
		(layer "In2.Cu")
		(net "P2E_CPU_SAS_C_TX_DP7")
	)
	(segment
		(start 70.0278 -55.4736)
		(end 69.331332 -55.4736)
		(width 0.1143)
		(layer "In2.Cu")
		(net "P2E_CPU_SAS_C_TX_DP7")
	)
	(segment
		(start 62.0903 -50.4825)
		(end 62.0903 -49.651666)
		(width 0.1143)
		(layer "In2.Cu")
		(net "P2E_CPU_SAS_C_TX_DP7")
	)
	(segment
		(start 57.425844 -45.12691)
		(end 57.425844 -44.866306)
		(width 0.1143)
		(layer "In2.Cu")
		(net "P2E_CPU_SAS_C_TX_DP7")
	)
	(segment
		(start 44.946824 -30.120082)
		(end 44.704508 -29.877766)
		(width 0.1143)
		(layer "In2.Cu")
		(net "P2E_CPU_SAS_C_TX_DP7")
	)
	(segment
		(start 48.918368 -33.789874)
		(end 48.616616 -33.789874)
		(width 0.1143)
		(layer "In2.Cu")
		(net "P2E_CPU_SAS_C_TX_DP7")
	)
	(segment
		(start 40.4876 -23.7871)
		(end 40.357806 -23.7871)
		(width 0.1143)
		(layer "In2.Cu")
		(net "P2E_CPU_SAS_C_TX_DP7")
	)
	(segment
		(start 72.263 -57.7088)
		(end 70.0278 -55.4736)
		(width 0.1143)
		(layer "In2.Cu")
		(net "P2E_CPU_SAS_C_TX_DP7")
	)
	(segment
		(start 35.31616 -18.443702)
		(end 35.014408 -18.443702)
		(width 0.1143)
		(layer "In2.Cu")
		(net "P2E_CPU_SAS_C_TX_DP7")
	)
	(segment
		(start 57.74055 -45.441616)
		(end 57.425844 -45.12691)
		(width 0.1143)
		(layer "In2.Cu")
		(net "P2E_CPU_SAS_C_TX_DP7")
	)
	(segment
		(start 35.558476 -18.98777)
		(end 35.558476 -18.686018)
		(width 0.1143)
		(layer "In2.Cu")
		(net "P2E_CPU_SAS_C_TX_DP7")
	)
	(segment
		(start 44.704508 -29.576014)
		(end 44.461938 -29.333444)
		(width 0.1143)
		(layer "In2.Cu")
		(net "P2E_CPU_SAS_C_TX_DP7")
	)
	(segment
		(start 42.226992 -25.22474)
		(end 41.984676 -24.982424)
		(width 0.1143)
		(layer "In2.Cu")
		(net "P2E_CPU_SAS_C_TX_DP7")
	)
	(segment
		(start 39.328598 -22.757892)
		(end 39.328598 -22.45614)
		(width 0.1143)
		(layer "In2.Cu")
		(net "P2E_CPU_SAS_C_TX_DP7")
	)
	(segment
		(start 45.491146 -30.664404)
		(end 45.491146 -30.362652)
		(width 0.1143)
		(layer "In2.Cu")
		(net "P2E_CPU_SAS_C_TX_DP7")
	)
	(segment
		(start 39.328598 -22.45614)
		(end 39.086282 -22.213824)
		(width 0.1143)
		(layer "In2.Cu")
		(net "P2E_CPU_SAS_C_TX_DP7")
	)
	(segment
		(start 67.4624 -53.604668)
		(end 67.4624 -53.050948)
		(width 0.1143)
		(layer "In2.Cu")
		(net "P2E_CPU_SAS_C_TX_DP7")
	)
	(segment
		(start 35.558476 -18.686018)
		(end 35.31616 -18.443702)
		(width 0.1143)
		(layer "In2.Cu")
		(net "P2E_CPU_SAS_C_TX_DP7")
	)
	(segment
		(start 43.01363 -26.011378)
		(end 42.771314 -25.769062)
		(width 0.1143)
		(layer "In2.Cu")
		(net "P2E_CPU_SAS_C_TX_DP7")
	)
	(segment
		(start 56.248808 -43.68927)
		(end 56.248808 -38.866318)
		(width 0.1143)
		(layer "In2.Cu")
		(net "P2E_CPU_SAS_C_TX_DP7")
	)
	(segment
		(start 62.0903 -49.651666)
		(end 61.562234 -49.1236)
		(width 0.1143)
		(layer "In2.Cu")
		(net "P2E_CPU_SAS_C_TX_DP7")
	)
	(segment
		(start 35.014408 -18.443702)
		(end 34.771838 -18.201132)
		(width 0.1143)
		(layer "In2.Cu")
		(net "P2E_CPU_SAS_C_TX_DP7")
	)
	(segment
		(start 50.777902 -36.884102)
		(end 49.4792 -35.5854)
		(width 0.1143)
		(layer "In2.Cu")
		(net "P2E_CPU_SAS_C_TX_DP7")
	)
	(segment
		(start 36.345114 -19.472656)
		(end 36.102798 -19.23034)
		(width 0.1143)
		(layer "In2.Cu")
		(net "P2E_CPU_SAS_C_TX_DP7")
	)
	(segment
		(start 63.9191 -52.3113)
		(end 62.0903 -50.4825)
		(width 0.1143)
		(layer "In2.Cu")
		(net "P2E_CPU_SAS_C_TX_DP7")
	)
	(segment
		(start 34.22777 -17.657064)
		(end 33.9852 -17.414494)
		(width 0.1143)
		(layer "In2.Cu")
		(net "P2E_CPU_SAS_C_TX_DP7")
	)
	(segment
		(start 66.722752 -52.3113)
		(end 63.9191 -52.3113)
		(width 0.1143)
		(layer "In2.Cu")
		(net "P2E_CPU_SAS_C_TX_DP7")
	)
	(segment
		(start 46.277784 -31.14929)
		(end 46.035468 -30.906974)
		(width 0.1143)
		(layer "In2.Cu")
		(net "P2E_CPU_SAS_C_TX_DP7")
	)
	(segment
		(start 49.160684 -34.333942)
		(end 49.160684 -34.03219)
		(width 0.1143)
		(layer "In2.Cu")
		(net "P2E_CPU_SAS_C_TX_DP7")
	)
	(segment
		(start 49.4792 -35.5854)
		(end 49.4792 -34.652458)
		(width 0.1143)
		(layer "In2.Cu")
		(net "P2E_CPU_SAS_C_TX_DP7")
	)
	(segment
		(start 42.226992 -25.526492)
		(end 42.226992 -25.22474)
		(width 0.1143)
		(layer "In2.Cu")
		(net "P2E_CPU_SAS_C_TX_DP7")
	)
	(segment
		(start 86.286848 -52.1462)
		(end 85.783928 -52.64912)
		(width 0.1016)
		(layer "F.Cu")
		(net "P2E_CPU_SAS_C_TX_DN5")
	)
	(segment
		(start 84.768944 -54.4068)
		(end 84.398104 -54.4068)
		(width 0.1016)
		(layer "F.Cu")
		(net "P2E_CPU_SAS_C_TX_DN5")
	)
	(segment
		(start 85.5472 -53.000656)
		(end 85.5472 -53.627528)
		(width 0.1016)
		(layer "F.Cu")
		(net "P2E_CPU_SAS_C_TX_DN5")
	)
	(segment
		(start 85.783928 -52.64912)
		(end 85.783928 -52.763928)
		(width 0.1016)
		(layer "F.Cu")
		(net "P2E_CPU_SAS_C_TX_DN5")
	)
	(segment
		(start 86.060788 -50.952654)
		(end 86.286848 -51.880262)
		(width 0.1016)
		(layer "F.Cu")
		(net "P2E_CPU_SAS_C_TX_DN5")
	)
	(segment
		(start 86.286848 -51.880262)
		(end 86.286848 -52.1462)
		(width 0.1016)
		(layer "F.Cu")
		(net "P2E_CPU_SAS_C_TX_DN5")
	)
	(segment
		(start 84.398104 -54.4068)
		(end 84.230464 -54.57444)
		(width 0.1016)
		(layer "F.Cu")
		(net "P2E_CPU_SAS_C_TX_DN5")
	)
	(segment
		(start 85.5472 -53.627528)
		(end 84.768944 -54.4068)
		(width 0.1016)
		(layer "F.Cu")
		(net "P2E_CPU_SAS_C_TX_DN5")
	)
	(segment
		(start 85.783928 -52.763928)
		(end 85.5472 -53.000656)
		(width 0.1016)
		(layer "F.Cu")
		(net "P2E_CPU_SAS_C_TX_DN5")
	)
	(via
		(at 41.418002 -13.8176)
		(size 0.508)
		(drill 0.254)
		(layers "F.Cu" "B.Cu")
		(net "P2E_CPU_SAS_C_TX_DN5")
	)
	(via
		(at 84.230464 -54.57444)
		(size 0.4318)
		(drill 0.2032)
		(layers "F.Cu" "B.Cu")
		(net "P2E_CPU_SAS_C_TX_DN5")
	)
	(segment
		(start 41.468802 -13.7668)
		(end 41.418002 -13.8176)
		(width 0.1397)
		(layer "B.Cu")
		(net "P2E_CPU_SAS_C_TX_DN5")
	)
	(segment
		(start 41.468802 -13.1572)
		(end 41.468802 -13.7668)
		(width 0.1397)
		(layer "B.Cu")
		(net "P2E_CPU_SAS_C_TX_DN5")
	)
	(segment
		(start 80.3402 -56.261)
		(end 79.695294 -56.261)
		(width 0.1143)
		(layer "In2.Cu")
		(net "P2E_CPU_SAS_C_TX_DN5")
	)
	(segment
		(start 59.01055 -38.201092)
		(end 55.095902 -34.286444)
		(width 0.1143)
		(layer "In2.Cu")
		(net "P2E_CPU_SAS_C_TX_DN5")
	)
	(segment
		(start 73.03135 -54.92115)
		(end 69.1642 -51.054)
		(width 0.1143)
		(layer "In2.Cu")
		(net "P2E_CPU_SAS_C_TX_DN5")
	)
	(segment
		(start 43.434 -15.630906)
		(end 42.895266 -16.16964)
		(width 0.1143)
		(layer "In2.Cu")
		(net "P2E_CPU_SAS_C_TX_DN5")
	)
	(segment
		(start 67.692778 -51.054)
		(end 67.375278 -50.7365)
		(width 0.1143)
		(layer "In2.Cu")
		(net "P2E_CPU_SAS_C_TX_DN5")
	)
	(segment
		(start 79.695294 -56.261)
		(end 79.17942 -55.745126)
		(width 0.1143)
		(layer "In2.Cu")
		(net "P2E_CPU_SAS_C_TX_DN5")
	)
	(segment
		(start 48.20158 -18.488914)
		(end 47.284386 -17.57172)
		(width 0.1143)
		(layer "In2.Cu")
		(net "P2E_CPU_SAS_C_TX_DN5")
	)
	(segment
		(start 42.15384 -16.16964)
		(end 41.6814 -15.6972)
		(width 0.1143)
		(layer "In2.Cu")
		(net "P2E_CPU_SAS_C_TX_DN5")
	)
	(segment
		(start 47.284386 -17.57172)
		(end 47.284386 -16.270986)
		(width 0.1143)
		(layer "In2.Cu")
		(net "P2E_CPU_SAS_C_TX_DN5")
	)
	(segment
		(start 83.520788 -54.40934)
		(end 81.732628 -56.1975)
		(width 0.1016)
		(layer "In2.Cu")
		(net "P2E_CPU_SAS_C_TX_DN5")
	)
	(segment
		(start 55.095902 -27.13736)
		(end 52.8701 -24.911558)
		(width 0.1143)
		(layer "In2.Cu")
		(net "P2E_CPU_SAS_C_TX_DN5")
	)
	(segment
		(start 45.727366 -16.0147)
		(end 45.638466 -16.1036)
		(width 0.1143)
		(layer "In2.Cu")
		(net "P2E_CPU_SAS_C_TX_DN5")
	)
	(segment
		(start 43.434 -14.868906)
		(end 43.434 -15.630906)
		(width 0.1143)
		(layer "In2.Cu")
		(net "P2E_CPU_SAS_C_TX_DN5")
	)
	(segment
		(start 44.958 -16.1036)
		(end 44.459906 -15.605506)
		(width 0.1143)
		(layer "In2.Cu")
		(net "P2E_CPU_SAS_C_TX_DN5")
	)
	(segment
		(start 81.732628 -56.1975)
		(end 80.4291 -56.1975)
		(width 0.1016)
		(layer "In2.Cu")
		(net "P2E_CPU_SAS_C_TX_DN5")
	)
	(segment
		(start 47.284386 -16.270986)
		(end 47.0281 -16.0147)
		(width 0.1143)
		(layer "In2.Cu")
		(net "P2E_CPU_SAS_C_TX_DN5")
	)
	(segment
		(start 43.774106 -14.5288)
		(end 43.434 -14.868906)
		(width 0.1143)
		(layer "In2.Cu")
		(net "P2E_CPU_SAS_C_TX_DN5")
	)
	(segment
		(start 44.459906 -15.605506)
		(end 44.459906 -14.74724)
		(width 0.1143)
		(layer "In2.Cu")
		(net "P2E_CPU_SAS_C_TX_DN5")
	)
	(segment
		(start 52.8701 -21.025866)
		(end 50.333148 -18.488914)
		(width 0.1143)
		(layer "In2.Cu")
		(net "P2E_CPU_SAS_C_TX_DN5")
	)
	(segment
		(start 75.82408 -55.745126)
		(end 75.000104 -54.92115)
		(width 0.1143)
		(layer "In2.Cu")
		(net "P2E_CPU_SAS_C_TX_DN5")
	)
	(segment
		(start 42.895266 -16.16964)
		(end 42.15384 -16.16964)
		(width 0.1143)
		(layer "In2.Cu")
		(net "P2E_CPU_SAS_C_TX_DN5")
	)
	(segment
		(start 47.0281 -16.0147)
		(end 45.727366 -16.0147)
		(width 0.1143)
		(layer "In2.Cu")
		(net "P2E_CPU_SAS_C_TX_DN5")
	)
	(segment
		(start 44.241466 -14.5288)
		(end 43.774106 -14.5288)
		(width 0.1143)
		(layer "In2.Cu")
		(net "P2E_CPU_SAS_C_TX_DN5")
	)
	(segment
		(start 59.01055 -41.464738)
		(end 59.01055 -38.201092)
		(width 0.1143)
		(layer "In2.Cu")
		(net "P2E_CPU_SAS_C_TX_DN5")
	)
	(segment
		(start 79.17942 -55.745126)
		(end 75.82408 -55.745126)
		(width 0.1143)
		(layer "In2.Cu")
		(net "P2E_CPU_SAS_C_TX_DN5")
	)
	(segment
		(start 65.585594 -50.7365)
		(end 61.722 -46.872906)
		(width 0.1143)
		(layer "In2.Cu")
		(net "P2E_CPU_SAS_C_TX_DN5")
	)
	(segment
		(start 41.6814 -15.6972)
		(end 41.6814 -14.080998)
		(width 0.1143)
		(layer "In2.Cu")
		(net "P2E_CPU_SAS_C_TX_DN5")
	)
	(segment
		(start 84.230464 -54.57444)
		(end 84.065364 -54.40934)
		(width 0.1016)
		(layer "In2.Cu")
		(net "P2E_CPU_SAS_C_TX_DN5")
	)
	(segment
		(start 75.000104 -54.92115)
		(end 73.03135 -54.92115)
		(width 0.1143)
		(layer "In2.Cu")
		(net "P2E_CPU_SAS_C_TX_DN5")
	)
	(segment
		(start 61.722 -45.869606)
		(end 61.1378 -45.285406)
		(width 0.1143)
		(layer "In2.Cu")
		(net "P2E_CPU_SAS_C_TX_DN5")
	)
	(segment
		(start 52.8701 -24.911558)
		(end 52.8701 -21.025866)
		(width 0.1143)
		(layer "In2.Cu")
		(net "P2E_CPU_SAS_C_TX_DN5")
	)
	(segment
		(start 80.4291 -56.1975)
		(end 80.3656 -56.261)
		(width 0.1016)
		(layer "In2.Cu")
		(net "P2E_CPU_SAS_C_TX_DN5")
	)
	(segment
		(start 61.722 -46.872906)
		(end 61.722 -45.869606)
		(width 0.1143)
		(layer "In2.Cu")
		(net "P2E_CPU_SAS_C_TX_DN5")
	)
	(segment
		(start 80.3656 -56.261)
		(end 80.3402 -56.261)
		(width 0.1016)
		(layer "In2.Cu")
		(net "P2E_CPU_SAS_C_TX_DN5")
	)
	(segment
		(start 45.638466 -16.1036)
		(end 44.958 -16.1036)
		(width 0.1143)
		(layer "In2.Cu")
		(net "P2E_CPU_SAS_C_TX_DN5")
	)
	(segment
		(start 55.095902 -34.286444)
		(end 55.095902 -27.13736)
		(width 0.1143)
		(layer "In2.Cu")
		(net "P2E_CPU_SAS_C_TX_DN5")
	)
	(segment
		(start 41.6814 -14.080998)
		(end 41.418002 -13.8176)
		(width 0.1143)
		(layer "In2.Cu")
		(net "P2E_CPU_SAS_C_TX_DN5")
	)
	(segment
		(start 84.065364 -54.40934)
		(end 83.520788 -54.40934)
		(width 0.1016)
		(layer "In2.Cu")
		(net "P2E_CPU_SAS_C_TX_DN5")
	)
	(segment
		(start 69.1642 -51.054)
		(end 67.692778 -51.054)
		(width 0.1143)
		(layer "In2.Cu")
		(net "P2E_CPU_SAS_C_TX_DN5")
	)
	(segment
		(start 61.1378 -43.591988)
		(end 59.01055 -41.464738)
		(width 0.1143)
		(layer "In2.Cu")
		(net "P2E_CPU_SAS_C_TX_DN5")
	)
	(segment
		(start 44.459906 -14.74724)
		(end 44.241466 -14.5288)
		(width 0.1143)
		(layer "In2.Cu")
		(net "P2E_CPU_SAS_C_TX_DN5")
	)
	(segment
		(start 50.333148 -18.488914)
		(end 48.20158 -18.488914)
		(width 0.1143)
		(layer "In2.Cu")
		(net "P2E_CPU_SAS_C_TX_DN5")
	)
	(segment
		(start 67.375278 -50.7365)
		(end 65.585594 -50.7365)
		(width 0.1143)
		(layer "In2.Cu")
		(net "P2E_CPU_SAS_C_TX_DN5")
	)
	(segment
		(start 61.1378 -45.285406)
		(end 61.1378 -43.591988)
		(width 0.1143)
		(layer "In2.Cu")
		(net "P2E_CPU_SAS_C_TX_DN5")
	)
	(segment
		(start 84.241132 -54.01564)
		(end 84.429092 -54.2036)
		(width 0.1016)
		(layer "F.Cu")
		(net "P2E_CPU_SAS_C_TX_DP5")
	)
	(segment
		(start 85.344 -52.916328)
		(end 85.580728 -52.6796)
		(width 0.1016)
		(layer "F.Cu")
		(net "P2E_CPU_SAS_C_TX_DP5")
	)
	(segment
		(start 84.429092 -54.2036)
		(end 84.684616 -54.2036)
		(width 0.1016)
		(layer "F.Cu")
		(net "P2E_CPU_SAS_C_TX_DP5")
	)
	(segment
		(start 85.344 -53.5432)
		(end 85.344 -52.916328)
		(width 0.1016)
		(layer "F.Cu")
		(net "P2E_CPU_SAS_C_TX_DP5")
	)
	(segment
		(start 85.580728 -52.6796)
		(end 85.580728 -52.564792)
		(width 0.1016)
		(layer "F.Cu")
		(net "P2E_CPU_SAS_C_TX_DP5")
	)
	(segment
		(start 84.684616 -54.2036)
		(end 85.344 -53.5432)
		(width 0.1016)
		(layer "F.Cu")
		(net "P2E_CPU_SAS_C_TX_DP5")
	)
	(segment
		(start 85.982048 -52.163472)
		(end 85.982048 -52.006754)
		(width 0.1016)
		(layer "F.Cu")
		(net "P2E_CPU_SAS_C_TX_DP5")
	)
	(segment
		(start 85.580728 -52.564792)
		(end 85.982048 -52.163472)
		(width 0.1016)
		(layer "F.Cu")
		(net "P2E_CPU_SAS_C_TX_DP5")
	)
	(via
		(at 42.281602 -13.8176)
		(size 0.508)
		(drill 0.254)
		(layers "F.Cu" "B.Cu")
		(net "P2E_CPU_SAS_C_TX_DP5")
	)
	(via
		(at 84.241132 -54.01564)
		(size 0.4318)
		(drill 0.2032)
		(layers "F.Cu" "B.Cu")
		(net "P2E_CPU_SAS_C_TX_DP5")
	)
	(segment
		(start 42.230802 -13.7668)
		(end 42.281602 -13.8176)
		(width 0.1397)
		(layer "B.Cu")
		(net "P2E_CPU_SAS_C_TX_DP5")
	)
	(segment
		(start 42.230802 -13.1572)
		(end 42.230802 -13.7668)
		(width 0.1397)
		(layer "B.Cu")
		(net "P2E_CPU_SAS_C_TX_DP5")
	)
	(segment
		(start 54.255162 -25.527762)
		(end 53.95341 -25.527762)
		(width 0.1143)
		(layer "In2.Cu")
		(net "P2E_CPU_SAS_C_TX_DP5")
	)
	(segment
		(start 53.2003 -22.005544)
		(end 53.41366 -21.792184)
		(width 0.1143)
		(layer "In2.Cu")
		(net "P2E_CPU_SAS_C_TX_DP5")
	)
	(segment
		(start 53.2003 -23.460964)
		(end 53.2003 -23.118064)
		(width 0.1143)
		(layer "In2.Cu")
		(net "P2E_CPU_SAS_C_TX_DP5")
	)
	(segment
		(start 62.953138 -47.636938)
		(end 62.953138 -47.335186)
		(width 0.1143)
		(layer "In2.Cu")
		(net "P2E_CPU_SAS_C_TX_DP5")
	)
	(segment
		(start 54.740048 -26.3144)
		(end 54.497732 -26.072084)
		(width 0.1143)
		(layer "In2.Cu")
		(net "P2E_CPU_SAS_C_TX_DP5")
	)
	(segment
		(start 75.960986 -55.414926)
		(end 75.13701 -54.59095)
		(width 0.1143)
		(layer "In2.Cu")
		(net "P2E_CPU_SAS_C_TX_DP5")
	)
	(segment
		(start 82.624422 -55.018178)
		(end 82.484214 -55.018178)
		(width 0.1016)
		(layer "In2.Cu")
		(net "P2E_CPU_SAS_C_TX_DP5")
	)
	(segment
		(start 62.0522 -46.736)
		(end 62.0522 -45.7327)
		(width 0.1143)
		(layer "In2.Cu")
		(net "P2E_CPU_SAS_C_TX_DP5")
	)
	(segment
		(start 67.829684 -50.7238)
		(end 67.512184 -50.4063)
		(width 0.1143)
		(layer "In2.Cu")
		(net "P2E_CPU_SAS_C_TX_DP5")
	)
	(segment
		(start 61.468 -45.1485)
		(end 61.468 -43.455082)
		(width 0.1143)
		(layer "In2.Cu")
		(net "P2E_CPU_SAS_C_TX_DP5")
	)
	(segment
		(start 55.426102 -34.149538)
		(end 55.426102 -27.000454)
		(width 0.1143)
		(layer "In2.Cu")
		(net "P2E_CPU_SAS_C_TX_DP5")
	)
	(segment
		(start 71.891144 -53.012086)
		(end 71.589392 -53.012086)
		(width 0.1143)
		(layer "In2.Cu")
		(net "P2E_CPU_SAS_C_TX_DP5")
	)
	(segment
		(start 61.468 -43.455082)
		(end 59.34075 -41.327832)
		(width 0.1143)
		(layer "In2.Cu")
		(net "P2E_CPU_SAS_C_TX_DP5")
	)
	(segment
		(start 53.95341 -25.527762)
		(end 53.2003 -24.774652)
		(width 0.1143)
		(layer "In2.Cu")
		(net "P2E_CPU_SAS_C_TX_DP5")
	)
	(segment
		(start 83.43646 -54.20614)
		(end 83.195414 -54.447186)
		(width 0.1016)
		(layer "In2.Cu")
		(net "P2E_CPU_SAS_C_TX_DP5")
	)
	(segment
		(start 44.790106 -14.610334)
		(end 44.378372 -14.1986)
		(width 0.1143)
		(layer "In2.Cu")
		(net "P2E_CPU_SAS_C_TX_DP5")
	)
	(segment
		(start 80.81264 -55.89524)
		(end 80.71358 -55.9943)
		(width 0.1016)
		(layer "In2.Cu")
		(net "P2E_CPU_SAS_C_TX_DP5")
	)
	(segment
		(start 53.41366 -21.792184)
		(end 53.41366 -21.449284)
		(width 0.1143)
		(layer "In2.Cu")
		(net "P2E_CPU_SAS_C_TX_DP5")
	)
	(segment
		(start 42.0116 -14.087602)
		(end 42.281602 -13.8176)
		(width 0.1143)
		(layer "In2.Cu")
		(net "P2E_CPU_SAS_C_TX_DP5")
	)
	(segment
		(start 42.290746 -15.83944)
		(end 42.0116 -15.560294)
		(width 0.1143)
		(layer "In2.Cu")
		(net "P2E_CPU_SAS_C_TX_DP5")
	)
	(segment
		(start 51.499262 -19.187922)
		(end 50.470054 -18.158714)
		(width 0.1143)
		(layer "In2.Cu")
		(net "P2E_CPU_SAS_C_TX_DP5")
	)
	(segment
		(start 53.2003 -21.235924)
		(end 53.2003 -20.88896)
		(width 0.1143)
		(layer "In2.Cu")
		(net "P2E_CPU_SAS_C_TX_DP5")
	)
	(segment
		(start 67.512184 -50.4063)
		(end 65.7225 -50.4063)
		(width 0.1143)
		(layer "In2.Cu")
		(net "P2E_CPU_SAS_C_TX_DP5")
	)
	(segment
		(start 53.41366 -24.017224)
		(end 53.41366 -23.674324)
		(width 0.1143)
		(layer "In2.Cu")
		(net "P2E_CPU_SAS_C_TX_DP5")
	)
	(segment
		(start 53.41366 -21.449284)
		(end 53.2003 -21.235924)
		(width 0.1143)
		(layer "In2.Cu")
		(net "P2E_CPU_SAS_C_TX_DP5")
	)
	(segment
		(start 53.2003 -22.348444)
		(end 53.2003 -22.005544)
		(width 0.1143)
		(layer "In2.Cu")
		(net "P2E_CPU_SAS_C_TX_DP5")
	)
	(segment
		(start 82.484214 -55.018178)
		(end 82.268822 -55.233824)
		(width 0.1016)
		(layer "In2.Cu")
		(net "P2E_CPU_SAS_C_TX_DP5")
	)
	(segment
		(start 69.301106 -50.7238)
		(end 67.829684 -50.7238)
		(width 0.1143)
		(layer "In2.Cu")
		(net "P2E_CPU_SAS_C_TX_DP5")
	)
	(segment
		(start 59.34075 -41.327832)
		(end 59.34075 -38.064186)
		(width 0.1143)
		(layer "In2.Cu")
		(net "P2E_CPU_SAS_C_TX_DP5")
	)
	(segment
		(start 53.2003 -20.88896)
		(end 52.04333 -19.73199)
		(width 0.1143)
		(layer "In2.Cu")
		(net "P2E_CPU_SAS_C_TX_DP5")
	)
	(segment
		(start 62.40907 -47.09287)
		(end 62.0522 -46.736)
		(width 0.1143)
		(layer "In2.Cu")
		(net "P2E_CPU_SAS_C_TX_DP5")
	)
	(segment
		(start 53.2003 -24.774652)
		(end 53.2003 -24.230584)
		(width 0.1143)
		(layer "In2.Cu")
		(net "P2E_CPU_SAS_C_TX_DP5")
	)
	(segment
		(start 80.3656 -55.9308)
		(end 80.3402 -55.9308)
		(width 0.1016)
		(layer "In2.Cu")
		(net "P2E_CPU_SAS_C_TX_DP5")
	)
	(segment
		(start 71.346822 -52.467764)
		(end 71.104506 -52.225448)
		(width 0.1143)
		(layer "In2.Cu")
		(net "P2E_CPU_SAS_C_TX_DP5")
	)
	(segment
		(start 84.241132 -54.01564)
		(end 84.050632 -54.20614)
		(width 0.1016)
		(layer "In2.Cu")
		(net "P2E_CPU_SAS_C_TX_DP5")
	)
	(segment
		(start 82.268822 -55.233824)
		(end 82.268822 -55.373778)
		(width 0.1016)
		(layer "In2.Cu")
		(net "P2E_CPU_SAS_C_TX_DP5")
	)
	(segment
		(start 47.614586 -16.13408)
		(end 47.165006 -15.6845)
		(width 0.1143)
		(layer "In2.Cu")
		(net "P2E_CPU_SAS_C_TX_DP5")
	)
	(segment
		(start 52.04333 -19.73199)
		(end 52.04333 -19.430238)
		(width 0.1143)
		(layer "In2.Cu")
		(net "P2E_CPU_SAS_C_TX_DP5")
	)
	(segment
		(start 55.28437 -26.858722)
		(end 55.28437 -26.55697)
		(width 0.1143)
		(layer "In2.Cu")
		(net "P2E_CPU_SAS_C_TX_DP5")
	)
	(segment
		(start 42.0116 -15.560294)
		(end 42.0116 -14.087602)
		(width 0.1143)
		(layer "In2.Cu")
		(net "P2E_CPU_SAS_C_TX_DP5")
	)
	(segment
		(start 53.41366 -23.674324)
		(end 53.2003 -23.460964)
		(width 0.1143)
		(layer "In2.Cu")
		(net "P2E_CPU_SAS_C_TX_DP5")
	)
	(segment
		(start 45.59046 -15.6845)
		(end 45.50156 -15.7734)
		(width 0.1143)
		(layer "In2.Cu")
		(net "P2E_CPU_SAS_C_TX_DP5")
	)
	(segment
		(start 53.2003 -24.230584)
		(end 53.41366 -24.017224)
		(width 0.1143)
		(layer "In2.Cu")
		(net "P2E_CPU_SAS_C_TX_DP5")
	)
	(segment
		(start 79.8322 -55.9308)
		(end 79.316326 -55.414926)
		(width 0.1143)
		(layer "In2.Cu")
		(net "P2E_CPU_SAS_C_TX_DP5")
	)
	(segment
		(start 47.165006 -15.6845)
		(end 45.59046 -15.6845)
		(width 0.1143)
		(layer "In2.Cu")
		(net "P2E_CPU_SAS_C_TX_DP5")
	)
	(segment
		(start 83.05546 -54.447186)
		(end 82.839814 -54.662578)
		(width 0.1016)
		(layer "In2.Cu")
		(net "P2E_CPU_SAS_C_TX_DP5")
	)
	(segment
		(start 63.739776 -48.121824)
		(end 63.49746 -47.879508)
		(width 0.1143)
		(layer "In2.Cu")
		(net "P2E_CPU_SAS_C_TX_DP5")
	)
	(segment
		(start 51.801014 -19.187922)
		(end 51.499262 -19.187922)
		(width 0.1143)
		(layer "In2.Cu")
		(net "P2E_CPU_SAS_C_TX_DP5")
	)
	(segment
		(start 55.426102 -27.000454)
		(end 55.28437 -26.858722)
		(width 0.1143)
		(layer "In2.Cu")
		(net "P2E_CPU_SAS_C_TX_DP5")
	)
	(segment
		(start 71.346822 -52.769516)
		(end 71.346822 -52.467764)
		(width 0.1143)
		(layer "In2.Cu")
		(net "P2E_CPU_SAS_C_TX_DP5")
	)
	(segment
		(start 65.7225 -50.4063)
		(end 63.739776 -48.423576)
		(width 0.1143)
		(layer "In2.Cu")
		(net "P2E_CPU_SAS_C_TX_DP5")
	)
	(segment
		(start 81.11744 -55.89524)
		(end 80.81264 -55.89524)
		(width 0.1016)
		(layer "In2.Cu")
		(net "P2E_CPU_SAS_C_TX_DP5")
	)
	(segment
		(start 59.34075 -38.064186)
		(end 55.426102 -34.149538)
		(width 0.1143)
		(layer "In2.Cu")
		(net "P2E_CPU_SAS_C_TX_DP5")
	)
	(segment
		(start 72.13346 -53.556154)
		(end 72.13346 -53.254402)
		(width 0.1143)
		(layer "In2.Cu")
		(net "P2E_CPU_SAS_C_TX_DP5")
	)
	(segment
		(start 53.2003 -23.118064)
		(end 53.41366 -22.904704)
		(width 0.1143)
		(layer "In2.Cu")
		(net "P2E_CPU_SAS_C_TX_DP5")
	)
	(segment
		(start 71.589392 -53.012086)
		(end 71.346822 -52.769516)
		(width 0.1143)
		(layer "In2.Cu")
		(net "P2E_CPU_SAS_C_TX_DP5")
	)
	(segment
		(start 43.6372 -14.1986)
		(end 43.1038 -14.732)
		(width 0.1143)
		(layer "In2.Cu")
		(net "P2E_CPU_SAS_C_TX_DP5")
	)
	(segment
		(start 71.104506 -52.225448)
		(end 70.802754 -52.225448)
		(width 0.1143)
		(layer "In2.Cu")
		(net "P2E_CPU_SAS_C_TX_DP5")
	)
	(segment
		(start 73.168256 -54.59095)
		(end 72.13346 -53.556154)
		(width 0.1143)
		(layer "In2.Cu")
		(net "P2E_CPU_SAS_C_TX_DP5")
	)
	(segment
		(start 84.050632 -54.20614)
		(end 83.43646 -54.20614)
		(width 0.1016)
		(layer "In2.Cu")
		(net "P2E_CPU_SAS_C_TX_DP5")
	)
	(segment
		(start 44.378372 -14.1986)
		(end 43.6372 -14.1986)
		(width 0.1143)
		(layer "In2.Cu")
		(net "P2E_CPU_SAS_C_TX_DP5")
	)
	(segment
		(start 52.04333 -19.430238)
		(end 51.801014 -19.187922)
		(width 0.1143)
		(layer "In2.Cu")
		(net "P2E_CPU_SAS_C_TX_DP5")
	)
	(segment
		(start 43.1038 -15.494)
		(end 42.75836 -15.83944)
		(width 0.1143)
		(layer "In2.Cu")
		(net "P2E_CPU_SAS_C_TX_DP5")
	)
	(segment
		(start 83.195414 -54.447186)
		(end 83.05546 -54.447186)
		(width 0.1016)
		(layer "In2.Cu")
		(net "P2E_CPU_SAS_C_TX_DP5")
	)
	(segment
		(start 82.268822 -55.373778)
		(end 81.6483 -55.9943)
		(width 0.1016)
		(layer "In2.Cu")
		(net "P2E_CPU_SAS_C_TX_DP5")
	)
	(segment
		(start 53.41366 -22.561804)
		(end 53.2003 -22.348444)
		(width 0.1143)
		(layer "In2.Cu")
		(net "P2E_CPU_SAS_C_TX_DP5")
	)
	(segment
		(start 54.497732 -26.072084)
		(end 54.497732 -25.770332)
		(width 0.1143)
		(layer "In2.Cu")
		(net "P2E_CPU_SAS_C_TX_DP5")
	)
	(segment
		(start 55.28437 -26.55697)
		(end 55.0418 -26.3144)
		(width 0.1143)
		(layer "In2.Cu")
		(net "P2E_CPU_SAS_C_TX_DP5")
	)
	(segment
		(start 80.3402 -55.9308)
		(end 79.8322 -55.9308)
		(width 0.1143)
		(layer "In2.Cu")
		(net "P2E_CPU_SAS_C_TX_DP5")
	)
	(segment
		(start 62.0522 -45.7327)
		(end 61.468 -45.1485)
		(width 0.1143)
		(layer "In2.Cu")
		(net "P2E_CPU_SAS_C_TX_DP5")
	)
	(segment
		(start 63.195708 -47.879508)
		(end 62.953138 -47.636938)
		(width 0.1143)
		(layer "In2.Cu")
		(net "P2E_CPU_SAS_C_TX_DP5")
	)
	(segment
		(start 81.2165 -55.9943)
		(end 81.11744 -55.89524)
		(width 0.1016)
		(layer "In2.Cu")
		(net "P2E_CPU_SAS_C_TX_DP5")
	)
	(segment
		(start 75.13701 -54.59095)
		(end 73.168256 -54.59095)
		(width 0.1143)
		(layer "In2.Cu")
		(net "P2E_CPU_SAS_C_TX_DP5")
	)
	(segment
		(start 70.802754 -52.225448)
		(end 69.301106 -50.7238)
		(width 0.1143)
		(layer "In2.Cu")
		(net "P2E_CPU_SAS_C_TX_DP5")
	)
	(segment
		(start 45.50156 -15.7734)
		(end 45.094906 -15.7734)
		(width 0.1143)
		(layer "In2.Cu")
		(net "P2E_CPU_SAS_C_TX_DP5")
	)
	(segment
		(start 48.338486 -18.158714)
		(end 47.614586 -17.434814)
		(width 0.1143)
		(layer "In2.Cu")
		(net "P2E_CPU_SAS_C_TX_DP5")
	)
	(segment
		(start 42.75836 -15.83944)
		(end 42.290746 -15.83944)
		(width 0.1143)
		(layer "In2.Cu")
		(net "P2E_CPU_SAS_C_TX_DP5")
	)
	(segment
		(start 62.953138 -47.335186)
		(end 62.710822 -47.09287)
		(width 0.1143)
		(layer "In2.Cu")
		(net "P2E_CPU_SAS_C_TX_DP5")
	)
	(segment
		(start 43.1038 -14.732)
		(end 43.1038 -15.494)
		(width 0.1143)
		(layer "In2.Cu")
		(net "P2E_CPU_SAS_C_TX_DP5")
	)
	(segment
		(start 54.497732 -25.770332)
		(end 54.255162 -25.527762)
		(width 0.1143)
		(layer "In2.Cu")
		(net "P2E_CPU_SAS_C_TX_DP5")
	)
	(segment
		(start 80.71358 -55.9943)
		(end 80.4291 -55.9943)
		(width 0.1016)
		(layer "In2.Cu")
		(net "P2E_CPU_SAS_C_TX_DP5")
	)
	(segment
		(start 55.0418 -26.3144)
		(end 54.740048 -26.3144)
		(width 0.1143)
		(layer "In2.Cu")
		(net "P2E_CPU_SAS_C_TX_DP5")
	)
	(segment
		(start 82.839814 -54.662578)
		(end 82.839814 -54.802786)
		(width 0.1016)
		(layer "In2.Cu")
		(net "P2E_CPU_SAS_C_TX_DP5")
	)
	(segment
		(start 45.094906 -15.7734)
		(end 44.790106 -15.4686)
		(width 0.1143)
		(layer "In2.Cu")
		(net "P2E_CPU_SAS_C_TX_DP5")
	)
	(segment
		(start 53.41366 -22.904704)
		(end 53.41366 -22.561804)
		(width 0.1143)
		(layer "In2.Cu")
		(net "P2E_CPU_SAS_C_TX_DP5")
	)
	(segment
		(start 50.470054 -18.158714)
		(end 48.338486 -18.158714)
		(width 0.1143)
		(layer "In2.Cu")
		(net "P2E_CPU_SAS_C_TX_DP5")
	)
	(segment
		(start 80.4291 -55.9943)
		(end 80.3656 -55.9308)
		(width 0.1016)
		(layer "In2.Cu")
		(net "P2E_CPU_SAS_C_TX_DP5")
	)
	(segment
		(start 72.13346 -53.254402)
		(end 71.891144 -53.012086)
		(width 0.1143)
		(layer "In2.Cu")
		(net "P2E_CPU_SAS_C_TX_DP5")
	)
	(segment
		(start 82.839814 -54.802786)
		(end 82.624422 -55.018178)
		(width 0.1016)
		(layer "In2.Cu")
		(net "P2E_CPU_SAS_C_TX_DP5")
	)
	(segment
		(start 63.49746 -47.879508)
		(end 63.195708 -47.879508)
		(width 0.1143)
		(layer "In2.Cu")
		(net "P2E_CPU_SAS_C_TX_DP5")
	)
	(segment
		(start 44.790106 -15.4686)
		(end 44.790106 -14.610334)
		(width 0.1143)
		(layer "In2.Cu")
		(net "P2E_CPU_SAS_C_TX_DP5")
	)
	(segment
		(start 63.739776 -48.423576)
		(end 63.739776 -48.121824)
		(width 0.1143)
		(layer "In2.Cu")
		(net "P2E_CPU_SAS_C_TX_DP5")
	)
	(segment
		(start 79.316326 -55.414926)
		(end 75.960986 -55.414926)
		(width 0.1143)
		(layer "In2.Cu")
		(net "P2E_CPU_SAS_C_TX_DP5")
	)
	(segment
		(start 47.614586 -17.434814)
		(end 47.614586 -16.13408)
		(width 0.1143)
		(layer "In2.Cu")
		(net "P2E_CPU_SAS_C_TX_DP5")
	)
	(segment
		(start 81.6483 -55.9943)
		(end 81.2165 -55.9943)
		(width 0.1016)
		(layer "In2.Cu")
		(net "P2E_CPU_SAS_C_TX_DP5")
	)
	(segment
		(start 62.710822 -47.09287)
		(end 62.40907 -47.09287)
		(width 0.1143)
		(layer "In2.Cu")
		(net "P2E_CPU_SAS_C_TX_DP5")
	)
	(segment
		(start 85.527388 -50.213514)
		(end 85.1916 -49.877726)
		(width 0.1397)
		(layer "F.Cu")
		(net "P2E_CPU_SAS_C_TX_DN4")
	)
	(segment
		(start 85.1916 -49.877726)
		(end 85.1916 -49.8602)
		(width 0.1397)
		(layer "F.Cu")
		(net "P2E_CPU_SAS_C_TX_DN4")
	)
	(via
		(at 45.466 -13.8176)
		(size 0.508)
		(drill 0.254)
		(layers "F.Cu" "B.Cu")
		(net "P2E_CPU_SAS_C_TX_DN4")
	)
	(via
		(at 85.1916 -49.8602)
		(size 0.4318)
		(drill 0.2032)
		(layers "F.Cu" "B.Cu")
		(net "P2E_CPU_SAS_C_TX_DN4")
	)
	(segment
		(start 45.466 -13.1572)
		(end 45.466 -13.8176)
		(width 0.1397)
		(layer "B.Cu")
		(net "P2E_CPU_SAS_C_TX_DN4")
	)
	(segment
		(start 60.286392 -36.959286)
		(end 60.286392 -34.544)
		(width 0.1143)
		(layer "In2.Cu")
		(net "P2E_CPU_SAS_C_TX_DN4")
	)
	(segment
		(start 86.190836 -50.453036)
		(end 86.190836 -51.044856)
		(width 0.1016)
		(layer "In2.Cu")
		(net "P2E_CPU_SAS_C_TX_DN4")
	)
	(segment
		(start 45.6819 -14.399006)
		(end 45.6819 -14.0335)
		(width 0.1143)
		(layer "In2.Cu")
		(net "P2E_CPU_SAS_C_TX_DN4")
	)
	(segment
		(start 79.520288 -55.082694)
		(end 76.510388 -55.082694)
		(width 0.1143)
		(layer "In2.Cu")
		(net "P2E_CPU_SAS_C_TX_DN4")
	)
	(segment
		(start 56.8198 -21.549106)
		(end 56.8198 -19.979894)
		(width 0.1143)
		(layer "In2.Cu")
		(net "P2E_CPU_SAS_C_TX_DN4")
	)
	(segment
		(start 60.286392 -34.544)
		(end 58.928 -33.185608)
		(width 0.1143)
		(layer "In2.Cu")
		(net "P2E_CPU_SAS_C_TX_DN4")
	)
	(segment
		(start 80.000094 -55.5625)
		(end 79.520288 -55.082694)
		(width 0.1143)
		(layer "In2.Cu")
		(net "P2E_CPU_SAS_C_TX_DN4")
	)
	(segment
		(start 74.774044 -53.34635)
		(end 73.883266 -53.34635)
		(width 0.1143)
		(layer "In2.Cu")
		(net "P2E_CPU_SAS_C_TX_DN4")
	)
	(segment
		(start 57.6072 -18.424906)
		(end 57.444894 -18.2626)
		(width 0.1143)
		(layer "In2.Cu")
		(net "P2E_CPU_SAS_C_TX_DN4")
	)
	(segment
		(start 80.4291 -55.5625)
		(end 80.4164 -55.5625)
		(width 0.1016)
		(layer "In2.Cu")
		(net "P2E_CPU_SAS_C_TX_DN4")
	)
	(segment
		(start 58.371994 -22.1615)
		(end 57.432194 -22.1615)
		(width 0.1143)
		(layer "In2.Cu")
		(net "P2E_CPU_SAS_C_TX_DN4")
	)
	(segment
		(start 59.96305 -37.282628)
		(end 60.286392 -36.959286)
		(width 0.1143)
		(layer "In2.Cu")
		(net "P2E_CPU_SAS_C_TX_DN4")
	)
	(segment
		(start 57.432194 -22.1615)
		(end 56.8198 -21.549106)
		(width 0.1143)
		(layer "In2.Cu")
		(net "P2E_CPU_SAS_C_TX_DN4")
	)
	(segment
		(start 55.6514 -17.2974)
		(end 54.5211 -16.1671)
		(width 0.1143)
		(layer "In2.Cu")
		(net "P2E_CPU_SAS_C_TX_DN4")
	)
	(segment
		(start 67.769994 -49.784)
		(end 66.04 -49.784)
		(width 0.1143)
		(layer "In2.Cu")
		(net "P2E_CPU_SAS_C_TX_DN4")
	)
	(segment
		(start 85.3948 -50.2158)
		(end 85.9536 -50.2158)
		(width 0.1016)
		(layer "In2.Cu")
		(net "P2E_CPU_SAS_C_TX_DN4")
	)
	(segment
		(start 57.6072 -19.192494)
		(end 57.6072 -18.424906)
		(width 0.1143)
		(layer "In2.Cu")
		(net "P2E_CPU_SAS_C_TX_DN4")
	)
	(segment
		(start 85.9536 -50.2158)
		(end 86.190836 -50.453036)
		(width 0.1016)
		(layer "In2.Cu")
		(net "P2E_CPU_SAS_C_TX_DN4")
	)
	(segment
		(start 45.6819 -14.0335)
		(end 45.466 -13.8176)
		(width 0.1143)
		(layer "In2.Cu")
		(net "P2E_CPU_SAS_C_TX_DN4")
	)
	(segment
		(start 85.1916 -49.8602)
		(end 85.1916 -50.0126)
		(width 0.1016)
		(layer "In2.Cu")
		(net "P2E_CPU_SAS_C_TX_DN4")
	)
	(segment
		(start 85.1916 -50.0126)
		(end 85.3948 -50.2158)
		(width 0.1016)
		(layer "In2.Cu")
		(net "P2E_CPU_SAS_C_TX_DN4")
	)
	(segment
		(start 62.0903 -43.197272)
		(end 59.96305 -41.070022)
		(width 0.1143)
		(layer "In2.Cu")
		(net "P2E_CPU_SAS_C_TX_DN4")
	)
	(segment
		(start 56.073294 -18.2626)
		(end 55.6514 -17.840706)
		(width 0.1143)
		(layer "In2.Cu")
		(net "P2E_CPU_SAS_C_TX_DN4")
	)
	(segment
		(start 80.4164 -55.5625)
		(end 80.000094 -55.5625)
		(width 0.1143)
		(layer "In2.Cu")
		(net "P2E_CPU_SAS_C_TX_DN4")
	)
	(segment
		(start 56.8198 -19.979894)
		(end 57.6072 -19.192494)
		(width 0.1143)
		(layer "In2.Cu")
		(net "P2E_CPU_SAS_C_TX_DN4")
	)
	(segment
		(start 70.638416 -50.1015)
		(end 68.087494 -50.1015)
		(width 0.1143)
		(layer "In2.Cu")
		(net "P2E_CPU_SAS_C_TX_DN4")
	)
	(segment
		(start 60.30595 -27.813)
		(end 60.30595 -26.556716)
		(width 0.1143)
		(layer "In2.Cu")
		(net "P2E_CPU_SAS_C_TX_DN4")
	)
	(segment
		(start 80.4926 -55.499)
		(end 80.4291 -55.5625)
		(width 0.1016)
		(layer "In2.Cu")
		(net "P2E_CPU_SAS_C_TX_DN4")
	)
	(segment
		(start 59.96305 -41.070022)
		(end 59.96305 -37.282628)
		(width 0.1143)
		(layer "In2.Cu")
		(net "P2E_CPU_SAS_C_TX_DN4")
	)
	(segment
		(start 57.444894 -18.2626)
		(end 56.073294 -18.2626)
		(width 0.1143)
		(layer "In2.Cu")
		(net "P2E_CPU_SAS_C_TX_DN4")
	)
	(segment
		(start 86.190836 -51.044856)
		(end 85.83041 -51.405282)
		(width 0.1016)
		(layer "In2.Cu")
		(net "P2E_CPU_SAS_C_TX_DN4")
	)
	(segment
		(start 81.440528 -55.499)
		(end 80.4926 -55.499)
		(width 0.1016)
		(layer "In2.Cu")
		(net "P2E_CPU_SAS_C_TX_DN4")
	)
	(segment
		(start 63.814452 -46.614842)
		(end 62.0903 -44.89069)
		(width 0.1143)
		(layer "In2.Cu")
		(net "P2E_CPU_SAS_C_TX_DN4")
	)
	(segment
		(start 55.6514 -17.840706)
		(end 55.6514 -17.2974)
		(width 0.1143)
		(layer "In2.Cu")
		(net "P2E_CPU_SAS_C_TX_DN4")
	)
	(segment
		(start 81.8134 -55.126128)
		(end 81.440528 -55.499)
		(width 0.1016)
		(layer "In2.Cu")
		(net "P2E_CPU_SAS_C_TX_DN4")
	)
	(segment
		(start 64.9224 -48.6664)
		(end 64.9224 -46.949106)
		(width 0.1143)
		(layer "In2.Cu")
		(net "P2E_CPU_SAS_C_TX_DN4")
	)
	(segment
		(start 73.883266 -53.34635)
		(end 70.638416 -50.1015)
		(width 0.1143)
		(layer "In2.Cu")
		(net "P2E_CPU_SAS_C_TX_DN4")
	)
	(segment
		(start 85.221318 -51.405282)
		(end 81.8134 -54.8132)
		(width 0.1016)
		(layer "In2.Cu")
		(net "P2E_CPU_SAS_C_TX_DN4")
	)
	(segment
		(start 58.928 -33.185608)
		(end 58.928 -29.19095)
		(width 0.1143)
		(layer "In2.Cu")
		(net "P2E_CPU_SAS_C_TX_DN4")
	)
	(segment
		(start 58.2549 -24.505666)
		(end 58.2549 -23.561294)
		(width 0.1143)
		(layer "In2.Cu")
		(net "P2E_CPU_SAS_C_TX_DN4")
	)
	(segment
		(start 58.2549 -23.561294)
		(end 58.8772 -22.938994)
		(width 0.1143)
		(layer "In2.Cu")
		(net "P2E_CPU_SAS_C_TX_DN4")
	)
	(segment
		(start 68.087494 -50.1015)
		(end 67.769994 -49.784)
		(width 0.1143)
		(layer "In2.Cu")
		(net "P2E_CPU_SAS_C_TX_DN4")
	)
	(segment
		(start 53.672994 -16.1671)
		(end 52.568094 -15.0622)
		(width 0.1143)
		(layer "In2.Cu")
		(net "P2E_CPU_SAS_C_TX_DN4")
	)
	(segment
		(start 52.568094 -15.0622)
		(end 46.345094 -15.0622)
		(width 0.1143)
		(layer "In2.Cu")
		(net "P2E_CPU_SAS_C_TX_DN4")
	)
	(segment
		(start 58.928 -29.19095)
		(end 60.30595 -27.813)
		(width 0.1143)
		(layer "In2.Cu")
		(net "P2E_CPU_SAS_C_TX_DN4")
	)
	(segment
		(start 46.345094 -15.0622)
		(end 45.6819 -14.399006)
		(width 0.1143)
		(layer "In2.Cu")
		(net "P2E_CPU_SAS_C_TX_DN4")
	)
	(segment
		(start 58.8772 -22.666706)
		(end 58.371994 -22.1615)
		(width 0.1143)
		(layer "In2.Cu")
		(net "P2E_CPU_SAS_C_TX_DN4")
	)
	(segment
		(start 58.8772 -22.938994)
		(end 58.8772 -22.666706)
		(width 0.1143)
		(layer "In2.Cu")
		(net "P2E_CPU_SAS_C_TX_DN4")
	)
	(segment
		(start 62.0903 -44.89069)
		(end 62.0903 -43.197272)
		(width 0.1143)
		(layer "In2.Cu")
		(net "P2E_CPU_SAS_C_TX_DN4")
	)
	(segment
		(start 76.510388 -55.082694)
		(end 74.774044 -53.34635)
		(width 0.1143)
		(layer "In2.Cu")
		(net "P2E_CPU_SAS_C_TX_DN4")
	)
	(segment
		(start 64.9224 -46.949106)
		(end 64.588136 -46.614842)
		(width 0.1143)
		(layer "In2.Cu")
		(net "P2E_CPU_SAS_C_TX_DN4")
	)
	(segment
		(start 64.588136 -46.614842)
		(end 63.814452 -46.614842)
		(width 0.1143)
		(layer "In2.Cu")
		(net "P2E_CPU_SAS_C_TX_DN4")
	)
	(segment
		(start 81.8134 -54.8132)
		(end 81.8134 -55.126128)
		(width 0.1016)
		(layer "In2.Cu")
		(net "P2E_CPU_SAS_C_TX_DN4")
	)
	(segment
		(start 54.5211 -16.1671)
		(end 53.672994 -16.1671)
		(width 0.1143)
		(layer "In2.Cu")
		(net "P2E_CPU_SAS_C_TX_DN4")
	)
	(segment
		(start 66.04 -49.784)
		(end 64.9224 -48.6664)
		(width 0.1143)
		(layer "In2.Cu")
		(net "P2E_CPU_SAS_C_TX_DN4")
	)
	(segment
		(start 60.30595 -26.556716)
		(end 58.2549 -24.505666)
		(width 0.1143)
		(layer "In2.Cu")
		(net "P2E_CPU_SAS_C_TX_DN4")
	)
	(segment
		(start 85.83041 -51.405282)
		(end 85.221318 -51.405282)
		(width 0.1016)
		(layer "In2.Cu")
		(net "P2E_CPU_SAS_C_TX_DN4")
	)
	(segment
		(start 85.557868 -51.447954)
		(end 85.557868 -50.90668)
		(width 0.1397)
		(layer "F.Cu")
		(net "P2E_CPU_SAS_C_TX_DP4")
	)
	(segment
		(start 85.557868 -50.90668)
		(end 85.277706 -50.626518)
		(width 0.1397)
		(layer "F.Cu")
		(net "P2E_CPU_SAS_C_TX_DP4")
	)
	(via
		(at 46.1772 -13.8176)
		(size 0.508)
		(drill 0.254)
		(layers "F.Cu" "B.Cu")
		(net "P2E_CPU_SAS_C_TX_DP4")
	)
	(via
		(at 85.277706 -50.626518)
		(size 0.4318)
		(drill 0.2032)
		(layers "F.Cu" "B.Cu")
		(net "P2E_CPU_SAS_C_TX_DP4")
	)
	(segment
		(start 46.228 -13.7668)
		(end 46.1772 -13.8176)
		(width 0.1397)
		(layer "B.Cu")
		(net "P2E_CPU_SAS_C_TX_DP4")
	)
	(segment
		(start 46.228 -13.1572)
		(end 46.228 -13.7668)
		(width 0.1397)
		(layer "B.Cu")
		(net "P2E_CPU_SAS_C_TX_DP4")
	)
	(segment
		(start 46.1772 -13.8176)
		(end 46.0121 -13.9827)
		(width 0.1143)
		(layer "In2.Cu")
		(net "P2E_CPU_SAS_C_TX_DP4")
	)
	(segment
		(start 72.647048 -51.341274)
		(end 72.889364 -51.58359)
		(width 0.1143)
		(layer "In2.Cu")
		(net "P2E_CPU_SAS_C_TX_DP4")
	)
	(segment
		(start 55.9816 -17.7038)
		(end 56.2102 -17.9324)
		(width 0.1143)
		(layer "In2.Cu")
		(net "P2E_CPU_SAS_C_TX_DP4")
	)
	(segment
		(start 57.15 -21.4122)
		(end 57.5691 -21.8313)
		(width 0.1143)
		(layer "In2.Cu")
		(net "P2E_CPU_SAS_C_TX_DP4")
	)
	(segment
		(start 73.676002 -52.67198)
		(end 74.020172 -53.01615)
		(width 0.1143)
		(layer "In2.Cu")
		(net "P2E_CPU_SAS_C_TX_DP4")
	)
	(segment
		(start 57.5691 -21.8313)
		(end 58.5089 -21.8313)
		(width 0.1143)
		(layer "In2.Cu")
		(net "P2E_CPU_SAS_C_TX_DP4")
	)
	(segment
		(start 85.869272 -50.419)
		(end 85.485224 -50.419)
		(width 0.1016)
		(layer "In2.Cu")
		(net "P2E_CPU_SAS_C_TX_DP4")
	)
	(segment
		(start 65.2526 -46.8122)
		(end 65.2526 -48.529494)
		(width 0.1143)
		(layer "In2.Cu")
		(net "P2E_CPU_SAS_C_TX_DP4")
	)
	(segment
		(start 60.29325 -40.933116)
		(end 62.4205 -43.060366)
		(width 0.1143)
		(layer "In2.Cu")
		(net "P2E_CPU_SAS_C_TX_DP4")
	)
	(segment
		(start 46.0121 -13.9827)
		(end 46.0121 -14.2621)
		(width 0.1143)
		(layer "In2.Cu")
		(net "P2E_CPU_SAS_C_TX_DP4")
	)
	(segment
		(start 83.423506 -52.775358)
		(end 83.639152 -52.559966)
		(width 0.1016)
		(layer "In2.Cu")
		(net "P2E_CPU_SAS_C_TX_DP4")
	)
	(segment
		(start 60.63615 -26.41981)
		(end 60.63615 -27.949906)
		(width 0.1143)
		(layer "In2.Cu")
		(net "P2E_CPU_SAS_C_TX_DP4")
	)
	(segment
		(start 60.29325 -37.419534)
		(end 60.29325 -40.933116)
		(width 0.1143)
		(layer "In2.Cu")
		(net "P2E_CPU_SAS_C_TX_DP4")
	)
	(segment
		(start 62.4205 -43.060366)
		(end 62.4205 -44.753784)
		(width 0.1143)
		(layer "In2.Cu")
		(net "P2E_CPU_SAS_C_TX_DP4")
	)
	(segment
		(start 72.889364 -51.58359)
		(end 72.889364 -51.885342)
		(width 0.1143)
		(layer "In2.Cu")
		(net "P2E_CPU_SAS_C_TX_DP4")
	)
	(segment
		(start 80.4164 -55.2323)
		(end 80.4799 -55.2958)
		(width 0.1016)
		(layer "In2.Cu")
		(net "P2E_CPU_SAS_C_TX_DP4")
	)
	(segment
		(start 69.688202 -49.7713)
		(end 69.901562 -49.55794)
		(width 0.1143)
		(layer "In2.Cu")
		(net "P2E_CPU_SAS_C_TX_DP4")
	)
	(segment
		(start 73.676002 -52.370228)
		(end 73.676002 -52.67198)
		(width 0.1143)
		(layer "In2.Cu")
		(net "P2E_CPU_SAS_C_TX_DP4")
	)
	(segment
		(start 72.102726 -50.796952)
		(end 72.102726 -51.098704)
		(width 0.1143)
		(layer "In2.Cu")
		(net "P2E_CPU_SAS_C_TX_DP4")
	)
	(segment
		(start 69.131942 -49.55794)
		(end 69.345302 -49.7713)
		(width 0.1143)
		(layer "In2.Cu")
		(net "P2E_CPU_SAS_C_TX_DP4")
	)
	(segment
		(start 46.482 -14.732)
		(end 52.705 -14.732)
		(width 0.1143)
		(layer "In2.Cu")
		(net "P2E_CPU_SAS_C_TX_DP4")
	)
	(segment
		(start 80.137 -55.2323)
		(end 80.4164 -55.2323)
		(width 0.1143)
		(layer "In2.Cu")
		(net "P2E_CPU_SAS_C_TX_DP4")
	)
	(segment
		(start 70.775322 -49.7713)
		(end 71.558658 -50.554636)
		(width 0.1143)
		(layer "In2.Cu")
		(net "P2E_CPU_SAS_C_TX_DP4")
	)
	(segment
		(start 74.020172 -53.01615)
		(end 74.91095 -53.01615)
		(width 0.1143)
		(layer "In2.Cu")
		(net "P2E_CPU_SAS_C_TX_DP4")
	)
	(segment
		(start 60.63615 -27.949906)
		(end 59.2582 -29.327856)
		(width 0.1143)
		(layer "In2.Cu")
		(net "P2E_CPU_SAS_C_TX_DP4")
	)
	(segment
		(start 62.4205 -44.753784)
		(end 63.951358 -46.284642)
		(width 0.1143)
		(layer "In2.Cu")
		(net "P2E_CPU_SAS_C_TX_DP4")
	)
	(segment
		(start 84.350352 -51.98872)
		(end 85.13699 -51.202082)
		(width 0.1016)
		(layer "In2.Cu")
		(net "P2E_CPU_SAS_C_TX_DP4")
	)
	(segment
		(start 81.6102 -55.0418)
		(end 81.6102 -54.728872)
		(width 0.1016)
		(layer "In2.Cu")
		(net "P2E_CPU_SAS_C_TX_DP4")
	)
	(segment
		(start 55.9816 -17.160494)
		(end 55.9816 -17.7038)
		(width 0.1143)
		(layer "In2.Cu")
		(net "P2E_CPU_SAS_C_TX_DP4")
	)
	(segment
		(start 59.2074 -22.5298)
		(end 59.2074 -23.0759)
		(width 0.1143)
		(layer "In2.Cu")
		(net "P2E_CPU_SAS_C_TX_DP4")
	)
	(segment
		(start 80.4799 -55.2958)
		(end 81.3562 -55.2958)
		(width 0.1016)
		(layer "In2.Cu")
		(net "P2E_CPU_SAS_C_TX_DP4")
	)
	(segment
		(start 81.3562 -55.2958)
		(end 81.6102 -55.0418)
		(width 0.1016)
		(layer "In2.Cu")
		(net "P2E_CPU_SAS_C_TX_DP4")
	)
	(segment
		(start 59.2582 -29.327856)
		(end 59.2582 -33.048702)
		(width 0.1143)
		(layer "In2.Cu")
		(net "P2E_CPU_SAS_C_TX_DP4")
	)
	(segment
		(start 60.616592 -34.407094)
		(end 60.616592 -37.096192)
		(width 0.1143)
		(layer "In2.Cu")
		(net "P2E_CPU_SAS_C_TX_DP4")
	)
	(segment
		(start 74.91095 -53.01615)
		(end 76.647294 -54.752494)
		(width 0.1143)
		(layer "In2.Cu")
		(net "P2E_CPU_SAS_C_TX_DP4")
	)
	(segment
		(start 67.9069 -49.4538)
		(end 68.2244 -49.7713)
		(width 0.1143)
		(layer "In2.Cu")
		(net "P2E_CPU_SAS_C_TX_DP4")
	)
	(segment
		(start 65.2526 -48.529494)
		(end 66.176906 -49.4538)
		(width 0.1143)
		(layer "In2.Cu")
		(net "P2E_CPU_SAS_C_TX_DP4")
	)
	(segment
		(start 72.102726 -51.098704)
		(end 72.345296 -51.341274)
		(width 0.1143)
		(layer "In2.Cu")
		(net "P2E_CPU_SAS_C_TX_DP4")
	)
	(segment
		(start 52.705 -14.732)
		(end 53.8099 -15.8369)
		(width 0.1143)
		(layer "In2.Cu")
		(net "P2E_CPU_SAS_C_TX_DP4")
	)
	(segment
		(start 73.131934 -52.127912)
		(end 73.433686 -52.127912)
		(width 0.1143)
		(layer "In2.Cu")
		(net "P2E_CPU_SAS_C_TX_DP4")
	)
	(segment
		(start 72.345296 -51.341274)
		(end 72.647048 -51.341274)
		(width 0.1143)
		(layer "In2.Cu")
		(net "P2E_CPU_SAS_C_TX_DP4")
	)
	(segment
		(start 73.433686 -52.127912)
		(end 73.676002 -52.370228)
		(width 0.1143)
		(layer "In2.Cu")
		(net "P2E_CPU_SAS_C_TX_DP4")
	)
	(segment
		(start 68.2244 -49.7713)
		(end 68.575682 -49.7713)
		(width 0.1143)
		(layer "In2.Cu")
		(net "P2E_CPU_SAS_C_TX_DP4")
	)
	(segment
		(start 85.746082 -51.202082)
		(end 85.987636 -50.960528)
		(width 0.1016)
		(layer "In2.Cu")
		(net "P2E_CPU_SAS_C_TX_DP4")
	)
	(segment
		(start 63.951358 -46.284642)
		(end 64.725042 -46.284642)
		(width 0.1143)
		(layer "In2.Cu")
		(net "P2E_CPU_SAS_C_TX_DP4")
	)
	(segment
		(start 83.639152 -52.559966)
		(end 83.779106 -52.559966)
		(width 0.1016)
		(layer "In2.Cu")
		(net "P2E_CPU_SAS_C_TX_DP4")
	)
	(segment
		(start 85.13699 -51.202082)
		(end 85.746082 -51.202082)
		(width 0.1016)
		(layer "In2.Cu")
		(net "P2E_CPU_SAS_C_TX_DP4")
	)
	(segment
		(start 59.2074 -23.0759)
		(end 58.5851 -23.6982)
		(width 0.1143)
		(layer "In2.Cu")
		(net "P2E_CPU_SAS_C_TX_DP4")
	)
	(segment
		(start 68.789042 -49.55794)
		(end 69.131942 -49.55794)
		(width 0.1143)
		(layer "In2.Cu")
		(net "P2E_CPU_SAS_C_TX_DP4")
	)
	(segment
		(start 58.5851 -23.6982)
		(end 58.5851 -24.36876)
		(width 0.1143)
		(layer "In2.Cu")
		(net "P2E_CPU_SAS_C_TX_DP4")
	)
	(segment
		(start 59.2582 -33.048702)
		(end 60.616592 -34.407094)
		(width 0.1143)
		(layer "In2.Cu")
		(net "P2E_CPU_SAS_C_TX_DP4")
	)
	(segment
		(start 68.575682 -49.7713)
		(end 68.789042 -49.55794)
		(width 0.1143)
		(layer "In2.Cu")
		(net "P2E_CPU_SAS_C_TX_DP4")
	)
	(segment
		(start 46.0121 -14.2621)
		(end 46.482 -14.732)
		(width 0.1143)
		(layer "In2.Cu")
		(net "P2E_CPU_SAS_C_TX_DP4")
	)
	(segment
		(start 79.657194 -54.752494)
		(end 80.137 -55.2323)
		(width 0.1143)
		(layer "In2.Cu")
		(net "P2E_CPU_SAS_C_TX_DP4")
	)
	(segment
		(start 57.5818 -17.9324)
		(end 57.9374 -18.288)
		(width 0.1143)
		(layer "In2.Cu")
		(net "P2E_CPU_SAS_C_TX_DP4")
	)
	(segment
		(start 54.658006 -15.8369)
		(end 55.9816 -17.160494)
		(width 0.1143)
		(layer "In2.Cu")
		(net "P2E_CPU_SAS_C_TX_DP4")
	)
	(segment
		(start 69.901562 -49.55794)
		(end 70.244462 -49.55794)
		(width 0.1143)
		(layer "In2.Cu")
		(net "P2E_CPU_SAS_C_TX_DP4")
	)
	(segment
		(start 56.2102 -17.9324)
		(end 57.5818 -17.9324)
		(width 0.1143)
		(layer "In2.Cu")
		(net "P2E_CPU_SAS_C_TX_DP4")
	)
	(segment
		(start 85.987636 -50.960528)
		(end 85.987636 -50.537364)
		(width 0.1016)
		(layer "In2.Cu")
		(net "P2E_CPU_SAS_C_TX_DP4")
	)
	(segment
		(start 83.994752 -52.34432)
		(end 83.994752 -52.204366)
		(width 0.1016)
		(layer "In2.Cu")
		(net "P2E_CPU_SAS_C_TX_DP4")
	)
	(segment
		(start 69.345302 -49.7713)
		(end 69.688202 -49.7713)
		(width 0.1143)
		(layer "In2.Cu")
		(net "P2E_CPU_SAS_C_TX_DP4")
	)
	(segment
		(start 53.8099 -15.8369)
		(end 54.658006 -15.8369)
		(width 0.1143)
		(layer "In2.Cu")
		(net "P2E_CPU_SAS_C_TX_DP4")
	)
	(segment
		(start 70.457822 -49.7713)
		(end 70.775322 -49.7713)
		(width 0.1143)
		(layer "In2.Cu")
		(net "P2E_CPU_SAS_C_TX_DP4")
	)
	(segment
		(start 85.987636 -50.537364)
		(end 85.869272 -50.419)
		(width 0.1016)
		(layer "In2.Cu")
		(net "P2E_CPU_SAS_C_TX_DP4")
	)
	(segment
		(start 83.779106 -52.559966)
		(end 83.994752 -52.34432)
		(width 0.1016)
		(layer "In2.Cu")
		(net "P2E_CPU_SAS_C_TX_DP4")
	)
	(segment
		(start 71.558658 -50.554636)
		(end 71.86041 -50.554636)
		(width 0.1143)
		(layer "In2.Cu")
		(net "P2E_CPU_SAS_C_TX_DP4")
	)
	(segment
		(start 70.244462 -49.55794)
		(end 70.457822 -49.7713)
		(width 0.1143)
		(layer "In2.Cu")
		(net "P2E_CPU_SAS_C_TX_DP4")
	)
	(segment
		(start 71.86041 -50.554636)
		(end 72.102726 -50.796952)
		(width 0.1143)
		(layer "In2.Cu")
		(net "P2E_CPU_SAS_C_TX_DP4")
	)
	(segment
		(start 84.210144 -51.98872)
		(end 84.350352 -51.98872)
		(width 0.1016)
		(layer "In2.Cu")
		(net "P2E_CPU_SAS_C_TX_DP4")
	)
	(segment
		(start 64.725042 -46.284642)
		(end 65.2526 -46.8122)
		(width 0.1143)
		(layer "In2.Cu")
		(net "P2E_CPU_SAS_C_TX_DP4")
	)
	(segment
		(start 76.647294 -54.752494)
		(end 79.657194 -54.752494)
		(width 0.1143)
		(layer "In2.Cu")
		(net "P2E_CPU_SAS_C_TX_DP4")
	)
	(segment
		(start 66.176906 -49.4538)
		(end 67.9069 -49.4538)
		(width 0.1143)
		(layer "In2.Cu")
		(net "P2E_CPU_SAS_C_TX_DP4")
	)
	(segment
		(start 60.616592 -37.096192)
		(end 60.29325 -37.419534)
		(width 0.1143)
		(layer "In2.Cu")
		(net "P2E_CPU_SAS_C_TX_DP4")
	)
	(segment
		(start 57.9374 -18.288)
		(end 57.9374 -19.3294)
		(width 0.1143)
		(layer "In2.Cu")
		(net "P2E_CPU_SAS_C_TX_DP4")
	)
	(segment
		(start 72.889364 -51.885342)
		(end 73.131934 -52.127912)
		(width 0.1143)
		(layer "In2.Cu")
		(net "P2E_CPU_SAS_C_TX_DP4")
	)
	(segment
		(start 58.5089 -21.8313)
		(end 59.2074 -22.5298)
		(width 0.1143)
		(layer "In2.Cu")
		(net "P2E_CPU_SAS_C_TX_DP4")
	)
	(segment
		(start 83.994752 -52.204366)
		(end 84.210144 -51.98872)
		(width 0.1016)
		(layer "In2.Cu")
		(net "P2E_CPU_SAS_C_TX_DP4")
	)
	(segment
		(start 81.6102 -54.728872)
		(end 83.423506 -52.915566)
		(width 0.1016)
		(layer "In2.Cu")
		(net "P2E_CPU_SAS_C_TX_DP4")
	)
	(segment
		(start 83.423506 -52.915566)
		(end 83.423506 -52.775358)
		(width 0.1016)
		(layer "In2.Cu")
		(net "P2E_CPU_SAS_C_TX_DP4")
	)
	(segment
		(start 57.9374 -19.3294)
		(end 57.15 -20.1168)
		(width 0.1143)
		(layer "In2.Cu")
		(net "P2E_CPU_SAS_C_TX_DP4")
	)
	(segment
		(start 58.5851 -24.36876)
		(end 60.63615 -26.41981)
		(width 0.1143)
		(layer "In2.Cu")
		(net "P2E_CPU_SAS_C_TX_DP4")
	)
	(segment
		(start 85.485224 -50.419)
		(end 85.277706 -50.626518)
		(width 0.1016)
		(layer "In2.Cu")
		(net "P2E_CPU_SAS_C_TX_DP4")
	)
	(segment
		(start 57.15 -20.1168)
		(end 57.15 -21.4122)
		(width 0.1143)
		(layer "In2.Cu")
		(net "P2E_CPU_SAS_C_TX_DP4")
	)
	(segment
		(start 34.021268 -12.024868)
		(end 34.2392 -12.2428)
		(width 0.1397)
		(layer "B.Cu")
		(net "P2E_CPU_SAS_TX_DP7")
	)
	(segment
		(start 34.349944 -8.447024)
		(end 34.021268 -8.7757)
		(width 0.1397)
		(layer "B.Cu")
		(net "P2E_CPU_SAS_TX_DP7")
	)
	(segment
		(start 34.349944 -5.814568)
		(end 34.349944 -8.447024)
		(width 0.1397)
		(layer "B.Cu")
		(net "P2E_CPU_SAS_TX_DP7")
	)
	(segment
		(start 34.021268 -8.7757)
		(end 34.021268 -12.024868)
		(width 0.1397)
		(layer "B.Cu")
		(net "P2E_CPU_SAS_TX_DP7")
	)
	(segment
		(start 33.349946 -5.814568)
		(end 33.349946 -8.447278)
		(width 0.1397)
		(layer "B.Cu")
		(net "P2E_CPU_SAS_TX_DN7")
	)
	(segment
		(start 33.349946 -8.447278)
		(end 33.678368 -8.7757)
		(width 0.1397)
		(layer "B.Cu")
		(net "P2E_CPU_SAS_TX_DN7")
	)
	(segment
		(start 33.678368 -12.041632)
		(end 33.4772 -12.2428)
		(width 0.1397)
		(layer "B.Cu")
		(net "P2E_CPU_SAS_TX_DN7")
	)
	(segment
		(start 33.678368 -8.7757)
		(end 33.678368 -12.041632)
		(width 0.1397)
		(layer "B.Cu")
		(net "P2E_CPU_SAS_TX_DN7")
	)
	(segment
		(start 38.349936 -5.814568)
		(end 38.349936 -8.447024)
		(width 0.1397)
		(layer "B.Cu")
		(net "P2E_CPU_SAS_TX_DP6")
	)
	(segment
		(start 38.02126 -8.7757)
		(end 38.02126 -12.03325)
		(width 0.1397)
		(layer "B.Cu")
		(net "P2E_CPU_SAS_TX_DP6")
	)
	(segment
		(start 38.349936 -8.447024)
		(end 38.02126 -8.7757)
		(width 0.1397)
		(layer "B.Cu")
		(net "P2E_CPU_SAS_TX_DP6")
	)
	(segment
		(start 38.02126 -12.03325)
		(end 38.23081 -12.2428)
		(width 0.1397)
		(layer "B.Cu")
		(net "P2E_CPU_SAS_TX_DP6")
	)
	(segment
		(start 37.67836 -12.03325)
		(end 37.46881 -12.2428)
		(width 0.1397)
		(layer "B.Cu")
		(net "P2E_CPU_SAS_TX_DN6")
	)
	(segment
		(start 37.349938 -5.814568)
		(end 37.349938 -8.447278)
		(width 0.1397)
		(layer "B.Cu")
		(net "P2E_CPU_SAS_TX_DN6")
	)
	(segment
		(start 37.67836 -8.7757)
		(end 37.67836 -12.03325)
		(width 0.1397)
		(layer "B.Cu")
		(net "P2E_CPU_SAS_TX_DN6")
	)
	(segment
		(start 37.349938 -8.447278)
		(end 37.67836 -8.7757)
		(width 0.1397)
		(layer "B.Cu")
		(net "P2E_CPU_SAS_TX_DN6")
	)
	(segment
		(start 41.34993 -5.814568)
		(end 41.34993 -8.447278)
		(width 0.1397)
		(layer "B.Cu")
		(net "P2E_CPU_SAS_TX_DN5")
	)
	(segment
		(start 41.678352 -12.03325)
		(end 41.468802 -12.2428)
		(width 0.1397)
		(layer "B.Cu")
		(net "P2E_CPU_SAS_TX_DN5")
	)
	(segment
		(start 41.678352 -8.7757)
		(end 41.678352 -12.03325)
		(width 0.1397)
		(layer "B.Cu")
		(net "P2E_CPU_SAS_TX_DN5")
	)
	(segment
		(start 41.34993 -8.447278)
		(end 41.678352 -8.7757)
		(width 0.1397)
		(layer "B.Cu")
		(net "P2E_CPU_SAS_TX_DN5")
	)
	(segment
		(start 46.021244 -8.7757)
		(end 46.021244 -12.036044)
		(width 0.1397)
		(layer "B.Cu")
		(net "P2E_CPU_SAS_TX_DP4")
	)
	(segment
		(start 46.34992 -5.814568)
		(end 46.34992 -8.447024)
		(width 0.1397)
		(layer "B.Cu")
		(net "P2E_CPU_SAS_TX_DP4")
	)
	(segment
		(start 46.021244 -12.036044)
		(end 46.228 -12.2428)
		(width 0.1397)
		(layer "B.Cu")
		(net "P2E_CPU_SAS_TX_DP4")
	)
	(segment
		(start 46.34992 -8.447024)
		(end 46.021244 -8.7757)
		(width 0.1397)
		(layer "B.Cu")
		(net "P2E_CPU_SAS_TX_DP4")
	)
	(segment
		(start 45.349922 -8.447278)
		(end 45.678344 -8.7757)
		(width 0.1397)
		(layer "B.Cu")
		(net "P2E_CPU_SAS_TX_DN4")
	)
	(segment
		(start 45.678344 -8.7757)
		(end 45.678344 -12.030456)
		(width 0.1397)
		(layer "B.Cu")
		(net "P2E_CPU_SAS_TX_DN4")
	)
	(segment
		(start 45.678344 -12.030456)
		(end 45.466 -12.2428)
		(width 0.1397)
		(layer "B.Cu")
		(net "P2E_CPU_SAS_TX_DN4")
	)
	(segment
		(start 45.349922 -5.814568)
		(end 45.349922 -8.447278)
		(width 0.1397)
		(layer "B.Cu")
		(net "P2E_CPU_SAS_TX_DN4")
	)
	(segment
		(start 42.021252 -8.7757)
		(end 42.021252 -12.03325)
		(width 0.1397)
		(layer "B.Cu")
		(net "P2E_CPU_SAS_TX_DP5")
	)
	(segment
		(start 42.021252 -12.03325)
		(end 42.230802 -12.2428)
		(width 0.1397)
		(layer "B.Cu")
		(net "P2E_CPU_SAS_TX_DP5")
	)
	(segment
		(start 42.349928 -8.447024)
		(end 42.021252 -8.7757)
		(width 0.1397)
		(layer "B.Cu")
		(net "P2E_CPU_SAS_TX_DP5")
	)
	(segment
		(start 42.349928 -5.814568)
		(end 42.349928 -8.447024)
		(width 0.1397)
		(layer "B.Cu")
		(net "P2E_CPU_SAS_TX_DP5")
	)
	(segment
		(start 82.488024 -54.18074)
		(end 82.107024 -54.18074)
		(width 0.127)
		(layer "F.Cu")
		(net "P2E_CPU_SAS_C_TX_DP3")
	)
	(segment
		(start 84.504784 -52.7431)
		(end 82.968084 -54.2798)
		(width 0.127)
		(layer "F.Cu")
		(net "P2E_CPU_SAS_C_TX_DP3")
	)
	(segment
		(start 82.007964 -54.2798)
		(end 80.7212 -54.2798)
		(width 0.127)
		(layer "F.Cu")
		(net "P2E_CPU_SAS_C_TX_DP3")
	)
	(segment
		(start 84.504784 -51.8414)
		(end 84.504784 -52.7431)
		(width 0.127)
		(layer "F.Cu")
		(net "P2E_CPU_SAS_C_TX_DP3")
	)
	(segment
		(start 80.7212 -54.2798)
		(end 80.5688 -54.1274)
		(width 0.127)
		(layer "F.Cu")
		(net "P2E_CPU_SAS_C_TX_DP3")
	)
	(segment
		(start 82.968084 -54.2798)
		(end 82.587084 -54.2798)
		(width 0.127)
		(layer "F.Cu")
		(net "P2E_CPU_SAS_C_TX_DP3")
	)
	(segment
		(start 84.945728 -51.099974)
		(end 84.504784 -51.8414)
		(width 0.127)
		(layer "F.Cu")
		(net "P2E_CPU_SAS_C_TX_DP3")
	)
	(segment
		(start 82.587084 -54.2798)
		(end 82.488024 -54.18074)
		(width 0.127)
		(layer "F.Cu")
		(net "P2E_CPU_SAS_C_TX_DP3")
	)
	(segment
		(start 82.107024 -54.18074)
		(end 82.007964 -54.2798)
		(width 0.127)
		(layer "F.Cu")
		(net "P2E_CPU_SAS_C_TX_DP3")
	)
	(via
		(at 68.834 -14.605)
		(size 0.508)
		(drill 0.254)
		(layers "F.Cu" "B.Cu")
		(net "P2E_CPU_SAS_C_TX_DP3")
	)
	(via
		(at 80.5688 -54.1274)
		(size 0.4318)
		(drill 0.2032)
		(layers "F.Cu" "B.Cu")
		(net "P2E_CPU_SAS_C_TX_DP3")
	)
	(segment
		(start 68.834 -14.0462)
		(end 68.834 -14.605)
		(width 0.1397)
		(layer "B.Cu")
		(net "P2E_CPU_SAS_C_TX_DP3")
	)
	(segment
		(start 61.595 -33.58261)
		(end 61.24575 -33.23336)
		(width 0.1143)
		(layer "In2.Cu")
		(net "P2E_CPU_SAS_C_TX_DP3")
	)
	(segment
		(start 66.97345 -19.58975)
		(end 67.567556 -19.58975)
		(width 0.1143)
		(layer "In2.Cu")
		(net "P2E_CPU_SAS_C_TX_DP3")
	)
	(segment
		(start 68.6562 -18.501106)
		(end 68.6562 -14.7828)
		(width 0.1143)
		(layer "In2.Cu")
		(net "P2E_CPU_SAS_C_TX_DP3")
	)
	(segment
		(start 63.8175 -44.803568)
		(end 63.8175 -43.11015)
		(width 0.1143)
		(layer "In2.Cu")
		(net "P2E_CPU_SAS_C_TX_DP3")
	)
	(segment
		(start 61.595 -37.465)
		(end 61.595 -33.58261)
		(width 0.1143)
		(layer "In2.Cu")
		(net "P2E_CPU_SAS_C_TX_DP3")
	)
	(segment
		(start 79.03083 -54.00675)
		(end 78.81747 -53.79339)
		(width 0.1143)
		(layer "In2.Cu")
		(net "P2E_CPU_SAS_C_TX_DP3")
	)
	(segment
		(start 65.059306 -45.2374)
		(end 64.251332 -45.2374)
		(width 0.1143)
		(layer "In2.Cu")
		(net "P2E_CPU_SAS_C_TX_DP3")
	)
	(segment
		(start 80.48625 -54.20995)
		(end 80.1624 -54.20995)
		(width 0.1143)
		(layer "In2.Cu")
		(net "P2E_CPU_SAS_C_TX_DP3")
	)
	(segment
		(start 64.251332 -45.2374)
		(end 63.8175 -44.803568)
		(width 0.1143)
		(layer "In2.Cu")
		(net "P2E_CPU_SAS_C_TX_DP3")
	)
	(segment
		(start 63.4365 -23.1267)
		(end 66.97345 -19.58975)
		(width 0.1143)
		(layer "In2.Cu")
		(net "P2E_CPU_SAS_C_TX_DP3")
	)
	(segment
		(start 78.81747 -53.79339)
		(end 78.47457 -53.79339)
		(width 0.1143)
		(layer "In2.Cu")
		(net "P2E_CPU_SAS_C_TX_DP3")
	)
	(segment
		(start 68.6562 -14.7828)
		(end 68.834 -14.605)
		(width 0.1143)
		(layer "In2.Cu")
		(net "P2E_CPU_SAS_C_TX_DP3")
	)
	(segment
		(start 67.567556 -19.58975)
		(end 68.6562 -18.501106)
		(width 0.1143)
		(layer "In2.Cu")
		(net "P2E_CPU_SAS_C_TX_DP3")
	)
	(segment
		(start 67.446906 -47.625)
		(end 65.059306 -45.2374)
		(width 0.1143)
		(layer "In2.Cu")
		(net "P2E_CPU_SAS_C_TX_DP3")
	)
	(segment
		(start 71.27875 -48.5902)
		(end 68.6054 -48.5902)
		(width 0.1143)
		(layer "In2.Cu")
		(net "P2E_CPU_SAS_C_TX_DP3")
	)
	(segment
		(start 63.8175 -43.11015)
		(end 61.24575 -40.5384)
		(width 0.1143)
		(layer "In2.Cu")
		(net "P2E_CPU_SAS_C_TX_DP3")
	)
	(segment
		(start 68.6054 -48.5902)
		(end 67.6402 -47.625)
		(width 0.1143)
		(layer "In2.Cu")
		(net "P2E_CPU_SAS_C_TX_DP3")
	)
	(segment
		(start 67.6402 -47.625)
		(end 67.446906 -47.625)
		(width 0.1143)
		(layer "In2.Cu")
		(net "P2E_CPU_SAS_C_TX_DP3")
	)
	(segment
		(start 79.9592 -54.00675)
		(end 79.03083 -54.00675)
		(width 0.1143)
		(layer "In2.Cu")
		(net "P2E_CPU_SAS_C_TX_DP3")
	)
	(segment
		(start 63.4365 -28.380944)
		(end 63.4365 -23.1267)
		(width 0.1143)
		(layer "In2.Cu")
		(net "P2E_CPU_SAS_C_TX_DP3")
	)
	(segment
		(start 78.26121 -54.00675)
		(end 76.94295 -54.00675)
		(width 0.1143)
		(layer "In2.Cu")
		(net "P2E_CPU_SAS_C_TX_DP3")
	)
	(segment
		(start 76.94295 -54.00675)
		(end 74.99985 -52.06365)
		(width 0.1143)
		(layer "In2.Cu")
		(net "P2E_CPU_SAS_C_TX_DP3")
	)
	(segment
		(start 61.24575 -40.5384)
		(end 61.24575 -37.81425)
		(width 0.1143)
		(layer "In2.Cu")
		(net "P2E_CPU_SAS_C_TX_DP3")
	)
	(segment
		(start 61.24575 -30.571694)
		(end 63.4365 -28.380944)
		(width 0.1143)
		(layer "In2.Cu")
		(net "P2E_CPU_SAS_C_TX_DP3")
	)
	(segment
		(start 78.47457 -53.79339)
		(end 78.26121 -54.00675)
		(width 0.1143)
		(layer "In2.Cu")
		(net "P2E_CPU_SAS_C_TX_DP3")
	)
	(segment
		(start 74.99985 -52.06365)
		(end 74.7522 -52.06365)
		(width 0.1143)
		(layer "In2.Cu")
		(net "P2E_CPU_SAS_C_TX_DP3")
	)
	(segment
		(start 80.5688 -54.1274)
		(end 80.48625 -54.20995)
		(width 0.1143)
		(layer "In2.Cu")
		(net "P2E_CPU_SAS_C_TX_DP3")
	)
	(segment
		(start 80.1624 -54.20995)
		(end 79.9592 -54.00675)
		(width 0.1143)
		(layer "In2.Cu")
		(net "P2E_CPU_SAS_C_TX_DP3")
	)
	(segment
		(start 74.7522 -52.06365)
		(end 71.27875 -48.5902)
		(width 0.1143)
		(layer "In2.Cu")
		(net "P2E_CPU_SAS_C_TX_DP3")
	)
	(segment
		(start 61.24575 -33.23336)
		(end 61.24575 -30.571694)
		(width 0.1143)
		(layer "In2.Cu")
		(net "P2E_CPU_SAS_C_TX_DP3")
	)
	(segment
		(start 61.24575 -37.81425)
		(end 61.595 -37.465)
		(width 0.1143)
		(layer "In2.Cu")
		(net "P2E_CPU_SAS_C_TX_DP3")
	)
	(segment
		(start 80.7466 -54.5084)
		(end 80.5688 -54.6862)
		(width 0.127)
		(layer "F.Cu")
		(net "P2E_CPU_SAS_C_TX_DN3")
	)
	(segment
		(start 84.733384 -52.837842)
		(end 83.062826 -54.5084)
		(width 0.127)
		(layer "F.Cu")
		(net "P2E_CPU_SAS_C_TX_DN3")
	)
	(segment
		(start 84.733384 -52.061618)
		(end 84.733384 -52.837842)
		(width 0.127)
		(layer "F.Cu")
		(net "P2E_CPU_SAS_C_TX_DN3")
	)
	(segment
		(start 84.953348 -51.841654)
		(end 84.733384 -52.061618)
		(width 0.127)
		(layer "F.Cu")
		(net "P2E_CPU_SAS_C_TX_DN3")
	)
	(segment
		(start 83.062826 -54.5084)
		(end 80.7466 -54.5084)
		(width 0.127)
		(layer "F.Cu")
		(net "P2E_CPU_SAS_C_TX_DN3")
	)
	(via
		(at 68.072 -14.605)
		(size 0.508)
		(drill 0.254)
		(layers "F.Cu" "B.Cu")
		(net "P2E_CPU_SAS_C_TX_DN3")
	)
	(via
		(at 80.5688 -54.6862)
		(size 0.4318)
		(drill 0.2032)
		(layers "F.Cu" "B.Cu")
		(net "P2E_CPU_SAS_C_TX_DN3")
	)
	(segment
		(start 68.072 -14.0462)
		(end 68.072 -14.605)
		(width 0.1397)
		(layer "B.Cu")
		(net "P2E_CPU_SAS_C_TX_DN3")
	)
	(segment
		(start 63.4873 -43.247056)
		(end 60.91555 -40.675306)
		(width 0.1143)
		(layer "In2.Cu")
		(net "P2E_CPU_SAS_C_TX_DN3")
	)
	(segment
		(start 66.836544 -19.25955)
		(end 67.43065 -19.25955)
		(width 0.1143)
		(layer "In2.Cu")
		(net "P2E_CPU_SAS_C_TX_DN3")
	)
	(segment
		(start 68.326 -14.859)
		(end 68.072 -14.605)
		(width 0.1143)
		(layer "In2.Cu")
		(net "P2E_CPU_SAS_C_TX_DN3")
	)
	(segment
		(start 67.503294 -47.9552)
		(end 67.31 -47.9552)
		(width 0.1143)
		(layer "In2.Cu")
		(net "P2E_CPU_SAS_C_TX_DN3")
	)
	(segment
		(start 60.91555 -33.370266)
		(end 60.91555 -30.434788)
		(width 0.1143)
		(layer "In2.Cu")
		(net "P2E_CPU_SAS_C_TX_DN3")
	)
	(segment
		(start 80.42275 -54.54015)
		(end 80.025494 -54.54015)
		(width 0.1143)
		(layer "In2.Cu")
		(net "P2E_CPU_SAS_C_TX_DN3")
	)
	(segment
		(start 64.114426 -45.5676)
		(end 63.4873 -44.940474)
		(width 0.1143)
		(layer "In2.Cu")
		(net "P2E_CPU_SAS_C_TX_DN3")
	)
	(segment
		(start 68.468494 -48.9204)
		(end 67.503294 -47.9552)
		(width 0.1143)
		(layer "In2.Cu")
		(net "P2E_CPU_SAS_C_TX_DN3")
	)
	(segment
		(start 67.31 -47.9552)
		(end 64.9224 -45.5676)
		(width 0.1143)
		(layer "In2.Cu")
		(net "P2E_CPU_SAS_C_TX_DN3")
	)
	(segment
		(start 80.025494 -54.54015)
		(end 79.822294 -54.33695)
		(width 0.1143)
		(layer "In2.Cu")
		(net "P2E_CPU_SAS_C_TX_DN3")
	)
	(segment
		(start 60.91555 -40.675306)
		(end 60.91555 -37.677344)
		(width 0.1143)
		(layer "In2.Cu")
		(net "P2E_CPU_SAS_C_TX_DN3")
	)
	(segment
		(start 68.326 -18.3642)
		(end 68.326 -14.859)
		(width 0.1143)
		(layer "In2.Cu")
		(net "P2E_CPU_SAS_C_TX_DN3")
	)
	(segment
		(start 74.862944 -52.39385)
		(end 74.615294 -52.39385)
		(width 0.1143)
		(layer "In2.Cu")
		(net "P2E_CPU_SAS_C_TX_DN3")
	)
	(segment
		(start 74.615294 -52.39385)
		(end 71.141844 -48.9204)
		(width 0.1143)
		(layer "In2.Cu")
		(net "P2E_CPU_SAS_C_TX_DN3")
	)
	(segment
		(start 71.141844 -48.9204)
		(end 68.468494 -48.9204)
		(width 0.1143)
		(layer "In2.Cu")
		(net "P2E_CPU_SAS_C_TX_DN3")
	)
	(segment
		(start 64.9224 -45.5676)
		(end 64.114426 -45.5676)
		(width 0.1143)
		(layer "In2.Cu")
		(net "P2E_CPU_SAS_C_TX_DN3")
	)
	(segment
		(start 80.5688 -54.6862)
		(end 80.42275 -54.54015)
		(width 0.1143)
		(layer "In2.Cu")
		(net "P2E_CPU_SAS_C_TX_DN3")
	)
	(segment
		(start 63.1063 -28.244038)
		(end 63.1063 -22.989794)
		(width 0.1143)
		(layer "In2.Cu")
		(net "P2E_CPU_SAS_C_TX_DN3")
	)
	(segment
		(start 61.2648 -37.328094)
		(end 61.2648 -33.719516)
		(width 0.1143)
		(layer "In2.Cu")
		(net "P2E_CPU_SAS_C_TX_DN3")
	)
	(segment
		(start 60.91555 -30.434788)
		(end 63.1063 -28.244038)
		(width 0.1143)
		(layer "In2.Cu")
		(net "P2E_CPU_SAS_C_TX_DN3")
	)
	(segment
		(start 63.4873 -44.940474)
		(end 63.4873 -43.247056)
		(width 0.1143)
		(layer "In2.Cu")
		(net "P2E_CPU_SAS_C_TX_DN3")
	)
	(segment
		(start 76.806044 -54.33695)
		(end 74.862944 -52.39385)
		(width 0.1143)
		(layer "In2.Cu")
		(net "P2E_CPU_SAS_C_TX_DN3")
	)
	(segment
		(start 79.822294 -54.33695)
		(end 76.806044 -54.33695)
		(width 0.1143)
		(layer "In2.Cu")
		(net "P2E_CPU_SAS_C_TX_DN3")
	)
	(segment
		(start 60.91555 -37.677344)
		(end 61.2648 -37.328094)
		(width 0.1143)
		(layer "In2.Cu")
		(net "P2E_CPU_SAS_C_TX_DN3")
	)
	(segment
		(start 61.2648 -33.719516)
		(end 60.91555 -33.370266)
		(width 0.1143)
		(layer "In2.Cu")
		(net "P2E_CPU_SAS_C_TX_DN3")
	)
	(segment
		(start 63.1063 -22.989794)
		(end 66.836544 -19.25955)
		(width 0.1143)
		(layer "In2.Cu")
		(net "P2E_CPU_SAS_C_TX_DN3")
	)
	(segment
		(start 67.43065 -19.25955)
		(end 68.326 -18.3642)
		(width 0.1143)
		(layer "In2.Cu")
		(net "P2E_CPU_SAS_C_TX_DN3")
	)
	(segment
		(start 83.708748 -51.970686)
		(end 84.003134 -52.265072)
		(width 0.127)
		(layer "F.Cu")
		(net "P2E_CPU_SAS_C_TX_DP2")
	)
	(segment
		(start 81.8896 -53.213)
		(end 81.6864 -53.0098)
		(width 0.127)
		(layer "F.Cu")
		(net "P2E_CPU_SAS_C_TX_DP2")
	)
	(segment
		(start 83.708748 -51.7398)
		(end 83.708748 -51.970686)
		(width 0.127)
		(layer "F.Cu")
		(net "P2E_CPU_SAS_C_TX_DP2")
	)
	(segment
		(start 84.056728 -51.099974)
		(end 83.708748 -51.7398)
		(width 0.127)
		(layer "F.Cu")
		(net "P2E_CPU_SAS_C_TX_DP2")
	)
	(segment
		(start 83.3882 -53.213)
		(end 81.8896 -53.213)
		(width 0.127)
		(layer "F.Cu")
		(net "P2E_CPU_SAS_C_TX_DP2")
	)
	(segment
		(start 84.003134 -52.598066)
		(end 83.3882 -53.213)
		(width 0.127)
		(layer "F.Cu")
		(net "P2E_CPU_SAS_C_TX_DP2")
	)
	(segment
		(start 84.003134 -52.265072)
		(end 84.003134 -52.598066)
		(width 0.127)
		(layer "F.Cu")
		(net "P2E_CPU_SAS_C_TX_DP2")
	)
	(via
		(at 81.6864 -53.0098)
		(size 0.4318)
		(drill 0.2032)
		(layers "F.Cu" "B.Cu")
		(net "P2E_CPU_SAS_C_TX_DP2")
	)
	(via
		(at 73.7108 -14.7066)
		(size 0.508)
		(drill 0.254)
		(layers "F.Cu" "B.Cu")
		(net "P2E_CPU_SAS_C_TX_DP2")
	)
	(segment
		(start 73.66 -14.6558)
		(end 73.7108 -14.7066)
		(width 0.1397)
		(layer "B.Cu")
		(net "P2E_CPU_SAS_C_TX_DP2")
	)
	(segment
		(start 73.66 -14.0462)
		(end 73.66 -14.6558)
		(width 0.1397)
		(layer "B.Cu")
		(net "P2E_CPU_SAS_C_TX_DP2")
	)
	(segment
		(start 73.8632 -47.843694)
		(end 73.295256 -47.27575)
		(width 0.1143)
		(layer "In2.Cu")
		(net "P2E_CPU_SAS_C_TX_DP2")
	)
	(segment
		(start 73.4314 -14.986)
		(end 73.7108 -14.7066)
		(width 0.1143)
		(layer "In2.Cu")
		(net "P2E_CPU_SAS_C_TX_DP2")
	)
	(segment
		(start 73.295256 -47.27575)
		(end 70.09765 -47.27575)
		(width 0.1143)
		(layer "In2.Cu")
		(net "P2E_CPU_SAS_C_TX_DP2")
	)
	(segment
		(start 81.6864 -53.0098)
		(end 81.54035 -53.15585)
		(width 0.1143)
		(layer "In2.Cu")
		(net "P2E_CPU_SAS_C_TX_DP2")
	)
	(segment
		(start 64.389 -29.010102)
		(end 64.389 -24.814022)
		(width 0.1143)
		(layer "In2.Cu")
		(net "P2E_CPU_SAS_C_TX_DP2")
	)
	(segment
		(start 62.97295 -40.767)
		(end 62.97295 -30.426152)
		(width 0.1143)
		(layer "In2.Cu")
		(net "P2E_CPU_SAS_C_TX_DP2")
	)
	(segment
		(start 64.77 -43.525694)
		(end 64.77 -42.56405)
		(width 0.1143)
		(layer "In2.Cu")
		(net "P2E_CPU_SAS_C_TX_DP2")
	)
	(segment
		(start 77.23505 -53.15585)
		(end 73.8632 -49.784)
		(width 0.1143)
		(layer "In2.Cu")
		(net "P2E_CPU_SAS_C_TX_DP2")
	)
	(segment
		(start 69.4944 -46.6725)
		(end 67.916806 -46.6725)
		(width 0.1143)
		(layer "In2.Cu")
		(net "P2E_CPU_SAS_C_TX_DP2")
	)
	(segment
		(start 73.8632 -49.784)
		(end 73.8632 -47.843694)
		(width 0.1143)
		(layer "In2.Cu")
		(net "P2E_CPU_SAS_C_TX_DP2")
	)
	(segment
		(start 67.916806 -46.6725)
		(end 64.77 -43.525694)
		(width 0.1143)
		(layer "In2.Cu")
		(net "P2E_CPU_SAS_C_TX_DP2")
	)
	(segment
		(start 64.389 -24.814022)
		(end 73.4314 -15.771622)
		(width 0.1143)
		(layer "In2.Cu")
		(net "P2E_CPU_SAS_C_TX_DP2")
	)
	(segment
		(start 70.09765 -47.27575)
		(end 69.4944 -46.6725)
		(width 0.1143)
		(layer "In2.Cu")
		(net "P2E_CPU_SAS_C_TX_DP2")
	)
	(segment
		(start 73.4314 -15.771622)
		(end 73.4314 -14.986)
		(width 0.1143)
		(layer "In2.Cu")
		(net "P2E_CPU_SAS_C_TX_DP2")
	)
	(segment
		(start 81.54035 -53.15585)
		(end 77.23505 -53.15585)
		(width 0.1143)
		(layer "In2.Cu")
		(net "P2E_CPU_SAS_C_TX_DP2")
	)
	(segment
		(start 62.97295 -30.426152)
		(end 64.389 -29.010102)
		(width 0.1143)
		(layer "In2.Cu")
		(net "P2E_CPU_SAS_C_TX_DP2")
	)
	(segment
		(start 64.77 -42.56405)
		(end 62.97295 -40.767)
		(width 0.1143)
		(layer "In2.Cu")
		(net "P2E_CPU_SAS_C_TX_DP2")
	)
	(segment
		(start 84.231734 -52.692808)
		(end 83.482942 -53.4416)
		(width 0.127)
		(layer "F.Cu")
		(net "P2E_CPU_SAS_C_TX_DN2")
	)
	(segment
		(start 84.026248 -51.839114)
		(end 84.026248 -51.964844)
		(width 0.127)
		(layer "F.Cu")
		(net "P2E_CPU_SAS_C_TX_DN2")
	)
	(segment
		(start 84.026248 -51.964844)
		(end 84.231734 -52.17033)
		(width 0.127)
		(layer "F.Cu")
		(net "P2E_CPU_SAS_C_TX_DN2")
	)
	(segment
		(start 83.482942 -53.4416)
		(end 81.8388 -53.4416)
		(width 0.127)
		(layer "F.Cu")
		(net "P2E_CPU_SAS_C_TX_DN2")
	)
	(segment
		(start 84.231734 -52.17033)
		(end 84.231734 -52.692808)
		(width 0.127)
		(layer "F.Cu")
		(net "P2E_CPU_SAS_C_TX_DN2")
	)
	(segment
		(start 81.8388 -53.4416)
		(end 81.6864 -53.594)
		(width 0.127)
		(layer "F.Cu")
		(net "P2E_CPU_SAS_C_TX_DN2")
	)
	(via
		(at 72.8472 -14.7066)
		(size 0.508)
		(drill 0.254)
		(layers "F.Cu" "B.Cu")
		(net "P2E_CPU_SAS_C_TX_DN2")
	)
	(via
		(at 81.6864 -53.594)
		(size 0.4318)
		(drill 0.2032)
		(layers "F.Cu" "B.Cu")
		(net "P2E_CPU_SAS_C_TX_DN2")
	)
	(segment
		(start 72.898 -14.6558)
		(end 72.8472 -14.7066)
		(width 0.1397)
		(layer "B.Cu")
		(net "P2E_CPU_SAS_C_TX_DN2")
	)
	(segment
		(start 72.898 -14.0462)
		(end 72.898 -14.6558)
		(width 0.1397)
		(layer "B.Cu")
		(net "P2E_CPU_SAS_C_TX_DN2")
	)
	(segment
		(start 64.0588 -24.677116)
		(end 73.1012 -15.634716)
		(width 0.1143)
		(layer "In2.Cu")
		(net "P2E_CPU_SAS_C_TX_DN2")
	)
	(segment
		(start 62.64275 -40.903906)
		(end 62.64275 -30.289246)
		(width 0.1143)
		(layer "In2.Cu")
		(net "P2E_CPU_SAS_C_TX_DN2")
	)
	(segment
		(start 64.0588 -28.873196)
		(end 64.0588 -24.677116)
		(width 0.1143)
		(layer "In2.Cu")
		(net "P2E_CPU_SAS_C_TX_DN2")
	)
	(segment
		(start 69.357494 -47.0027)
		(end 67.7799 -47.0027)
		(width 0.1143)
		(layer "In2.Cu")
		(net "P2E_CPU_SAS_C_TX_DN2")
	)
	(segment
		(start 73.533 -47.9806)
		(end 73.15835 -47.60595)
		(width 0.1143)
		(layer "In2.Cu")
		(net "P2E_CPU_SAS_C_TX_DN2")
	)
	(segment
		(start 81.6864 -53.594)
		(end 81.57845 -53.48605)
		(width 0.1143)
		(layer "In2.Cu")
		(net "P2E_CPU_SAS_C_TX_DN2")
	)
	(segment
		(start 73.1012 -15.634716)
		(end 73.1012 -14.9606)
		(width 0.1143)
		(layer "In2.Cu")
		(net "P2E_CPU_SAS_C_TX_DN2")
	)
	(segment
		(start 73.15835 -47.60595)
		(end 69.960744 -47.60595)
		(width 0.1143)
		(layer "In2.Cu")
		(net "P2E_CPU_SAS_C_TX_DN2")
	)
	(segment
		(start 81.57845 -53.48605)
		(end 77.098144 -53.48605)
		(width 0.1143)
		(layer "In2.Cu")
		(net "P2E_CPU_SAS_C_TX_DN2")
	)
	(segment
		(start 73.533 -49.920906)
		(end 73.533 -47.9806)
		(width 0.1143)
		(layer "In2.Cu")
		(net "P2E_CPU_SAS_C_TX_DN2")
	)
	(segment
		(start 69.960744 -47.60595)
		(end 69.357494 -47.0027)
		(width 0.1143)
		(layer "In2.Cu")
		(net "P2E_CPU_SAS_C_TX_DN2")
	)
	(segment
		(start 64.4398 -43.6626)
		(end 64.4398 -42.700956)
		(width 0.1143)
		(layer "In2.Cu")
		(net "P2E_CPU_SAS_C_TX_DN2")
	)
	(segment
		(start 77.098144 -53.48605)
		(end 73.533 -49.920906)
		(width 0.1143)
		(layer "In2.Cu")
		(net "P2E_CPU_SAS_C_TX_DN2")
	)
	(segment
		(start 64.4398 -42.700956)
		(end 62.64275 -40.903906)
		(width 0.1143)
		(layer "In2.Cu")
		(net "P2E_CPU_SAS_C_TX_DN2")
	)
	(segment
		(start 62.64275 -30.289246)
		(end 64.0588 -28.873196)
		(width 0.1143)
		(layer "In2.Cu")
		(net "P2E_CPU_SAS_C_TX_DN2")
	)
	(segment
		(start 67.7799 -47.0027)
		(end 64.4398 -43.6626)
		(width 0.1143)
		(layer "In2.Cu")
		(net "P2E_CPU_SAS_C_TX_DN2")
	)
	(segment
		(start 73.1012 -14.9606)
		(end 72.8472 -14.7066)
		(width 0.1143)
		(layer "In2.Cu")
		(net "P2E_CPU_SAS_C_TX_DN2")
	)
	(segment
		(start 82.916268 -51.18735)
		(end 82.713068 -51.39055)
		(width 0.1397)
		(layer "F.Cu")
		(net "P2E_CPU_SAS_C_TX_DP1")
	)
	(segment
		(start 82.916268 -50.952654)
		(end 82.916268 -51.18735)
		(width 0.1397)
		(layer "F.Cu")
		(net "P2E_CPU_SAS_C_TX_DP1")
	)
	(via
		(at 82.713068 -51.39055)
		(size 0.4318)
		(drill 0.2032)
		(layers "F.Cu" "B.Cu")
		(net "P2E_CPU_SAS_C_TX_DP1")
	)
	(via
		(at 78.2828 -14.5796)
		(size 0.508)
		(drill 0.254)
		(layers "F.Cu" "B.Cu")
		(net "P2E_CPU_SAS_C_TX_DP1")
	)
	(segment
		(start 78.232 -14.5288)
		(end 78.2828 -14.5796)
		(width 0.1397)
		(layer "B.Cu")
		(net "P2E_CPU_SAS_C_TX_DP1")
	)
	(segment
		(start 78.232 -13.9192)
		(end 78.232 -14.5288)
		(width 0.1397)
		(layer "B.Cu")
		(net "P2E_CPU_SAS_C_TX_DP1")
	)
	(segment
		(start 74.8157 -49.3395)
		(end 74.8157 -46.638464)
		(width 0.1143)
		(layer "In2.Cu")
		(net "P2E_CPU_SAS_C_TX_DP1")
	)
	(segment
		(start 65.872106 -29.9974)
		(end 66.51879 -29.9974)
		(width 0.1143)
		(layer "In2.Cu")
		(net "P2E_CPU_SAS_C_TX_DP1")
	)
	(segment
		(start 73.786492 -45.307504)
		(end 73.544176 -45.065188)
		(width 0.1143)
		(layer "In2.Cu")
		(net "P2E_CPU_SAS_C_TX_DP1")
	)
	(segment
		(start 79.890874 -51.45024)
		(end 79.677514 -51.6636)
		(width 0.1143)
		(layer "In2.Cu")
		(net "P2E_CPU_SAS_C_TX_DP1")
	)
	(segment
		(start 81.003394 -51.45024)
		(end 80.790034 -51.6636)
		(width 0.1143)
		(layer "In2.Cu")
		(net "P2E_CPU_SAS_C_TX_DP1")
	)
	(segment
		(start 70.997572 -23.42515)
		(end 71.47433 -23.42515)
		(width 0.1143)
		(layer "In2.Cu")
		(net "P2E_CPU_SAS_C_TX_DP1")
	)
	(segment
		(start 66.51879 -29.9974)
		(end 67.73926 -28.77693)
		(width 0.1143)
		(layer "In2.Cu")
		(net "P2E_CPU_SAS_C_TX_DP1")
	)
	(segment
		(start 68.599304 -42.869104)
		(end 68.116958 -42.869104)
		(width 0.1143)
		(layer "In2.Cu")
		(net "P2E_CPU_SAS_C_TX_DP1")
	)
	(segment
		(start 74.330814 -45.851826)
		(end 74.029062 -45.851826)
		(width 0.1143)
		(layer "In2.Cu")
		(net "P2E_CPU_SAS_C_TX_DP1")
	)
	(segment
		(start 77.0382 -51.562)
		(end 74.8157 -49.3395)
		(width 0.1143)
		(layer "In2.Cu")
		(net "P2E_CPU_SAS_C_TX_DP1")
	)
	(segment
		(start 68.834 -25.588722)
		(end 70.997572 -23.42515)
		(width 0.1143)
		(layer "In2.Cu")
		(net "P2E_CPU_SAS_C_TX_DP1")
	)
	(segment
		(start 81.346294 -51.45024)
		(end 81.003394 -51.45024)
		(width 0.1143)
		(layer "In2.Cu")
		(net "P2E_CPU_SAS_C_TX_DP1")
	)
	(segment
		(start 65.3669 -30.502606)
		(end 65.872106 -29.9974)
		(width 0.1143)
		(layer "In2.Cu")
		(net "P2E_CPU_SAS_C_TX_DP1")
	)
	(segment
		(start 79.677514 -51.6636)
		(end 79.334614 -51.6636)
		(width 0.1143)
		(layer "In2.Cu")
		(net "P2E_CPU_SAS_C_TX_DP1")
	)
	(segment
		(start 80.790034 -51.6636)
		(end 80.447134 -51.6636)
		(width 0.1143)
		(layer "In2.Cu")
		(net "P2E_CPU_SAS_C_TX_DP1")
	)
	(segment
		(start 72.756776 -44.57954)
		(end 70.30974 -44.57954)
		(width 0.1143)
		(layer "In2.Cu")
		(net "P2E_CPU_SAS_C_TX_DP1")
	)
	(segment
		(start 68.834 -25.924002)
		(end 68.834 -25.588722)
		(width 0.1143)
		(layer "In2.Cu")
		(net "P2E_CPU_SAS_C_TX_DP1")
	)
	(segment
		(start 72.451214 -21.487892)
		(end 72.882506 -21.0566)
		(width 0.1143)
		(layer "In2.Cu")
		(net "P2E_CPU_SAS_C_TX_DP1")
	)
	(segment
		(start 73.786492 -45.609256)
		(end 73.786492 -45.307504)
		(width 0.1143)
		(layer "In2.Cu")
		(net "P2E_CPU_SAS_C_TX_DP1")
	)
	(segment
		(start 82.713068 -51.39055)
		(end 82.713068 -51.525932)
		(width 0.1143)
		(layer "In2.Cu")
		(net "P2E_CPU_SAS_C_TX_DP1")
	)
	(segment
		(start 71.47433 -23.42515)
		(end 72.451214 -22.448266)
		(width 0.1143)
		(layer "In2.Cu")
		(net "P2E_CPU_SAS_C_TX_DP1")
	)
	(segment
		(start 70.30974 -44.57954)
		(end 68.599304 -42.869104)
		(width 0.1143)
		(layer "In2.Cu")
		(net "P2E_CPU_SAS_C_TX_DP1")
	)
	(segment
		(start 82.5754 -51.6636)
		(end 81.559654 -51.6636)
		(width 0.1143)
		(layer "In2.Cu")
		(net "P2E_CPU_SAS_C_TX_DP1")
	)
	(segment
		(start 81.559654 -51.6636)
		(end 81.346294 -51.45024)
		(width 0.1143)
		(layer "In2.Cu")
		(net "P2E_CPU_SAS_C_TX_DP1")
	)
	(segment
		(start 78.0288 -14.8336)
		(end 78.2828 -14.5796)
		(width 0.1143)
		(layer "In2.Cu")
		(net "P2E_CPU_SAS_C_TX_DP1")
	)
	(segment
		(start 74.8157 -46.638464)
		(end 74.57313 -46.395894)
		(width 0.1143)
		(layer "In2.Cu")
		(net "P2E_CPU_SAS_C_TX_DP1")
	)
	(segment
		(start 82.713068 -51.525932)
		(end 82.5754 -51.6636)
		(width 0.1143)
		(layer "In2.Cu")
		(net "P2E_CPU_SAS_C_TX_DP1")
	)
	(segment
		(start 80.447134 -51.6636)
		(end 80.233774 -51.45024)
		(width 0.1143)
		(layer "In2.Cu")
		(net "P2E_CPU_SAS_C_TX_DP1")
	)
	(segment
		(start 76.273914 -18.625566)
		(end 76.273914 -17.665192)
		(width 0.1143)
		(layer "In2.Cu")
		(net "P2E_CPU_SAS_C_TX_DP1")
	)
	(segment
		(start 79.334614 -51.6636)
		(end 79.121254 -51.45024)
		(width 0.1143)
		(layer "In2.Cu")
		(net "P2E_CPU_SAS_C_TX_DP1")
	)
	(segment
		(start 67.73926 -28.77693)
		(end 67.73926 -27.018742)
		(width 0.1143)
		(layer "In2.Cu")
		(net "P2E_CPU_SAS_C_TX_DP1")
	)
	(segment
		(start 74.029062 -45.851826)
		(end 73.786492 -45.609256)
		(width 0.1143)
		(layer "In2.Cu")
		(net "P2E_CPU_SAS_C_TX_DP1")
	)
	(segment
		(start 80.233774 -51.45024)
		(end 79.890874 -51.45024)
		(width 0.1143)
		(layer "In2.Cu")
		(net "P2E_CPU_SAS_C_TX_DP1")
	)
	(segment
		(start 73.544176 -45.065188)
		(end 73.242424 -45.065188)
		(width 0.1143)
		(layer "In2.Cu")
		(net "P2E_CPU_SAS_C_TX_DP1")
	)
	(segment
		(start 68.116958 -42.869104)
		(end 65.3669 -40.119046)
		(width 0.1143)
		(layer "In2.Cu")
		(net "P2E_CPU_SAS_C_TX_DP1")
	)
	(segment
		(start 78.222094 -51.6636)
		(end 77.815694 -52.07)
		(width 0.1143)
		(layer "In2.Cu")
		(net "P2E_CPU_SAS_C_TX_DP1")
	)
	(segment
		(start 78.0288 -16.519906)
		(end 78.0288 -14.8336)
		(width 0.1143)
		(layer "In2.Cu")
		(net "P2E_CPU_SAS_C_TX_DP1")
	)
	(segment
		(start 74.57313 -46.094142)
		(end 74.330814 -45.851826)
		(width 0.1143)
		(layer "In2.Cu")
		(net "P2E_CPU_SAS_C_TX_DP1")
	)
	(segment
		(start 79.121254 -51.45024)
		(end 78.778354 -51.45024)
		(width 0.1143)
		(layer "In2.Cu")
		(net "P2E_CPU_SAS_C_TX_DP1")
	)
	(segment
		(start 76.819506 -17.1196)
		(end 77.429106 -17.1196)
		(width 0.1143)
		(layer "In2.Cu")
		(net "P2E_CPU_SAS_C_TX_DP1")
	)
	(segment
		(start 77.3176 -52.07)
		(end 77.0382 -51.7906)
		(width 0.1143)
		(layer "In2.Cu")
		(net "P2E_CPU_SAS_C_TX_DP1")
	)
	(segment
		(start 77.0382 -51.7906)
		(end 77.0382 -51.562)
		(width 0.1143)
		(layer "In2.Cu")
		(net "P2E_CPU_SAS_C_TX_DP1")
	)
	(segment
		(start 72.451214 -22.448266)
		(end 72.451214 -21.487892)
		(width 0.1143)
		(layer "In2.Cu")
		(net "P2E_CPU_SAS_C_TX_DP1")
	)
	(segment
		(start 78.778354 -51.45024)
		(end 78.564994 -51.6636)
		(width 0.1143)
		(layer "In2.Cu")
		(net "P2E_CPU_SAS_C_TX_DP1")
	)
	(segment
		(start 78.564994 -51.6636)
		(end 78.222094 -51.6636)
		(width 0.1143)
		(layer "In2.Cu")
		(net "P2E_CPU_SAS_C_TX_DP1")
	)
	(segment
		(start 67.73926 -27.018742)
		(end 68.834 -25.924002)
		(width 0.1143)
		(layer "In2.Cu")
		(net "P2E_CPU_SAS_C_TX_DP1")
	)
	(segment
		(start 77.815694 -52.07)
		(end 77.3176 -52.07)
		(width 0.1143)
		(layer "In2.Cu")
		(net "P2E_CPU_SAS_C_TX_DP1")
	)
	(segment
		(start 73.842626 -21.0566)
		(end 76.273914 -18.625566)
		(width 0.1143)
		(layer "In2.Cu")
		(net "P2E_CPU_SAS_C_TX_DP1")
	)
	(segment
		(start 73.242424 -45.065188)
		(end 72.756776 -44.57954)
		(width 0.1143)
		(layer "In2.Cu")
		(net "P2E_CPU_SAS_C_TX_DP1")
	)
	(segment
		(start 65.3669 -40.119046)
		(end 65.3669 -30.502606)
		(width 0.1143)
		(layer "In2.Cu")
		(net "P2E_CPU_SAS_C_TX_DP1")
	)
	(segment
		(start 77.429106 -17.1196)
		(end 78.0288 -16.519906)
		(width 0.1143)
		(layer "In2.Cu")
		(net "P2E_CPU_SAS_C_TX_DP1")
	)
	(segment
		(start 74.57313 -46.395894)
		(end 74.57313 -46.094142)
		(width 0.1143)
		(layer "In2.Cu")
		(net "P2E_CPU_SAS_C_TX_DP1")
	)
	(segment
		(start 76.273914 -17.665192)
		(end 76.819506 -17.1196)
		(width 0.1143)
		(layer "In2.Cu")
		(net "P2E_CPU_SAS_C_TX_DP1")
	)
	(segment
		(start 72.882506 -21.0566)
		(end 73.842626 -21.0566)
		(width 0.1143)
		(layer "In2.Cu")
		(net "P2E_CPU_SAS_C_TX_DP1")
	)
	(segment
		(start 83.112864 -51.664616)
		(end 83.334606 -51.442874)
		(width 0.1397)
		(layer "F.Cu")
		(net "P2E_CPU_SAS_C_TX_DN1")
	)
	(segment
		(start 83.112864 -51.791108)
		(end 83.112864 -51.664616)
		(width 0.1397)
		(layer "F.Cu")
		(net "P2E_CPU_SAS_C_TX_DN1")
	)
	(segment
		(start 83.334606 -51.442874)
		(end 83.447128 -51.442874)
		(width 0.1397)
		(layer "F.Cu")
		(net "P2E_CPU_SAS_C_TX_DN1")
	)
	(via
		(at 77.4192 -14.5796)
		(size 0.508)
		(drill 0.254)
		(layers "F.Cu" "B.Cu")
		(net "P2E_CPU_SAS_C_TX_DN1")
	)
	(via
		(at 83.112864 -51.791108)
		(size 0.4318)
		(drill 0.2032)
		(layers "F.Cu" "B.Cu")
		(net "P2E_CPU_SAS_C_TX_DN1")
	)
	(segment
		(start 77.47 -14.5288)
		(end 77.4192 -14.5796)
		(width 0.1397)
		(layer "B.Cu")
		(net "P2E_CPU_SAS_C_TX_DN1")
	)
	(segment
		(start 77.47 -13.9192)
		(end 77.47 -14.5288)
		(width 0.1397)
		(layer "B.Cu")
		(net "P2E_CPU_SAS_C_TX_DN1")
	)
	(segment
		(start 70.860666 -23.09495)
		(end 71.337424 -23.09495)
		(width 0.1143)
		(layer "In2.Cu")
		(net "P2E_CPU_SAS_C_TX_DN1")
	)
	(segment
		(start 77.2922 -16.7894)
		(end 77.6986 -16.383)
		(width 0.1143)
		(layer "In2.Cu")
		(net "P2E_CPU_SAS_C_TX_DN1")
	)
	(segment
		(start 76.6826 -16.7894)
		(end 77.2922 -16.7894)
		(width 0.1143)
		(layer "In2.Cu")
		(net "P2E_CPU_SAS_C_TX_DN1")
	)
	(segment
		(start 74.4855 -46.77537)
		(end 72.61987 -44.90974)
		(width 0.1143)
		(layer "In2.Cu")
		(net "P2E_CPU_SAS_C_TX_DN1")
	)
	(segment
		(start 68.5038 -25.451816)
		(end 70.860666 -23.09495)
		(width 0.1143)
		(layer "In2.Cu")
		(net "P2E_CPU_SAS_C_TX_DN1")
	)
	(segment
		(start 75.943714 -17.528286)
		(end 76.6826 -16.7894)
		(width 0.1143)
		(layer "In2.Cu")
		(net "P2E_CPU_SAS_C_TX_DN1")
	)
	(segment
		(start 76.708 -51.698906)
		(end 74.4855 -49.476406)
		(width 0.1143)
		(layer "In2.Cu")
		(net "P2E_CPU_SAS_C_TX_DN1")
	)
	(segment
		(start 65.0367 -30.3657)
		(end 65.7352 -29.6672)
		(width 0.1143)
		(layer "In2.Cu")
		(net "P2E_CPU_SAS_C_TX_DN1")
	)
	(segment
		(start 77.180694 -52.4002)
		(end 76.708 -51.927506)
		(width 0.1143)
		(layer "In2.Cu")
		(net "P2E_CPU_SAS_C_TX_DN1")
	)
	(segment
		(start 74.4855 -49.476406)
		(end 74.4855 -46.77537)
		(width 0.1143)
		(layer "In2.Cu")
		(net "P2E_CPU_SAS_C_TX_DN1")
	)
	(segment
		(start 65.0367 -40.255952)
		(end 65.0367 -30.3657)
		(width 0.1143)
		(layer "In2.Cu")
		(net "P2E_CPU_SAS_C_TX_DN1")
	)
	(segment
		(start 76.708 -51.927506)
		(end 76.708 -51.698906)
		(width 0.1143)
		(layer "In2.Cu")
		(net "P2E_CPU_SAS_C_TX_DN1")
	)
	(segment
		(start 72.121014 -22.31136)
		(end 72.121014 -21.350986)
		(width 0.1143)
		(layer "In2.Cu")
		(net "P2E_CPU_SAS_C_TX_DN1")
	)
	(segment
		(start 67.980052 -43.199304)
		(end 65.0367 -40.255952)
		(width 0.1143)
		(layer "In2.Cu")
		(net "P2E_CPU_SAS_C_TX_DN1")
	)
	(segment
		(start 68.462398 -43.199304)
		(end 67.980052 -43.199304)
		(width 0.1143)
		(layer "In2.Cu")
		(net "P2E_CPU_SAS_C_TX_DN1")
	)
	(segment
		(start 70.172834 -44.90974)
		(end 68.462398 -43.199304)
		(width 0.1143)
		(layer "In2.Cu")
		(net "P2E_CPU_SAS_C_TX_DN1")
	)
	(segment
		(start 82.914998 -51.791108)
		(end 82.712306 -51.9938)
		(width 0.1143)
		(layer "In2.Cu")
		(net "P2E_CPU_SAS_C_TX_DN1")
	)
	(segment
		(start 75.943714 -18.48866)
		(end 75.943714 -17.528286)
		(width 0.1143)
		(layer "In2.Cu")
		(net "P2E_CPU_SAS_C_TX_DN1")
	)
	(segment
		(start 77.6986 -16.383)
		(end 77.6986 -14.859)
		(width 0.1143)
		(layer "In2.Cu")
		(net "P2E_CPU_SAS_C_TX_DN1")
	)
	(segment
		(start 77.6986 -14.859)
		(end 77.4192 -14.5796)
		(width 0.1143)
		(layer "In2.Cu")
		(net "P2E_CPU_SAS_C_TX_DN1")
	)
	(segment
		(start 82.712306 -51.9938)
		(end 78.359 -51.9938)
		(width 0.1143)
		(layer "In2.Cu")
		(net "P2E_CPU_SAS_C_TX_DN1")
	)
	(segment
		(start 68.5038 -25.787096)
		(end 68.5038 -25.451816)
		(width 0.1143)
		(layer "In2.Cu")
		(net "P2E_CPU_SAS_C_TX_DN1")
	)
	(segment
		(start 72.7456 -20.7264)
		(end 73.70572 -20.7264)
		(width 0.1143)
		(layer "In2.Cu")
		(net "P2E_CPU_SAS_C_TX_DN1")
	)
	(segment
		(start 67.40906 -28.640024)
		(end 67.40906 -26.881836)
		(width 0.1143)
		(layer "In2.Cu")
		(net "P2E_CPU_SAS_C_TX_DN1")
	)
	(segment
		(start 66.381884 -29.6672)
		(end 67.40906 -28.640024)
		(width 0.1143)
		(layer "In2.Cu")
		(net "P2E_CPU_SAS_C_TX_DN1")
	)
	(segment
		(start 72.61987 -44.90974)
		(end 70.172834 -44.90974)
		(width 0.1143)
		(layer "In2.Cu")
		(net "P2E_CPU_SAS_C_TX_DN1")
	)
	(segment
		(start 78.359 -51.9938)
		(end 77.9526 -52.4002)
		(width 0.1143)
		(layer "In2.Cu")
		(net "P2E_CPU_SAS_C_TX_DN1")
	)
	(segment
		(start 73.70572 -20.7264)
		(end 75.943714 -18.48866)
		(width 0.1143)
		(layer "In2.Cu")
		(net "P2E_CPU_SAS_C_TX_DN1")
	)
	(segment
		(start 83.112864 -51.791108)
		(end 82.914998 -51.791108)
		(width 0.1143)
		(layer "In2.Cu")
		(net "P2E_CPU_SAS_C_TX_DN1")
	)
	(segment
		(start 71.337424 -23.09495)
		(end 72.121014 -22.31136)
		(width 0.1143)
		(layer "In2.Cu")
		(net "P2E_CPU_SAS_C_TX_DN1")
	)
	(segment
		(start 77.9526 -52.4002)
		(end 77.180694 -52.4002)
		(width 0.1143)
		(layer "In2.Cu")
		(net "P2E_CPU_SAS_C_TX_DN1")
	)
	(segment
		(start 67.40906 -26.881836)
		(end 68.5038 -25.787096)
		(width 0.1143)
		(layer "In2.Cu")
		(net "P2E_CPU_SAS_C_TX_DN1")
	)
	(segment
		(start 72.121014 -21.350986)
		(end 72.7456 -20.7264)
		(width 0.1143)
		(layer "In2.Cu")
		(net "P2E_CPU_SAS_C_TX_DN1")
	)
	(segment
		(start 65.7352 -29.6672)
		(end 66.381884 -29.6672)
		(width 0.1143)
		(layer "In2.Cu")
		(net "P2E_CPU_SAS_C_TX_DN1")
	)
	(segment
		(start 70.02145 -10.02284)
		(end 69.44233 -10.60196)
		(width 0.1397)
		(layer "B.Cu")
		(net "P2E_CPU_SAS_TX_DP3")
	)
	(segment
		(start 70.02145 -8.7757)
		(end 70.02145 -10.02284)
		(width 0.1397)
		(layer "B.Cu")
		(net "P2E_CPU_SAS_TX_DP3")
	)
	(segment
		(start 69.44233 -11.76147)
		(end 68.6816 -12.5222)
		(width 0.1397)
		(layer "B.Cu")
		(net "P2E_CPU_SAS_TX_DP3")
	)
	(segment
		(start 70.349872 -5.814568)
		(end 70.349872 -8.447278)
		(width 0.1397)
		(layer "B.Cu")
		(net "P2E_CPU_SAS_TX_DP3")
	)
	(segment
		(start 68.6816 -12.9794)
		(end 68.834 -13.1318)
		(width 0.1397)
		(layer "B.Cu")
		(net "P2E_CPU_SAS_TX_DP3")
	)
	(segment
		(start 68.6816 -12.5222)
		(end 68.6816 -12.9794)
		(width 0.1397)
		(layer "B.Cu")
		(net "P2E_CPU_SAS_TX_DP3")
	)
	(segment
		(start 69.44233 -10.60196)
		(end 69.44233 -11.76147)
		(width 0.1397)
		(layer "B.Cu")
		(net "P2E_CPU_SAS_TX_DP3")
	)
	(segment
		(start 70.349872 -8.447278)
		(end 70.02145 -8.7757)
		(width 0.1397)
		(layer "B.Cu")
		(net "P2E_CPU_SAS_TX_DP3")
	)
	(segment
		(start 82.238088 -50.640488)
		(end 82.046572 -50.448972)
		(width 0.1397)
		(layer "F.Cu")
		(net "P2E_CPU_SAS_C_TX_DN0")
	)
	(segment
		(start 82.238088 -50.741834)
		(end 82.238088 -50.640488)
		(width 0.1397)
		(layer "F.Cu")
		(net "P2E_CPU_SAS_C_TX_DN0")
	)
	(segment
		(start 82.046572 -50.448972)
		(end 81.853024 -50.448972)
		(width 0.1397)
		(layer "F.Cu")
		(net "P2E_CPU_SAS_C_TX_DN0")
	)
	(via
		(at 80.2132 -14.5796)
		(size 0.508)
		(drill 0.254)
		(layers "F.Cu" "B.Cu")
		(net "P2E_CPU_SAS_C_TX_DN0")
	)
	(via
		(at 81.853024 -50.448972)
		(size 0.4318)
		(drill 0.2032)
		(layers "F.Cu" "B.Cu")
		(net "P2E_CPU_SAS_C_TX_DN0")
	)
	(segment
		(start 80.264 -13.9192)
		(end 80.264 -14.5288)
		(width 0.1397)
		(layer "B.Cu")
		(net "P2E_CPU_SAS_C_TX_DN0")
	)
	(segment
		(start 80.264 -14.5288)
		(end 80.2132 -14.5796)
		(width 0.1397)
		(layer "B.Cu")
		(net "P2E_CPU_SAS_C_TX_DN0")
	)
	(segment
		(start 81.112106 -50.3428)
		(end 80.527906 -50.927)
		(width 0.1143)
		(layer "In2.Cu")
		(net "P2E_CPU_SAS_C_TX_DN0")
	)
	(segment
		(start 74.422 -21.35759)
		(end 78.687422 -17.092168)
		(width 0.1143)
		(layer "In2.Cu")
		(net "P2E_CPU_SAS_C_TX_DN0")
	)
	(segment
		(start 70.081394 -43.4467)
		(end 68.881244 -42.24655)
		(width 0.1143)
		(layer "In2.Cu")
		(net "P2E_CPU_SAS_C_TX_DN0")
	)
	(segment
		(start 67.82435 -30.486096)
		(end 67.82435 -29.86405)
		(width 0.1143)
		(layer "In2.Cu")
		(net "P2E_CPU_SAS_C_TX_DN0")
	)
	(segment
		(start 76.815696 -50.5079)
		(end 75.7809 -49.473104)
		(width 0.1143)
		(layer "In2.Cu")
		(net "P2E_CPU_SAS_C_TX_DN0")
	)
	(segment
		(start 68.374514 -42.24655)
		(end 65.9892 -39.861236)
		(width 0.1143)
		(layer "In2.Cu")
		(net "P2E_CPU_SAS_C_TX_DN0")
	)
	(segment
		(start 73.3425 -22.710648)
		(end 73.342754 -22.710902)
		(width 0.1143)
		(layer "In2.Cu")
		(net "P2E_CPU_SAS_C_TX_DN0")
	)
	(segment
		(start 68.2752 -29.4132)
		(end 68.8975 -29.4132)
		(width 0.1143)
		(layer "In2.Cu")
		(net "P2E_CPU_SAS_C_TX_DN0")
	)
	(segment
		(start 78.5241 -50.5079)
		(end 76.815696 -50.5079)
		(width 0.1143)
		(layer "In2.Cu")
		(net "P2E_CPU_SAS_C_TX_DN0")
	)
	(segment
		(start 73.342754 -22.710902)
		(end 74.027792 -22.710902)
		(width 0.1143)
		(layer "In2.Cu")
		(net "P2E_CPU_SAS_C_TX_DN0")
	)
	(segment
		(start 67.82435 -29.86405)
		(end 68.2752 -29.4132)
		(width 0.1143)
		(layer "In2.Cu")
		(net "P2E_CPU_SAS_C_TX_DN0")
	)
	(segment
		(start 65.9892 -31.4198)
		(end 66.59245 -30.81655)
		(width 0.1143)
		(layer "In2.Cu")
		(net "P2E_CPU_SAS_C_TX_DN0")
	)
	(segment
		(start 71.303896 -24.04745)
		(end 71.732394 -24.04745)
		(width 0.1143)
		(layer "In2.Cu")
		(net "P2E_CPU_SAS_C_TX_DN0")
	)
	(segment
		(start 66.59245 -30.81655)
		(end 67.493896 -30.81655)
		(width 0.1143)
		(layer "In2.Cu")
		(net "P2E_CPU_SAS_C_TX_DN0")
	)
	(segment
		(start 75.7809 -49.473104)
		(end 75.7809 -46.101)
		(width 0.1143)
		(layer "In2.Cu")
		(net "P2E_CPU_SAS_C_TX_DN0")
	)
	(segment
		(start 65.9892 -34.965894)
		(end 66.7512 -34.203894)
		(width 0.1143)
		(layer "In2.Cu")
		(net "P2E_CPU_SAS_C_TX_DN0")
	)
	(segment
		(start 80.508348 -14.874748)
		(end 80.2132 -14.5796)
		(width 0.1143)
		(layer "In2.Cu")
		(net "P2E_CPU_SAS_C_TX_DN0")
	)
	(segment
		(start 66.7512 -33.233106)
		(end 65.9892 -32.471106)
		(width 0.1143)
		(layer "In2.Cu")
		(net "P2E_CPU_SAS_C_TX_DN0")
	)
	(segment
		(start 81.853024 -50.448972)
		(end 81.746852 -50.3428)
		(width 0.1143)
		(layer "In2.Cu")
		(net "P2E_CPU_SAS_C_TX_DN0")
	)
	(segment
		(start 81.746852 -50.3428)
		(end 81.112106 -50.3428)
		(width 0.1143)
		(layer "In2.Cu")
		(net "P2E_CPU_SAS_C_TX_DN0")
	)
	(segment
		(start 74.422 -22.316694)
		(end 74.422 -21.35759)
		(width 0.1143)
		(layer "In2.Cu")
		(net "P2E_CPU_SAS_C_TX_DN0")
	)
	(segment
		(start 68.881244 -42.24655)
		(end 68.374514 -42.24655)
		(width 0.1143)
		(layer "In2.Cu")
		(net "P2E_CPU_SAS_C_TX_DN0")
	)
	(segment
		(start 69.6087 -28.702)
		(end 69.6087 -25.742646)
		(width 0.1143)
		(layer "In2.Cu")
		(net "P2E_CPU_SAS_C_TX_DN0")
	)
	(segment
		(start 75.7809 -46.101)
		(end 73.1266 -43.4467)
		(width 0.1143)
		(layer "In2.Cu")
		(net "P2E_CPU_SAS_C_TX_DN0")
	)
	(segment
		(start 68.8975 -29.4132)
		(end 69.6087 -28.702)
		(width 0.1143)
		(layer "In2.Cu")
		(net "P2E_CPU_SAS_C_TX_DN0")
	)
	(segment
		(start 66.7512 -34.203894)
		(end 66.7512 -33.233106)
		(width 0.1143)
		(layer "In2.Cu")
		(net "P2E_CPU_SAS_C_TX_DN0")
	)
	(segment
		(start 80.508348 -15.271496)
		(end 80.508348 -14.874748)
		(width 0.1143)
		(layer "In2.Cu")
		(net "P2E_CPU_SAS_C_TX_DN0")
	)
	(segment
		(start 74.027792 -22.710902)
		(end 74.422 -22.316694)
		(width 0.1143)
		(layer "In2.Cu")
		(net "P2E_CPU_SAS_C_TX_DN0")
	)
	(segment
		(start 65.9892 -32.471106)
		(end 65.9892 -31.4198)
		(width 0.1143)
		(layer "In2.Cu")
		(net "P2E_CPU_SAS_C_TX_DN0")
	)
	(segment
		(start 80.311244 -15.4686)
		(end 80.508348 -15.271496)
		(width 0.1143)
		(layer "In2.Cu")
		(net "P2E_CPU_SAS_C_TX_DN0")
	)
	(segment
		(start 69.6087 -25.742646)
		(end 71.303896 -24.04745)
		(width 0.1143)
		(layer "In2.Cu")
		(net "P2E_CPU_SAS_C_TX_DN0")
	)
	(segment
		(start 78.687422 -16.130778)
		(end 79.3496 -15.4686)
		(width 0.1143)
		(layer "In2.Cu")
		(net "P2E_CPU_SAS_C_TX_DN0")
	)
	(segment
		(start 73.1266 -43.4467)
		(end 70.081394 -43.4467)
		(width 0.1143)
		(layer "In2.Cu")
		(net "P2E_CPU_SAS_C_TX_DN0")
	)
	(segment
		(start 71.732394 -24.04745)
		(end 73.069196 -22.710648)
		(width 0.1143)
		(layer "In2.Cu")
		(net "P2E_CPU_SAS_C_TX_DN0")
	)
	(segment
		(start 65.9892 -39.861236)
		(end 65.9892 -34.965894)
		(width 0.1143)
		(layer "In2.Cu")
		(net "P2E_CPU_SAS_C_TX_DN0")
	)
	(segment
		(start 78.687422 -17.092168)
		(end 78.687422 -16.130778)
		(width 0.1143)
		(layer "In2.Cu")
		(net "P2E_CPU_SAS_C_TX_DN0")
	)
	(segment
		(start 73.069196 -22.710648)
		(end 73.3425 -22.710648)
		(width 0.1143)
		(layer "In2.Cu")
		(net "P2E_CPU_SAS_C_TX_DN0")
	)
	(segment
		(start 78.9432 -50.927)
		(end 78.5241 -50.5079)
		(width 0.1143)
		(layer "In2.Cu")
		(net "P2E_CPU_SAS_C_TX_DN0")
	)
	(segment
		(start 80.527906 -50.927)
		(end 78.9432 -50.927)
		(width 0.1143)
		(layer "In2.Cu")
		(net "P2E_CPU_SAS_C_TX_DN0")
	)
	(segment
		(start 67.493896 -30.81655)
		(end 67.82435 -30.486096)
		(width 0.1143)
		(layer "In2.Cu")
		(net "P2E_CPU_SAS_C_TX_DN0")
	)
	(segment
		(start 79.3496 -15.4686)
		(end 80.311244 -15.4686)
		(width 0.1143)
		(layer "In2.Cu")
		(net "P2E_CPU_SAS_C_TX_DN0")
	)
	(segment
		(start 74.349864 -8.447024)
		(end 74.021188 -8.7757)
		(width 0.1397)
		(layer "B.Cu")
		(net "P2E_CPU_SAS_TX_DP2")
	)
	(segment
		(start 73.45045 -12.92225)
		(end 73.66 -13.1318)
		(width 0.1397)
		(layer "B.Cu")
		(net "P2E_CPU_SAS_TX_DP2")
	)
	(segment
		(start 73.45045 -12.14755)
		(end 73.45045 -12.92225)
		(width 0.1397)
		(layer "B.Cu")
		(net "P2E_CPU_SAS_TX_DP2")
	)
	(segment
		(start 74.021188 -11.576812)
		(end 73.45045 -12.14755)
		(width 0.1397)
		(layer "B.Cu")
		(net "P2E_CPU_SAS_TX_DP2")
	)
	(segment
		(start 74.021188 -8.7757)
		(end 74.021188 -11.576812)
		(width 0.1397)
		(layer "B.Cu")
		(net "P2E_CPU_SAS_TX_DP2")
	)
	(segment
		(start 74.349864 -5.814568)
		(end 74.349864 -8.447024)
		(width 0.1397)
		(layer "B.Cu")
		(net "P2E_CPU_SAS_TX_DP2")
	)
	(segment
		(start 69.349874 -8.447024)
		(end 69.67855 -8.7757)
		(width 0.1397)
		(layer "B.Cu")
		(net "P2E_CPU_SAS_TX_DN3")
	)
	(segment
		(start 69.09943 -10.45972)
		(end 69.09943 -11.61923)
		(width 0.1397)
		(layer "B.Cu")
		(net "P2E_CPU_SAS_TX_DN3")
	)
	(segment
		(start 68.3387 -12.8651)
		(end 68.072 -13.1318)
		(width 0.1397)
		(layer "B.Cu")
		(net "P2E_CPU_SAS_TX_DN3")
	)
	(segment
		(start 69.67855 -8.7757)
		(end 69.67855 -9.8806)
		(width 0.1397)
		(layer "B.Cu")
		(net "P2E_CPU_SAS_TX_DN3")
	)
	(segment
		(start 69.349874 -5.814568)
		(end 69.349874 -8.447024)
		(width 0.1397)
		(layer "B.Cu")
		(net "P2E_CPU_SAS_TX_DN3")
	)
	(segment
		(start 69.67855 -9.8806)
		(end 69.09943 -10.45972)
		(width 0.1397)
		(layer "B.Cu")
		(net "P2E_CPU_SAS_TX_DN3")
	)
	(segment
		(start 69.09943 -11.61923)
		(end 68.3387 -12.37996)
		(width 0.1397)
		(layer "B.Cu")
		(net "P2E_CPU_SAS_TX_DN3")
	)
	(segment
		(start 68.3387 -12.37996)
		(end 68.3387 -12.8651)
		(width 0.1397)
		(layer "B.Cu")
		(net "P2E_CPU_SAS_TX_DN3")
	)
	(segment
		(start 82.748628 -50.264314)
		(end 82.445098 -49.960784)
		(width 0.1397)
		(layer "F.Cu")
		(net "P2E_CPU_SAS_C_TX_DP0")
	)
	(segment
		(start 82.445098 -49.960784)
		(end 82.126074 -49.960784)
		(width 0.1397)
		(layer "F.Cu")
		(net "P2E_CPU_SAS_C_TX_DP0")
	)
	(via
		(at 82.126074 -49.960784)
		(size 0.4318)
		(drill 0.2032)
		(layers "F.Cu" "B.Cu")
		(net "P2E_CPU_SAS_C_TX_DP0")
	)
	(via
		(at 81.0768 -14.5796)
		(size 0.508)
		(drill 0.254)
		(layers "F.Cu" "B.Cu")
		(net "P2E_CPU_SAS_C_TX_DP0")
	)
	(segment
		(start 81.026 -13.9192)
		(end 81.026 -14.5288)
		(width 0.1397)
		(layer "B.Cu")
		(net "P2E_CPU_SAS_C_TX_DP0")
	)
	(segment
		(start 81.026 -14.5288)
		(end 81.0768 -14.5796)
		(width 0.1397)
		(layer "B.Cu")
		(net "P2E_CPU_SAS_C_TX_DP0")
	)
	(segment
		(start 66.729356 -31.14675)
		(end 67.631056 -31.14675)
		(width 0.1143)
		(layer "In2.Cu")
		(net "P2E_CPU_SAS_C_TX_DP0")
	)
	(segment
		(start 66.3194 -39.72433)
		(end 66.3194 -35.1028)
		(width 0.1143)
		(layer "In2.Cu")
		(net "P2E_CPU_SAS_C_TX_DP0")
	)
	(segment
		(start 68.412106 -29.7434)
		(end 69.034406 -29.7434)
		(width 0.1143)
		(layer "In2.Cu")
		(net "P2E_CPU_SAS_C_TX_DP0")
	)
	(segment
		(start 79.017622 -17.229074)
		(end 79.017622 -16.267684)
		(width 0.1143)
		(layer "In2.Cu")
		(net "P2E_CPU_SAS_C_TX_DP0")
	)
	(segment
		(start 79.080106 -50.5968)
		(end 78.661006 -50.1777)
		(width 0.1143)
		(layer "In2.Cu")
		(net "P2E_CPU_SAS_C_TX_DP0")
	)
	(segment
		(start 72.18934 -43.1165)
		(end 71.97598 -42.90314)
		(width 0.1143)
		(layer "In2.Cu")
		(net "P2E_CPU_SAS_C_TX_DP0")
	)
	(segment
		(start 66.3194 -35.1028)
		(end 67.0814 -34.3408)
		(width 0.1143)
		(layer "In2.Cu")
		(net "P2E_CPU_SAS_C_TX_DP0")
	)
	(segment
		(start 67.0814 -34.3408)
		(end 67.0814 -33.0962)
		(width 0.1143)
		(layer "In2.Cu")
		(net "P2E_CPU_SAS_C_TX_DP0")
	)
	(segment
		(start 76.952602 -50.1777)
		(end 76.1111 -49.336198)
		(width 0.1143)
		(layer "In2.Cu")
		(net "P2E_CPU_SAS_C_TX_DP0")
	)
	(segment
		(start 79.017622 -16.267684)
		(end 79.486506 -15.7988)
		(width 0.1143)
		(layer "In2.Cu")
		(net "P2E_CPU_SAS_C_TX_DP0")
	)
	(segment
		(start 80.44815 -15.7988)
		(end 80.838548 -15.408402)
		(width 0.1143)
		(layer "In2.Cu")
		(net "P2E_CPU_SAS_C_TX_DP0")
	)
	(segment
		(start 71.440802 -24.37765)
		(end 71.8693 -24.37765)
		(width 0.1143)
		(layer "In2.Cu")
		(net "P2E_CPU_SAS_C_TX_DP0")
	)
	(segment
		(start 67.631056 -31.14675)
		(end 68.15455 -30.623002)
		(width 0.1143)
		(layer "In2.Cu")
		(net "P2E_CPU_SAS_C_TX_DP0")
	)
	(segment
		(start 74.7522 -21.494496)
		(end 79.017622 -17.229074)
		(width 0.1143)
		(layer "In2.Cu")
		(net "P2E_CPU_SAS_C_TX_DP0")
	)
	(segment
		(start 69.034406 -29.7434)
		(end 69.9389 -28.838906)
		(width 0.1143)
		(layer "In2.Cu")
		(net "P2E_CPU_SAS_C_TX_DP0")
	)
	(segment
		(start 76.1111 -45.964094)
		(end 73.263506 -43.1165)
		(width 0.1143)
		(layer "In2.Cu")
		(net "P2E_CPU_SAS_C_TX_DP0")
	)
	(segment
		(start 66.3194 -32.3342)
		(end 66.3194 -31.556706)
		(width 0.1143)
		(layer "In2.Cu")
		(net "P2E_CPU_SAS_C_TX_DP0")
	)
	(segment
		(start 74.164698 -23.041102)
		(end 74.7522 -22.4536)
		(width 0.1143)
		(layer "In2.Cu")
		(net "P2E_CPU_SAS_C_TX_DP0")
	)
	(segment
		(start 73.263506 -43.1165)
		(end 72.18934 -43.1165)
		(width 0.1143)
		(layer "In2.Cu")
		(net "P2E_CPU_SAS_C_TX_DP0")
	)
	(segment
		(start 80.838548 -14.817852)
		(end 81.0768 -14.5796)
		(width 0.1143)
		(layer "In2.Cu")
		(net "P2E_CPU_SAS_C_TX_DP0")
	)
	(segment
		(start 68.15455 -30.623002)
		(end 68.15455 -30.000956)
		(width 0.1143)
		(layer "In2.Cu")
		(net "P2E_CPU_SAS_C_TX_DP0")
	)
	(segment
		(start 68.51142 -41.91635)
		(end 66.3194 -39.72433)
		(width 0.1143)
		(layer "In2.Cu")
		(net "P2E_CPU_SAS_C_TX_DP0")
	)
	(segment
		(start 80.838548 -15.408402)
		(end 80.838548 -14.817852)
		(width 0.1143)
		(layer "In2.Cu")
		(net "P2E_CPU_SAS_C_TX_DP0")
	)
	(segment
		(start 82.066384 -50.0126)
		(end 80.9752 -50.0126)
		(width 0.1143)
		(layer "In2.Cu")
		(net "P2E_CPU_SAS_C_TX_DP0")
	)
	(segment
		(start 68.15455 -30.000956)
		(end 68.412106 -29.7434)
		(width 0.1143)
		(layer "In2.Cu")
		(net "P2E_CPU_SAS_C_TX_DP0")
	)
	(segment
		(start 71.63308 -42.90314)
		(end 71.41972 -43.1165)
		(width 0.1143)
		(layer "In2.Cu")
		(net "P2E_CPU_SAS_C_TX_DP0")
	)
	(segment
		(start 70.2183 -43.1165)
		(end 69.01815 -41.91635)
		(width 0.1143)
		(layer "In2.Cu")
		(net "P2E_CPU_SAS_C_TX_DP0")
	)
	(segment
		(start 80.9752 -50.0126)
		(end 80.391 -50.5968)
		(width 0.1143)
		(layer "In2.Cu")
		(net "P2E_CPU_SAS_C_TX_DP0")
	)
	(segment
		(start 80.391 -50.5968)
		(end 79.080106 -50.5968)
		(width 0.1143)
		(layer "In2.Cu")
		(net "P2E_CPU_SAS_C_TX_DP0")
	)
	(segment
		(start 69.9389 -25.879552)
		(end 71.440802 -24.37765)
		(width 0.1143)
		(layer "In2.Cu")
		(net "P2E_CPU_SAS_C_TX_DP0")
	)
	(segment
		(start 79.486506 -15.7988)
		(end 80.44815 -15.7988)
		(width 0.1143)
		(layer "In2.Cu")
		(net "P2E_CPU_SAS_C_TX_DP0")
	)
	(segment
		(start 69.01815 -41.91635)
		(end 68.51142 -41.91635)
		(width 0.1143)
		(layer "In2.Cu")
		(net "P2E_CPU_SAS_C_TX_DP0")
	)
	(segment
		(start 82.1182 -49.960784)
		(end 82.066384 -50.0126)
		(width 0.1143)
		(layer "In2.Cu")
		(net "P2E_CPU_SAS_C_TX_DP0")
	)
	(segment
		(start 71.97598 -42.90314)
		(end 71.63308 -42.90314)
		(width 0.1143)
		(layer "In2.Cu")
		(net "P2E_CPU_SAS_C_TX_DP0")
	)
	(segment
		(start 66.3194 -31.556706)
		(end 66.729356 -31.14675)
		(width 0.1143)
		(layer "In2.Cu")
		(net "P2E_CPU_SAS_C_TX_DP0")
	)
	(segment
		(start 69.9389 -28.838906)
		(end 69.9389 -25.879552)
		(width 0.1143)
		(layer "In2.Cu")
		(net "P2E_CPU_SAS_C_TX_DP0")
	)
	(segment
		(start 82.126074 -49.960784)
		(end 82.1182 -49.960784)
		(width 0.1143)
		(layer "In2.Cu")
		(net "P2E_CPU_SAS_C_TX_DP0")
	)
	(segment
		(start 67.0814 -33.0962)
		(end 66.3194 -32.3342)
		(width 0.1143)
		(layer "In2.Cu")
		(net "P2E_CPU_SAS_C_TX_DP0")
	)
	(segment
		(start 76.1111 -49.336198)
		(end 76.1111 -45.964094)
		(width 0.1143)
		(layer "In2.Cu")
		(net "P2E_CPU_SAS_C_TX_DP0")
	)
	(segment
		(start 71.41972 -43.1165)
		(end 70.2183 -43.1165)
		(width 0.1143)
		(layer "In2.Cu")
		(net "P2E_CPU_SAS_C_TX_DP0")
	)
	(segment
		(start 71.8693 -24.37765)
		(end 73.205848 -23.041102)
		(width 0.1143)
		(layer "In2.Cu")
		(net "P2E_CPU_SAS_C_TX_DP0")
	)
	(segment
		(start 73.205848 -23.041102)
		(end 74.164698 -23.041102)
		(width 0.1143)
		(layer "In2.Cu")
		(net "P2E_CPU_SAS_C_TX_DP0")
	)
	(segment
		(start 78.661006 -50.1777)
		(end 76.952602 -50.1777)
		(width 0.1143)
		(layer "In2.Cu")
		(net "P2E_CPU_SAS_C_TX_DP0")
	)
	(segment
		(start 74.7522 -22.4536)
		(end 74.7522 -21.494496)
		(width 0.1143)
		(layer "In2.Cu")
		(net "P2E_CPU_SAS_C_TX_DP0")
	)
	(segment
		(start 78.349856 -8.447024)
		(end 78.02118 -8.7757)
		(width 0.1397)
		(layer "B.Cu")
		(net "P2E_CPU_SAS_TX_DP1")
	)
	(segment
		(start 78.349856 -5.814568)
		(end 78.349856 -8.447024)
		(width 0.1397)
		(layer "B.Cu")
		(net "P2E_CPU_SAS_TX_DP1")
	)
	(segment
		(start 78.02118 -12.79398)
		(end 78.232 -13.0048)
		(width 0.1397)
		(layer "B.Cu")
		(net "P2E_CPU_SAS_TX_DP1")
	)
	(segment
		(start 78.02118 -8.7757)
		(end 78.02118 -12.79398)
		(width 0.1397)
		(layer "B.Cu")
		(net "P2E_CPU_SAS_TX_DP1")
	)
	(segment
		(start 73.349866 -5.814568)
		(end 73.349866 -8.447278)
		(width 0.1397)
		(layer "B.Cu")
		(net "P2E_CPU_SAS_TX_DN2")
	)
	(segment
		(start 73.349866 -8.447278)
		(end 73.678288 -8.7757)
		(width 0.1397)
		(layer "B.Cu")
		(net "P2E_CPU_SAS_TX_DN2")
	)
	(segment
		(start 73.10755 -12.92225)
		(end 72.898 -13.1318)
		(width 0.1397)
		(layer "B.Cu")
		(net "P2E_CPU_SAS_TX_DN2")
	)
	(segment
		(start 73.678288 -11.434572)
		(end 73.10755 -12.00531)
		(width 0.1397)
		(layer "B.Cu")
		(net "P2E_CPU_SAS_TX_DN2")
	)
	(segment
		(start 73.10755 -12.00531)
		(end 73.10755 -12.92225)
		(width 0.1397)
		(layer "B.Cu")
		(net "P2E_CPU_SAS_TX_DN2")
	)
	(segment
		(start 73.678288 -8.7757)
		(end 73.678288 -11.434572)
		(width 0.1397)
		(layer "B.Cu")
		(net "P2E_CPU_SAS_TX_DN2")
	)
	(segment
		(start 77.67828 -8.7757)
		(end 77.67828 -12.79652)
		(width 0.1397)
		(layer "B.Cu")
		(net "P2E_CPU_SAS_TX_DN1")
	)
	(segment
		(start 77.67828 -12.79652)
		(end 77.47 -13.0048)
		(width 0.1397)
		(layer "B.Cu")
		(net "P2E_CPU_SAS_TX_DN1")
	)
	(segment
		(start 77.349858 -5.814568)
		(end 77.349858 -8.447278)
		(width 0.1397)
		(layer "B.Cu")
		(net "P2E_CPU_SAS_TX_DN1")
	)
	(segment
		(start 77.349858 -8.447278)
		(end 77.67828 -8.7757)
		(width 0.1397)
		(layer "B.Cu")
		(net "P2E_CPU_SAS_TX_DN1")
	)
	(segment
		(start 82.349848 -5.814568)
		(end 82.349848 -8.447278)
		(width 0.1397)
		(layer "B.Cu")
		(net "P2E_CPU_SAS_TX_DP0")
	)
	(segment
		(start 82.349848 -8.447278)
		(end 82.021426 -8.7757)
		(width 0.1397)
		(layer "B.Cu")
		(net "P2E_CPU_SAS_TX_DP0")
	)
	(segment
		(start 80.8101 -11.3919)
		(end 80.8101 -12.7889)
		(width 0.1397)
		(layer "B.Cu")
		(net "P2E_CPU_SAS_TX_DP0")
	)
	(segment
		(start 82.021426 -8.7757)
		(end 82.021426 -10.180574)
		(width 0.1397)
		(layer "B.Cu")
		(net "P2E_CPU_SAS_TX_DP0")
	)
	(segment
		(start 80.8101 -12.7889)
		(end 81.026 -13.0048)
		(width 0.1397)
		(layer "B.Cu")
		(net "P2E_CPU_SAS_TX_DP0")
	)
	(segment
		(start 82.021426 -10.180574)
		(end 80.8101 -11.3919)
		(width 0.1397)
		(layer "B.Cu")
		(net "P2E_CPU_SAS_TX_DP0")
	)
	(segment
		(start 81.34985 -8.447024)
		(end 81.678526 -8.7757)
		(width 0.1397)
		(layer "B.Cu")
		(net "P2E_CPU_SAS_TX_DN0")
	)
	(segment
		(start 81.34985 -5.814568)
		(end 81.34985 -8.447024)
		(width 0.1397)
		(layer "B.Cu")
		(net "P2E_CPU_SAS_TX_DN0")
	)
	(segment
		(start 80.4672 -11.24966)
		(end 80.4672 -12.8016)
		(width 0.1397)
		(layer "B.Cu")
		(net "P2E_CPU_SAS_TX_DN0")
	)
	(segment
		(start 81.678526 -8.7757)
		(end 81.678526 -10.038334)
		(width 0.1397)
		(layer "B.Cu")
		(net "P2E_CPU_SAS_TX_DN0")
	)
	(segment
		(start 80.4672 -12.8016)
		(end 80.264 -13.0048)
		(width 0.1397)
		(layer "B.Cu")
		(net "P2E_CPU_SAS_TX_DN0")
	)
	(segment
		(start 81.678526 -10.038334)
		(end 80.4672 -11.24966)
		(width 0.1397)
		(layer "B.Cu")
		(net "P2E_CPU_SAS_TX_DN0")
	)
	(segment
		(start 87.434928 -48.783494)
		(end 86.998302 -48.783494)
		(width 0.1397)
		(layer "F.Cu")
		(net "P2E_CPU_SAS_RX_DN7")
	)
	(segment
		(start 35.349942 -8.447024)
		(end 35.678618 -8.7757)
		(width 0.1397)
		(layer "F.Cu")
		(net "P2E_CPU_SAS_RX_DN7")
	)
	(segment
		(start 35.678618 -9.980422)
		(end 35.408362 -10.250678)
		(width 0.1397)
		(layer "F.Cu")
		(net "P2E_CPU_SAS_RX_DN7")
	)
	(segment
		(start 35.678618 -8.7757)
		(end 35.678618 -9.980422)
		(width 0.1397)
		(layer "F.Cu")
		(net "P2E_CPU_SAS_RX_DN7")
	)
	(segment
		(start 86.998302 -48.783494)
		(end 86.9569 -48.824896)
		(width 0.1397)
		(layer "F.Cu")
		(net "P2E_CPU_SAS_RX_DN7")
	)
	(segment
		(start 86.9569 -48.824896)
		(end 86.9569 -48.82515)
		(width 0.1397)
		(layer "F.Cu")
		(net "P2E_CPU_SAS_RX_DN7")
	)
	(segment
		(start 35.349942 -6.195568)
		(end 35.349942 -8.447024)
		(width 0.1397)
		(layer "F.Cu")
		(net "P2E_CPU_SAS_RX_DN7")
	)
	(segment
		(start 86.9569 -48.82515)
		(end 86.954106 -48.82515)
		(width 0.1397)
		(layer "F.Cu")
		(net "P2E_CPU_SAS_RX_DN7")
	)
	(via
		(at 86.954106 -48.82515)
		(size 0.4318)
		(drill 0.2032)
		(layers "F.Cu" "B.Cu")
		(net "P2E_CPU_SAS_RX_DN7")
	)
	(via
		(at 35.408362 -10.250678)
		(size 0.508)
		(drill 0.254)
		(layers "F.Cu" "B.Cu")
		(net "P2E_CPU_SAS_RX_DN7")
	)
	(segment
		(start 86.545928 -48.6664)
		(end 86.4362 -48.776128)
		(width 0.1016)
		(layer "In9.Cu")
		(net "P2E_CPU_SAS_RX_DN7")
	)
	(segment
		(start 58.47715 -44.97324)
		(end 56.833008 -43.329098)
		(width 0.1143)
		(layer "In9.Cu")
		(net "P2E_CPU_SAS_RX_DN7")
	)
	(segment
		(start 60.089542 -48.0314)
		(end 58.47715 -46.419008)
		(width 0.1143)
		(layer "In9.Cu")
		(net "P2E_CPU_SAS_RX_DN7")
	)
	(segment
		(start 44.82465 -28.146756)
		(end 44.82465 -26.673556)
		(width 0.1143)
		(layer "In9.Cu")
		(net "P2E_CPU_SAS_RX_DN7")
	)
	(segment
		(start 53.203094 -33.3502)
		(end 50.028094 -33.3502)
		(width 0.1143)
		(layer "In9.Cu")
		(net "P2E_CPU_SAS_RX_DN7")
	)
	(segment
		(start 67.10426 -51.56835)
		(end 65.218564 -51.56835)
		(width 0.1143)
		(layer "In9.Cu")
		(net "P2E_CPU_SAS_RX_DN7")
	)
	(segment
		(start 42.89552 -24.744426)
		(end 42.89552 -22.45868)
		(width 0.1143)
		(layer "In9.Cu")
		(net "P2E_CPU_SAS_RX_DN7")
	)
	(segment
		(start 37.096192 -16.371824)
		(end 36.772596 -16.371824)
		(width 0.1143)
		(layer "In9.Cu")
		(net "P2E_CPU_SAS_RX_DN7")
	)
	(segment
		(start 83.439 -54.668928)
		(end 81.935828 -56.1721)
		(width 0.1016)
		(layer "In9.Cu")
		(net "P2E_CPU_SAS_RX_DN7")
	)
	(segment
		(start 81.3562 -56.2356)
		(end 74.132694 -56.2356)
		(width 0.1143)
		(layer "In9.Cu")
		(net "P2E_CPU_SAS_RX_DN7")
	)
	(segment
		(start 58.47715 -46.419008)
		(end 58.47715 -44.97324)
		(width 0.1143)
		(layer "In9.Cu")
		(net "P2E_CPU_SAS_RX_DN7")
	)
	(segment
		(start 36.772596 -16.371824)
		(end 36.0045 -15.603728)
		(width 0.1143)
		(layer "In9.Cu")
		(net "P2E_CPU_SAS_RX_DN7")
	)
	(segment
		(start 56.833008 -39.000938)
		(end 55.912258 -38.080188)
		(width 0.1143)
		(layer "In9.Cu")
		(net "P2E_CPU_SAS_RX_DN7")
	)
	(segment
		(start 56.833008 -43.329098)
		(end 56.833008 -39.000938)
		(width 0.1143)
		(layer "In9.Cu")
		(net "P2E_CPU_SAS_RX_DN7")
	)
	(segment
		(start 81.556606 -56.1721)
		(end 81.493106 -56.2356)
		(width 0.1016)
		(layer "In9.Cu")
		(net "P2E_CPU_SAS_RX_DN7")
	)
	(segment
		(start 81.493106 -56.2356)
		(end 81.3562 -56.2356)
		(width 0.1016)
		(layer "In9.Cu")
		(net "P2E_CPU_SAS_RX_DN7")
	)
	(segment
		(start 55.912258 -37.642038)
		(end 53.95595 -35.68573)
		(width 0.1143)
		(layer "In9.Cu")
		(net "P2E_CPU_SAS_RX_DN7")
	)
	(segment
		(start 55.912258 -38.080188)
		(end 55.912258 -37.642038)
		(width 0.1143)
		(layer "In9.Cu")
		(net "P2E_CPU_SAS_RX_DN7")
	)
	(segment
		(start 83.439 -53.957728)
		(end 83.439 -54.668928)
		(width 0.1016)
		(layer "In9.Cu")
		(net "P2E_CPU_SAS_RX_DN7")
	)
	(segment
		(start 53.95595 -35.68573)
		(end 53.95595 -34.103056)
		(width 0.1143)
		(layer "In9.Cu")
		(net "P2E_CPU_SAS_RX_DN7")
	)
	(segment
		(start 86.795356 -48.6664)
		(end 86.545928 -48.6664)
		(width 0.1016)
		(layer "In9.Cu")
		(net "P2E_CPU_SAS_RX_DN7")
	)
	(segment
		(start 37.7571 -17.32026)
		(end 37.7571 -17.032732)
		(width 0.1143)
		(layer "In9.Cu")
		(net "P2E_CPU_SAS_RX_DN7")
	)
	(segment
		(start 74.132694 -56.2356)
		(end 69.687694 -51.7906)
		(width 0.1143)
		(layer "In9.Cu")
		(net "P2E_CPU_SAS_RX_DN7")
	)
	(segment
		(start 86.4362 -50.419)
		(end 84.963 -51.8922)
		(width 0.1016)
		(layer "In9.Cu")
		(net "P2E_CPU_SAS_RX_DN7")
	)
	(segment
		(start 69.687694 -51.7906)
		(end 67.32651 -51.7906)
		(width 0.1143)
		(layer "In9.Cu")
		(net "P2E_CPU_SAS_RX_DN7")
	)
	(segment
		(start 35.703002 -14.323568)
		(end 35.703002 -10.545318)
		(width 0.1143)
		(layer "In9.Cu")
		(net "P2E_CPU_SAS_RX_DN7")
	)
	(segment
		(start 61.681614 -48.0314)
		(end 60.089542 -48.0314)
		(width 0.1143)
		(layer "In9.Cu")
		(net "P2E_CPU_SAS_RX_DN7")
	)
	(segment
		(start 42.89552 -22.45868)
		(end 37.7571 -17.32026)
		(width 0.1143)
		(layer "In9.Cu")
		(net "P2E_CPU_SAS_RX_DN7")
	)
	(segment
		(start 67.32651 -51.7906)
		(end 67.10426 -51.56835)
		(width 0.1143)
		(layer "In9.Cu")
		(net "P2E_CPU_SAS_RX_DN7")
	)
	(segment
		(start 86.954106 -48.82515)
		(end 86.795356 -48.6664)
		(width 0.1016)
		(layer "In9.Cu")
		(net "P2E_CPU_SAS_RX_DN7")
	)
	(segment
		(start 86.4362 -48.776128)
		(end 86.4362 -50.419)
		(width 0.1016)
		(layer "In9.Cu")
		(net "P2E_CPU_SAS_RX_DN7")
	)
	(segment
		(start 36.0045 -15.603728)
		(end 36.0045 -14.625066)
		(width 0.1143)
		(layer "In9.Cu")
		(net "P2E_CPU_SAS_RX_DN7")
	)
	(segment
		(start 81.935828 -56.1721)
		(end 81.556606 -56.1721)
		(width 0.1016)
		(layer "In9.Cu")
		(net "P2E_CPU_SAS_RX_DN7")
	)
	(segment
		(start 84.963 -52.433728)
		(end 83.439 -53.957728)
		(width 0.1016)
		(layer "In9.Cu")
		(net "P2E_CPU_SAS_RX_DN7")
	)
	(segment
		(start 44.82465 -26.673556)
		(end 42.89552 -24.744426)
		(width 0.1143)
		(layer "In9.Cu")
		(net "P2E_CPU_SAS_RX_DN7")
	)
	(segment
		(start 36.0045 -14.625066)
		(end 35.703002 -14.323568)
		(width 0.1143)
		(layer "In9.Cu")
		(net "P2E_CPU_SAS_RX_DN7")
	)
	(segment
		(start 50.028094 -33.3502)
		(end 44.82465 -28.146756)
		(width 0.1143)
		(layer "In9.Cu")
		(net "P2E_CPU_SAS_RX_DN7")
	)
	(segment
		(start 35.703002 -10.545318)
		(end 35.408362 -10.250678)
		(width 0.1143)
		(layer "In9.Cu")
		(net "P2E_CPU_SAS_RX_DN7")
	)
	(segment
		(start 53.95595 -34.103056)
		(end 53.203094 -33.3502)
		(width 0.1143)
		(layer "In9.Cu")
		(net "P2E_CPU_SAS_RX_DN7")
	)
	(segment
		(start 84.963 -51.8922)
		(end 84.963 -52.433728)
		(width 0.1016)
		(layer "In9.Cu")
		(net "P2E_CPU_SAS_RX_DN7")
	)
	(segment
		(start 65.218564 -51.56835)
		(end 61.681614 -48.0314)
		(width 0.1143)
		(layer "In9.Cu")
		(net "P2E_CPU_SAS_RX_DN7")
	)
	(segment
		(start 37.7571 -17.032732)
		(end 37.096192 -16.371824)
		(width 0.1143)
		(layer "In9.Cu")
		(net "P2E_CPU_SAS_RX_DN7")
	)
	(segment
		(start 40.349932 -6.195568)
		(end 40.349932 -8.447024)
		(width 0.1397)
		(layer "F.Cu")
		(net "P2E_CPU_SAS_RX_DP6")
	)
	(segment
		(start 86.149688 -48.402494)
		(end 86.149688 -48.400716)
		(width 0.1397)
		(layer "F.Cu")
		(net "P2E_CPU_SAS_RX_DP6")
	)
	(segment
		(start 85.805772 -48.0568)
		(end 85.8012 -48.0568)
		(width 0.1397)
		(layer "F.Cu")
		(net "P2E_CPU_SAS_RX_DP6")
	)
	(segment
		(start 40.349932 -8.447024)
		(end 40.021256 -8.7757)
		(width 0.1397)
		(layer "F.Cu")
		(net "P2E_CPU_SAS_RX_DP6")
	)
	(segment
		(start 86.149688 -48.400716)
		(end 85.805772 -48.0568)
		(width 0.1397)
		(layer "F.Cu")
		(net "P2E_CPU_SAS_RX_DP6")
	)
	(segment
		(start 40.021256 -8.7757)
		(end 40.021256 -9.9441)
		(width 0.1397)
		(layer "F.Cu")
		(net "P2E_CPU_SAS_RX_DP6")
	)
	(segment
		(start 40.021256 -9.9441)
		(end 40.327834 -10.250678)
		(width 0.1397)
		(layer "F.Cu")
		(net "P2E_CPU_SAS_RX_DP6")
	)
	(via
		(at 85.8012 -48.0568)
		(size 0.4318)
		(drill 0.2032)
		(layers "F.Cu" "B.Cu")
		(net "P2E_CPU_SAS_RX_DP6")
	)
	(via
		(at 40.327834 -10.250678)
		(size 0.508)
		(drill 0.254)
		(layers "F.Cu" "B.Cu")
		(net "P2E_CPU_SAS_RX_DP6")
	)
	(segment
		(start 82.308446 -53.911754)
		(end 82.0928 -54.1274)
		(width 0.1016)
		(layer "In9.Cu")
		(net "P2E_CPU_SAS_RX_DP6")
	)
	(segment
		(start 79.450438 -54.184042)
		(end 79.148686 -54.184042)
		(width 0.1143)
		(layer "In9.Cu")
		(net "P2E_CPU_SAS_RX_DP6")
	)
	(segment
		(start 45.0723 -14.7193)
		(end 41.4147 -14.7193)
		(width 0.1143)
		(layer "In9.Cu")
		(net "P2E_CPU_SAS_RX_DP6")
	)
	(segment
		(start 47.4218 -17.5514)
		(end 47.4218 -17.0688)
		(width 0.1143)
		(layer "In9.Cu")
		(net "P2E_CPU_SAS_RX_DP6")
	)
	(segment
		(start 39.273226 -12.97432)
		(end 38.9636 -12.664694)
		(width 0.1143)
		(layer "In9.Cu")
		(net "P2E_CPU_SAS_RX_DP6")
	)
	(segment
		(start 50.6222 -25.771094)
		(end 50.6222 -23.485094)
		(width 0.1143)
		(layer "In9.Cu")
		(net "P2E_CPU_SAS_RX_DP6")
	)
	(segment
		(start 38.9636 -12.664694)
		(end 38.9636 -12.049506)
		(width 0.1143)
		(layer "In9.Cu")
		(net "P2E_CPU_SAS_RX_DP6")
	)
	(segment
		(start 40.033194 -10.545318)
		(end 40.327834 -10.250678)
		(width 0.1143)
		(layer "In9.Cu")
		(net "P2E_CPU_SAS_RX_DP6")
	)
	(segment
		(start 70.219316 -50.5079)
		(end 67.858132 -50.5079)
		(width 0.1143)
		(layer "In9.Cu")
		(net "P2E_CPU_SAS_RX_DP6")
	)
	(segment
		(start 63.790068 -48.325532)
		(end 63.790068 -47.307246)
		(width 0.1143)
		(layer "In9.Cu")
		(net "P2E_CPU_SAS_RX_DP6")
	)
	(segment
		(start 54.03342 -30.15742)
		(end 54.03342 -28.547314)
		(width 0.1143)
		(layer "In9.Cu")
		(net "P2E_CPU_SAS_RX_DP6")
	)
	(segment
		(start 81.877154 -54.749446)
		(end 81.7372 -54.749446)
		(width 0.1016)
		(layer "In9.Cu")
		(net "P2E_CPU_SAS_RX_DP6")
	)
	(segment
		(start 54.03342 -28.547314)
		(end 53.299106 -27.813)
		(width 0.1143)
		(layer "In9.Cu")
		(net "P2E_CPU_SAS_RX_DP6")
	)
	(segment
		(start 61.473334 -44.990512)
		(end 61.473334 -43.37558)
		(width 0.1143)
		(layer "In9.Cu")
		(net "P2E_CPU_SAS_RX_DP6")
	)
	(segment
		(start 79.692754 -54.72811)
		(end 79.692754 -54.426358)
		(width 0.1143)
		(layer "In9.Cu")
		(net "P2E_CPU_SAS_RX_DP6")
	)
	(segment
		(start 85.4202 -48.3108)
		(end 85.203284 -48.527716)
		(width 0.1016)
		(layer "In9.Cu")
		(net "P2E_CPU_SAS_RX_DP6")
	)
	(segment
		(start 40.033194 -10.979912)
		(end 40.033194 -10.545318)
		(width 0.1143)
		(layer "In9.Cu")
		(net "P2E_CPU_SAS_RX_DP6")
	)
	(segment
		(start 67.635882 -50.28565)
		(end 65.750186 -50.28565)
		(width 0.1143)
		(layer "In9.Cu")
		(net "P2E_CPU_SAS_RX_DP6")
	)
	(segment
		(start 56.05145 -34.81705)
		(end 56.05145 -32.17545)
		(width 0.1143)
		(layer "In9.Cu")
		(net "P2E_CPU_SAS_RX_DP6")
	)
	(segment
		(start 80.90154 -55.22214)
		(end 80.59674 -55.22214)
		(width 0.1016)
		(layer "In9.Cu")
		(net "P2E_CPU_SAS_RX_DP6")
	)
	(segment
		(start 59.2582 -38.0238)
		(end 56.05145 -34.81705)
		(width 0.1143)
		(layer "In9.Cu")
		(net "P2E_CPU_SAS_RX_DP6")
	)
	(segment
		(start 63.790068 -47.307246)
		(end 61.473334 -44.990512)
		(width 0.1143)
		(layer "In9.Cu")
		(net "P2E_CPU_SAS_RX_DP6")
	)
	(segment
		(start 84.6074 -49.623472)
		(end 84.6074 -51.1048)
		(width 0.1016)
		(layer "In9.Cu")
		(net "P2E_CPU_SAS_RX_DP6")
	)
	(segment
		(start 39.66972 -12.97432)
		(end 39.273226 -12.97432)
		(width 0.1143)
		(layer "In9.Cu")
		(net "P2E_CPU_SAS_RX_DP6")
	)
	(segment
		(start 82.0928 -54.5338)
		(end 81.877154 -54.749446)
		(width 0.1016)
		(layer "In9.Cu")
		(net "P2E_CPU_SAS_RX_DP6")
	)
	(segment
		(start 41.4147 -14.7193)
		(end 39.66972 -12.97432)
		(width 0.1143)
		(layer "In9.Cu")
		(net "P2E_CPU_SAS_RX_DP6")
	)
	(segment
		(start 81.7372 -54.749446)
		(end 81.521554 -54.964838)
		(width 0.1016)
		(layer "In9.Cu")
		(net "P2E_CPU_SAS_RX_DP6")
	)
	(segment
		(start 82.308446 -53.7718)
		(end 82.308446 -53.911754)
		(width 0.1016)
		(layer "In9.Cu")
		(net "P2E_CPU_SAS_RX_DP6")
	)
	(segment
		(start 82.523838 -53.556154)
		(end 82.308446 -53.7718)
		(width 0.1016)
		(layer "In9.Cu")
		(net "P2E_CPU_SAS_RX_DP6")
	)
	(segment
		(start 53.299106 -27.813)
		(end 52.664106 -27.813)
		(width 0.1143)
		(layer "In9.Cu")
		(net "P2E_CPU_SAS_RX_DP6")
	)
	(segment
		(start 79.148686 -54.184042)
		(end 77.910944 -52.9463)
		(width 0.1143)
		(layer "In9.Cu")
		(net "P2E_CPU_SAS_RX_DP6")
	)
	(segment
		(start 81.0006 -55.3212)
		(end 80.90154 -55.22214)
		(width 0.1016)
		(layer "In9.Cu")
		(net "P2E_CPU_SAS_RX_DP6")
	)
	(segment
		(start 83.095084 -52.985162)
		(end 82.879438 -53.200554)
		(width 0.1016)
		(layer "In9.Cu")
		(net "P2E_CPU_SAS_RX_DP6")
	)
	(segment
		(start 50.6222 -23.485094)
		(end 48.3108 -21.173694)
		(width 0.1143)
		(layer "In9.Cu")
		(net "P2E_CPU_SAS_RX_DP6")
	)
	(segment
		(start 67.858132 -50.5079)
		(end 67.635882 -50.28565)
		(width 0.1143)
		(layer "In9.Cu")
		(net "P2E_CPU_SAS_RX_DP6")
	)
	(segment
		(start 48.3108 -18.4404)
		(end 47.4218 -17.5514)
		(width 0.1143)
		(layer "In9.Cu")
		(net "P2E_CPU_SAS_RX_DP6")
	)
	(segment
		(start 61.473334 -43.37558)
		(end 59.2582 -41.160446)
		(width 0.1143)
		(layer "In9.Cu")
		(net "P2E_CPU_SAS_RX_DP6")
	)
	(segment
		(start 84.6074 -51.1048)
		(end 83.9851 -51.7271)
		(width 0.1016)
		(layer "In9.Cu")
		(net "P2E_CPU_SAS_RX_DP6")
	)
	(segment
		(start 85.5472 -48.3108)
		(end 85.4202 -48.3108)
		(width 0.1016)
		(layer "In9.Cu")
		(net "P2E_CPU_SAS_RX_DP6")
	)
	(segment
		(start 79.935324 -54.97068)
		(end 79.692754 -54.72811)
		(width 0.1143)
		(layer "In9.Cu")
		(net "P2E_CPU_SAS_RX_DP6")
	)
	(segment
		(start 80.49768 -55.3212)
		(end 80.195928 -55.3212)
		(width 0.1016)
		(layer "In9.Cu")
		(net "P2E_CPU_SAS_RX_DP6")
	)
	(segment
		(start 79.953358 -55.07863)
		(end 79.953358 -54.988714)
		(width 0.1016)
		(layer "In9.Cu")
		(net "P2E_CPU_SAS_RX_DP6")
	)
	(segment
		(start 77.910944 -52.9463)
		(end 72.657716 -52.9463)
		(width 0.1143)
		(layer "In9.Cu")
		(net "P2E_CPU_SAS_RX_DP6")
	)
	(segment
		(start 80.195928 -55.3212)
		(end 79.953358 -55.07863)
		(width 0.1016)
		(layer "In9.Cu")
		(net "P2E_CPU_SAS_RX_DP6")
	)
	(segment
		(start 82.664046 -53.556154)
		(end 82.523838 -53.556154)
		(width 0.1016)
		(layer "In9.Cu")
		(net "P2E_CPU_SAS_RX_DP6")
	)
	(segment
		(start 81.3054 -55.3212)
		(end 81.0006 -55.3212)
		(width 0.1016)
		(layer "In9.Cu")
		(net "P2E_CPU_SAS_RX_DP6")
	)
	(segment
		(start 48.3108 -21.173694)
		(end 48.3108 -18.4404)
		(width 0.1143)
		(layer "In9.Cu")
		(net "P2E_CPU_SAS_RX_DP6")
	)
	(segment
		(start 83.9851 -51.7271)
		(end 83.9851 -52.2351)
		(width 0.1016)
		(layer "In9.Cu")
		(net "P2E_CPU_SAS_RX_DP6")
	)
	(segment
		(start 85.203284 -48.527716)
		(end 85.203284 -49.027588)
		(width 0.1016)
		(layer "In9.Cu")
		(net "P2E_CPU_SAS_RX_DP6")
	)
	(segment
		(start 79.953358 -54.988714)
		(end 79.935324 -54.97068)
		(width 0.1016)
		(layer "In9.Cu")
		(net "P2E_CPU_SAS_RX_DP6")
	)
	(segment
		(start 83.235038 -52.985162)
		(end 83.095084 -52.985162)
		(width 0.1016)
		(layer "In9.Cu")
		(net "P2E_CPU_SAS_RX_DP6")
	)
	(segment
		(start 47.4218 -17.0688)
		(end 45.0723 -14.7193)
		(width 0.1143)
		(layer "In9.Cu")
		(net "P2E_CPU_SAS_RX_DP6")
	)
	(segment
		(start 52.664106 -27.813)
		(end 50.6222 -25.771094)
		(width 0.1143)
		(layer "In9.Cu")
		(net "P2E_CPU_SAS_RX_DP6")
	)
	(segment
		(start 65.750186 -50.28565)
		(end 63.790068 -48.325532)
		(width 0.1143)
		(layer "In9.Cu")
		(net "P2E_CPU_SAS_RX_DP6")
	)
	(segment
		(start 79.692754 -54.426358)
		(end 79.450438 -54.184042)
		(width 0.1143)
		(layer "In9.Cu")
		(net "P2E_CPU_SAS_RX_DP6")
	)
	(segment
		(start 82.879438 -53.340762)
		(end 82.664046 -53.556154)
		(width 0.1016)
		(layer "In9.Cu")
		(net "P2E_CPU_SAS_RX_DP6")
	)
	(segment
		(start 85.203284 -49.027588)
		(end 84.6074 -49.623472)
		(width 0.1016)
		(layer "In9.Cu")
		(net "P2E_CPU_SAS_RX_DP6")
	)
	(segment
		(start 85.8012 -48.0568)
		(end 85.5472 -48.3108)
		(width 0.1016)
		(layer "In9.Cu")
		(net "P2E_CPU_SAS_RX_DP6")
	)
	(segment
		(start 80.59674 -55.22214)
		(end 80.49768 -55.3212)
		(width 0.1016)
		(layer "In9.Cu")
		(net "P2E_CPU_SAS_RX_DP6")
	)
	(segment
		(start 38.9636 -12.049506)
		(end 40.033194 -10.979912)
		(width 0.1143)
		(layer "In9.Cu")
		(net "P2E_CPU_SAS_RX_DP6")
	)
	(segment
		(start 82.0928 -54.1274)
		(end 82.0928 -54.5338)
		(width 0.1016)
		(layer "In9.Cu")
		(net "P2E_CPU_SAS_RX_DP6")
	)
	(segment
		(start 59.2582 -41.160446)
		(end 59.2582 -38.0238)
		(width 0.1143)
		(layer "In9.Cu")
		(net "P2E_CPU_SAS_RX_DP6")
	)
	(segment
		(start 82.879438 -53.200554)
		(end 82.879438 -53.340762)
		(width 0.1016)
		(layer "In9.Cu")
		(net "P2E_CPU_SAS_RX_DP6")
	)
	(segment
		(start 72.657716 -52.9463)
		(end 70.219316 -50.5079)
		(width 0.1143)
		(layer "In9.Cu")
		(net "P2E_CPU_SAS_RX_DP6")
	)
	(segment
		(start 81.521554 -54.964838)
		(end 81.521554 -55.105046)
		(width 0.1016)
		(layer "In9.Cu")
		(net "P2E_CPU_SAS_RX_DP6")
	)
	(segment
		(start 83.9851 -52.2351)
		(end 83.235038 -52.985162)
		(width 0.1016)
		(layer "In9.Cu")
		(net "P2E_CPU_SAS_RX_DP6")
	)
	(segment
		(start 81.521554 -55.105046)
		(end 81.3054 -55.3212)
		(width 0.1016)
		(layer "In9.Cu")
		(net "P2E_CPU_SAS_RX_DP6")
	)
	(segment
		(start 56.05145 -32.17545)
		(end 54.03342 -30.15742)
		(width 0.1143)
		(layer "In9.Cu")
		(net "P2E_CPU_SAS_RX_DP6")
	)
	(segment
		(start 39.678356 -8.7757)
		(end 39.678356 -9.980676)
		(width 0.1397)
		(layer "F.Cu")
		(net "P2E_CPU_SAS_RX_DN6")
	)
	(segment
		(start 39.349934 -8.447278)
		(end 39.678356 -8.7757)
		(width 0.1397)
		(layer "F.Cu")
		(net "P2E_CPU_SAS_RX_DN6")
	)
	(segment
		(start 86.149688 -49.162716)
		(end 85.805772 -48.8188)
		(width 0.1397)
		(layer "F.Cu")
		(net "P2E_CPU_SAS_RX_DN6")
	)
	(segment
		(start 85.805772 -48.8188)
		(end 85.8012 -48.8188)
		(width 0.1397)
		(layer "F.Cu")
		(net "P2E_CPU_SAS_RX_DN6")
	)
	(segment
		(start 39.678356 -9.980676)
		(end 39.408354 -10.250678)
		(width 0.1397)
		(layer "F.Cu")
		(net "P2E_CPU_SAS_RX_DN6")
	)
	(segment
		(start 39.349934 -6.195568)
		(end 39.349934 -8.447278)
		(width 0.1397)
		(layer "F.Cu")
		(net "P2E_CPU_SAS_RX_DN6")
	)
	(segment
		(start 86.149688 -49.164494)
		(end 86.149688 -49.162716)
		(width 0.1397)
		(layer "F.Cu")
		(net "P2E_CPU_SAS_RX_DN6")
	)
	(via
		(at 39.408354 -10.250678)
		(size 0.508)
		(drill 0.254)
		(layers "F.Cu" "B.Cu")
		(net "P2E_CPU_SAS_RX_DN6")
	)
	(via
		(at 85.8012 -48.8188)
		(size 0.4318)
		(drill 0.2032)
		(layers "F.Cu" "B.Cu")
		(net "P2E_CPU_SAS_RX_DN6")
	)
	(segment
		(start 81.389728 -55.5244)
		(end 80.1116 -55.5244)
		(width 0.1016)
		(layer "In9.Cu")
		(net "P2E_CPU_SAS_RX_DN6")
	)
	(segment
		(start 84.1883 -51.811428)
		(end 84.1883 -52.319428)
		(width 0.1016)
		(layer "In9.Cu")
		(net "P2E_CPU_SAS_RX_DN6")
	)
	(segment
		(start 47.0916 -17.688306)
		(end 47.0916 -17.205706)
		(width 0.1143)
		(layer "In9.Cu")
		(net "P2E_CPU_SAS_RX_DN6")
	)
	(segment
		(start 84.8106 -51.189128)
		(end 84.1883 -51.811428)
		(width 0.1016)
		(layer "In9.Cu")
		(net "P2E_CPU_SAS_RX_DN6")
	)
	(segment
		(start 61.143134 -45.127418)
		(end 61.143134 -43.512486)
		(width 0.1143)
		(layer "In9.Cu")
		(net "P2E_CPU_SAS_RX_DN6")
	)
	(segment
		(start 84.1883 -52.319428)
		(end 82.296 -54.211728)
		(width 0.1016)
		(layer "In9.Cu")
		(net "P2E_CPU_SAS_RX_DN6")
	)
	(segment
		(start 61.143134 -43.512486)
		(end 58.928 -41.297352)
		(width 0.1143)
		(layer "In9.Cu")
		(net "P2E_CPU_SAS_RX_DN6")
	)
	(segment
		(start 85.406484 -49.111916)
		(end 84.8106 -49.7078)
		(width 0.1016)
		(layer "In9.Cu")
		(net "P2E_CPU_SAS_RX_DN6")
	)
	(segment
		(start 47.0916 -17.205706)
		(end 44.935394 -15.0495)
		(width 0.1143)
		(layer "In9.Cu")
		(net "P2E_CPU_SAS_RX_DN6")
	)
	(segment
		(start 82.296 -54.211728)
		(end 82.296 -54.618128)
		(width 0.1016)
		(layer "In9.Cu")
		(net "P2E_CPU_SAS_RX_DN6")
	)
	(segment
		(start 41.277794 -15.0495)
		(end 39.532814 -13.30452)
		(width 0.1143)
		(layer "In9.Cu")
		(net "P2E_CPU_SAS_RX_DN6")
	)
	(segment
		(start 50.292 -25.908)
		(end 50.292 -23.622)
		(width 0.1143)
		(layer "In9.Cu")
		(net "P2E_CPU_SAS_RX_DN6")
	)
	(segment
		(start 85.8012 -48.8188)
		(end 85.8012 -48.666908)
		(width 0.1016)
		(layer "In9.Cu")
		(net "P2E_CPU_SAS_RX_DN6")
	)
	(segment
		(start 79.791306 -55.204106)
		(end 79.701644 -55.204106)
		(width 0.1016)
		(layer "In9.Cu")
		(net "P2E_CPU_SAS_RX_DN6")
	)
	(segment
		(start 39.702994 -10.843006)
		(end 39.702994 -10.545318)
		(width 0.1143)
		(layer "In9.Cu")
		(net "P2E_CPU_SAS_RX_DN6")
	)
	(segment
		(start 55.72125 -32.312356)
		(end 53.70322 -30.294326)
		(width 0.1143)
		(layer "In9.Cu")
		(net "P2E_CPU_SAS_RX_DN6")
	)
	(segment
		(start 79.701644 -55.204106)
		(end 77.774038 -53.2765)
		(width 0.1143)
		(layer "In9.Cu")
		(net "P2E_CPU_SAS_RX_DN6")
	)
	(segment
		(start 84.8106 -49.7078)
		(end 84.8106 -51.189128)
		(width 0.1016)
		(layer "In9.Cu")
		(net "P2E_CPU_SAS_RX_DN6")
	)
	(segment
		(start 72.52081 -53.2765)
		(end 70.08241 -50.8381)
		(width 0.1143)
		(layer "In9.Cu")
		(net "P2E_CPU_SAS_RX_DN6")
	)
	(segment
		(start 80.1116 -55.5244)
		(end 79.791306 -55.204106)
		(width 0.1016)
		(layer "In9.Cu")
		(net "P2E_CPU_SAS_RX_DN6")
	)
	(segment
		(start 70.08241 -50.8381)
		(end 67.721226 -50.8381)
		(width 0.1143)
		(layer "In9.Cu")
		(net "P2E_CPU_SAS_RX_DN6")
	)
	(segment
		(start 63.459868 -48.462438)
		(end 63.459868 -47.444152)
		(width 0.1143)
		(layer "In9.Cu")
		(net "P2E_CPU_SAS_RX_DN6")
	)
	(segment
		(start 47.9806 -21.3106)
		(end 47.9806 -18.577306)
		(width 0.1143)
		(layer "In9.Cu")
		(net "P2E_CPU_SAS_RX_DN6")
	)
	(segment
		(start 55.72125 -34.953956)
		(end 55.72125 -32.312356)
		(width 0.1143)
		(layer "In9.Cu")
		(net "P2E_CPU_SAS_RX_DN6")
	)
	(segment
		(start 50.292 -23.622)
		(end 47.9806 -21.3106)
		(width 0.1143)
		(layer "In9.Cu")
		(net "P2E_CPU_SAS_RX_DN6")
	)
	(segment
		(start 38.6334 -11.9126)
		(end 39.702994 -10.843006)
		(width 0.1143)
		(layer "In9.Cu")
		(net "P2E_CPU_SAS_RX_DN6")
	)
	(segment
		(start 85.648292 -48.514)
		(end 85.504528 -48.514)
		(width 0.1016)
		(layer "In9.Cu")
		(net "P2E_CPU_SAS_RX_DN6")
	)
	(segment
		(start 58.928 -41.297352)
		(end 58.928 -38.160706)
		(width 0.1143)
		(layer "In9.Cu")
		(net "P2E_CPU_SAS_RX_DN6")
	)
	(segment
		(start 53.70322 -28.68422)
		(end 53.1622 -28.1432)
		(width 0.1143)
		(layer "In9.Cu")
		(net "P2E_CPU_SAS_RX_DN6")
	)
	(segment
		(start 63.459868 -47.444152)
		(end 61.143134 -45.127418)
		(width 0.1143)
		(layer "In9.Cu")
		(net "P2E_CPU_SAS_RX_DN6")
	)
	(segment
		(start 82.296 -54.618128)
		(end 81.389728 -55.5244)
		(width 0.1016)
		(layer "In9.Cu")
		(net "P2E_CPU_SAS_RX_DN6")
	)
	(segment
		(start 44.935394 -15.0495)
		(end 41.277794 -15.0495)
		(width 0.1143)
		(layer "In9.Cu")
		(net "P2E_CPU_SAS_RX_DN6")
	)
	(segment
		(start 47.9806 -18.577306)
		(end 47.0916 -17.688306)
		(width 0.1143)
		(layer "In9.Cu")
		(net "P2E_CPU_SAS_RX_DN6")
	)
	(segment
		(start 65.61328 -50.61585)
		(end 63.459868 -48.462438)
		(width 0.1143)
		(layer "In9.Cu")
		(net "P2E_CPU_SAS_RX_DN6")
	)
	(segment
		(start 39.13632 -13.30452)
		(end 38.6334 -12.8016)
		(width 0.1143)
		(layer "In9.Cu")
		(net "P2E_CPU_SAS_RX_DN6")
	)
	(segment
		(start 38.6334 -12.8016)
		(end 38.6334 -11.9126)
		(width 0.1143)
		(layer "In9.Cu")
		(net "P2E_CPU_SAS_RX_DN6")
	)
	(segment
		(start 67.498976 -50.61585)
		(end 65.61328 -50.61585)
		(width 0.1143)
		(layer "In9.Cu")
		(net "P2E_CPU_SAS_RX_DN6")
	)
	(segment
		(start 53.70322 -30.294326)
		(end 53.70322 -28.68422)
		(width 0.1143)
		(layer "In9.Cu")
		(net "P2E_CPU_SAS_RX_DN6")
	)
	(segment
		(start 58.928 -38.160706)
		(end 55.72125 -34.953956)
		(width 0.1143)
		(layer "In9.Cu")
		(net "P2E_CPU_SAS_RX_DN6")
	)
	(segment
		(start 67.721226 -50.8381)
		(end 67.498976 -50.61585)
		(width 0.1143)
		(layer "In9.Cu")
		(net "P2E_CPU_SAS_RX_DN6")
	)
	(segment
		(start 85.406484 -48.612044)
		(end 85.406484 -49.111916)
		(width 0.1016)
		(layer "In9.Cu")
		(net "P2E_CPU_SAS_RX_DN6")
	)
	(segment
		(start 39.532814 -13.30452)
		(end 39.13632 -13.30452)
		(width 0.1143)
		(layer "In9.Cu")
		(net "P2E_CPU_SAS_RX_DN6")
	)
	(segment
		(start 85.8012 -48.666908)
		(end 85.648292 -48.514)
		(width 0.1016)
		(layer "In9.Cu")
		(net "P2E_CPU_SAS_RX_DN6")
	)
	(segment
		(start 77.774038 -53.2765)
		(end 72.52081 -53.2765)
		(width 0.1143)
		(layer "In9.Cu")
		(net "P2E_CPU_SAS_RX_DN6")
	)
	(segment
		(start 52.5272 -28.1432)
		(end 50.292 -25.908)
		(width 0.1143)
		(layer "In9.Cu")
		(net "P2E_CPU_SAS_RX_DN6")
	)
	(segment
		(start 85.504528 -48.514)
		(end 85.406484 -48.612044)
		(width 0.1016)
		(layer "In9.Cu")
		(net "P2E_CPU_SAS_RX_DN6")
	)
	(segment
		(start 39.702994 -10.545318)
		(end 39.408354 -10.250678)
		(width 0.1143)
		(layer "In9.Cu")
		(net "P2E_CPU_SAS_RX_DN6")
	)
	(segment
		(start 53.1622 -28.1432)
		(end 52.5272 -28.1432)
		(width 0.1143)
		(layer "In9.Cu")
		(net "P2E_CPU_SAS_RX_DN6")
	)
	(segment
		(start 36.34994 -6.195568)
		(end 36.34994 -8.447278)
		(width 0.1397)
		(layer "F.Cu")
		(net "P2E_CPU_SAS_RX_DP7")
	)
	(segment
		(start 36.021518 -8.7757)
		(end 36.021518 -9.944354)
		(width 0.1397)
		(layer "F.Cu")
		(net "P2E_CPU_SAS_RX_DP7")
	)
	(segment
		(start 36.021518 -9.944354)
		(end 36.327842 -10.250678)
		(width 0.1397)
		(layer "F.Cu")
		(net "P2E_CPU_SAS_RX_DP7")
	)
	(segment
		(start 36.34994 -8.447278)
		(end 36.021518 -8.7757)
		(width 0.1397)
		(layer "F.Cu")
		(net "P2E_CPU_SAS_RX_DP7")
	)
	(segment
		(start 87.434928 -48.021494)
		(end 87.190326 -48.266096)
		(width 0.1397)
		(layer "F.Cu")
		(net "P2E_CPU_SAS_RX_DP7")
	)
	(segment
		(start 87.190326 -48.266096)
		(end 86.954868 -48.266096)
		(width 0.1397)
		(layer "F.Cu")
		(net "P2E_CPU_SAS_RX_DP7")
	)
	(via
		(at 36.327842 -10.250678)
		(size 0.508)
		(drill 0.254)
		(layers "F.Cu" "B.Cu")
		(net "P2E_CPU_SAS_RX_DP7")
	)
	(via
		(at 86.954868 -48.266096)
		(size 0.4318)
		(drill 0.2032)
		(layers "F.Cu" "B.Cu")
		(net "P2E_CPU_SAS_RX_DP7")
	)
	(segment
		(start 36.3347 -15.466822)
		(end 36.3347 -14.48816)
		(width 0.1143)
		(layer "In9.Cu")
		(net "P2E_CPU_SAS_RX_DP7")
	)
	(segment
		(start 69.8246 -51.4604)
		(end 67.463416 -51.4604)
		(width 0.1143)
		(layer "In9.Cu")
		(net "P2E_CPU_SAS_RX_DP7")
	)
	(segment
		(start 83.973162 -53.136038)
		(end 83.832954 -53.136038)
		(width 0.1016)
		(layer "In9.Cu")
		(net "P2E_CPU_SAS_RX_DP7")
	)
	(segment
		(start 57.163208 -38.864032)
		(end 56.242458 -37.943282)
		(width 0.1143)
		(layer "In9.Cu")
		(net "P2E_CPU_SAS_RX_DP7")
	)
	(segment
		(start 60.226448 -47.7012)
		(end 58.80735 -46.282102)
		(width 0.1143)
		(layer "In9.Cu")
		(net "P2E_CPU_SAS_RX_DP7")
	)
	(segment
		(start 56.242458 -37.505132)
		(end 54.28615 -35.548824)
		(width 0.1143)
		(layer "In9.Cu")
		(net "P2E_CPU_SAS_RX_DP7")
	)
	(segment
		(start 86.233 -50.334672)
		(end 86.017354 -50.550318)
		(width 0.1016)
		(layer "In9.Cu")
		(net "P2E_CPU_SAS_RX_DP7")
	)
	(segment
		(start 43.22572 -24.60752)
		(end 43.22572 -22.321774)
		(width 0.1143)
		(layer "In9.Cu")
		(net "P2E_CPU_SAS_RX_DP7")
	)
	(segment
		(start 67.463416 -51.4604)
		(end 67.241166 -51.23815)
		(width 0.1143)
		(layer "In9.Cu")
		(net "P2E_CPU_SAS_RX_DP7")
	)
	(segment
		(start 85.661754 -50.76571)
		(end 85.661754 -50.905918)
		(width 0.1016)
		(layer "In9.Cu")
		(net "P2E_CPU_SAS_RX_DP7")
	)
	(segment
		(start 74.2696 -55.9054)
		(end 69.8246 -51.4604)
		(width 0.1143)
		(layer "In9.Cu")
		(net "P2E_CPU_SAS_RX_DP7")
	)
	(segment
		(start 81.493106 -55.9054)
		(end 81.3562 -55.9054)
		(width 0.1016)
		(layer "In9.Cu")
		(net "P2E_CPU_SAS_RX_DP7")
	)
	(segment
		(start 61.81852 -47.7012)
		(end 60.226448 -47.7012)
		(width 0.1143)
		(layer "In9.Cu")
		(net "P2E_CPU_SAS_RX_DP7")
	)
	(segment
		(start 84.188554 -52.780438)
		(end 84.188554 -52.920646)
		(width 0.1016)
		(layer "In9.Cu")
		(net "P2E_CPU_SAS_RX_DP7")
	)
	(segment
		(start 43.22572 -22.321774)
		(end 38.0873 -17.183354)
		(width 0.1143)
		(layer "In9.Cu")
		(net "P2E_CPU_SAS_RX_DP7")
	)
	(segment
		(start 81.8515 -55.9689)
		(end 81.556606 -55.9689)
		(width 0.1016)
		(layer "In9.Cu")
		(net "P2E_CPU_SAS_RX_DP7")
	)
	(segment
		(start 36.3347 -14.48816)
		(end 36.033202 -14.186662)
		(width 0.1143)
		(layer "In9.Cu")
		(net "P2E_CPU_SAS_RX_DP7")
	)
	(segment
		(start 67.241166 -51.23815)
		(end 65.35547 -51.23815)
		(width 0.1143)
		(layer "In9.Cu")
		(net "P2E_CPU_SAS_RX_DP7")
	)
	(segment
		(start 36.909502 -16.041624)
		(end 36.3347 -15.466822)
		(width 0.1143)
		(layer "In9.Cu")
		(net "P2E_CPU_SAS_RX_DP7")
	)
	(segment
		(start 84.188554 -52.920646)
		(end 83.973162 -53.136038)
		(width 0.1016)
		(layer "In9.Cu")
		(net "P2E_CPU_SAS_RX_DP7")
	)
	(segment
		(start 83.2358 -54.5846)
		(end 83.020154 -54.800246)
		(width 0.1016)
		(layer "In9.Cu")
		(net "P2E_CPU_SAS_RX_DP7")
	)
	(segment
		(start 85.8774 -50.550318)
		(end 85.661754 -50.76571)
		(width 0.1016)
		(layer "In9.Cu")
		(net "P2E_CPU_SAS_RX_DP7")
	)
	(segment
		(start 36.033202 -10.545318)
		(end 36.327842 -10.250678)
		(width 0.1143)
		(layer "In9.Cu")
		(net "P2E_CPU_SAS_RX_DP7")
	)
	(segment
		(start 82.8802 -54.800246)
		(end 82.664554 -55.015638)
		(width 0.1016)
		(layer "In9.Cu")
		(net "P2E_CPU_SAS_RX_DP7")
	)
	(segment
		(start 45.15485 -26.53665)
		(end 43.22572 -24.60752)
		(width 0.1143)
		(layer "In9.Cu")
		(net "P2E_CPU_SAS_RX_DP7")
	)
	(segment
		(start 86.4616 -48.4632)
		(end 86.233 -48.6918)
		(width 0.1016)
		(layer "In9.Cu")
		(net "P2E_CPU_SAS_RX_DP7")
	)
	(segment
		(start 86.954868 -48.266096)
		(end 86.757764 -48.4632)
		(width 0.1016)
		(layer "In9.Cu")
		(net "P2E_CPU_SAS_RX_DP7")
	)
	(segment
		(start 36.033202 -14.186662)
		(end 36.033202 -10.545318)
		(width 0.1143)
		(layer "In9.Cu")
		(net "P2E_CPU_SAS_RX_DP7")
	)
	(segment
		(start 84.4042 -52.565046)
		(end 84.188554 -52.780438)
		(width 0.1016)
		(layer "In9.Cu")
		(net "P2E_CPU_SAS_RX_DP7")
	)
	(segment
		(start 54.28615 -33.96615)
		(end 53.34 -33.02)
		(width 0.1143)
		(layer "In9.Cu")
		(net "P2E_CPU_SAS_RX_DP7")
	)
	(segment
		(start 57.163208 -43.192192)
		(end 57.163208 -38.864032)
		(width 0.1143)
		(layer "In9.Cu")
		(net "P2E_CPU_SAS_RX_DP7")
	)
	(segment
		(start 38.0873 -17.183354)
		(end 38.0873 -16.895826)
		(width 0.1143)
		(layer "In9.Cu")
		(net "P2E_CPU_SAS_RX_DP7")
	)
	(segment
		(start 82.093562 -55.586884)
		(end 82.093562 -55.726838)
		(width 0.1016)
		(layer "In9.Cu")
		(net "P2E_CPU_SAS_RX_DP7")
	)
	(segment
		(start 86.233 -48.6918)
		(end 86.233 -50.334672)
		(width 0.1016)
		(layer "In9.Cu")
		(net "P2E_CPU_SAS_RX_DP7")
	)
	(segment
		(start 86.017354 -50.550318)
		(end 85.8774 -50.550318)
		(width 0.1016)
		(layer "In9.Cu")
		(net "P2E_CPU_SAS_RX_DP7")
	)
	(segment
		(start 84.544154 -52.565046)
		(end 84.4042 -52.565046)
		(width 0.1016)
		(layer "In9.Cu")
		(net "P2E_CPU_SAS_RX_DP7")
	)
	(segment
		(start 65.35547 -51.23815)
		(end 61.81852 -47.7012)
		(width 0.1143)
		(layer "In9.Cu")
		(net "P2E_CPU_SAS_RX_DP7")
	)
	(segment
		(start 82.093562 -55.726838)
		(end 81.8515 -55.9689)
		(width 0.1016)
		(layer "In9.Cu")
		(net "P2E_CPU_SAS_RX_DP7")
	)
	(segment
		(start 37.233098 -16.041624)
		(end 36.909502 -16.041624)
		(width 0.1143)
		(layer "In9.Cu")
		(net "P2E_CPU_SAS_RX_DP7")
	)
	(segment
		(start 83.617562 -53.351684)
		(end 83.617562 -53.491638)
		(width 0.1016)
		(layer "In9.Cu")
		(net "P2E_CPU_SAS_RX_DP7")
	)
	(segment
		(start 82.449162 -55.371238)
		(end 82.308954 -55.371238)
		(width 0.1016)
		(layer "In9.Cu")
		(net "P2E_CPU_SAS_RX_DP7")
	)
	(segment
		(start 54.28615 -35.548824)
		(end 54.28615 -33.96615)
		(width 0.1143)
		(layer "In9.Cu")
		(net "P2E_CPU_SAS_RX_DP7")
	)
	(segment
		(start 82.664554 -55.015638)
		(end 82.664554 -55.155846)
		(width 0.1016)
		(layer "In9.Cu")
		(net "P2E_CPU_SAS_RX_DP7")
	)
	(segment
		(start 83.832954 -53.136038)
		(end 83.617562 -53.351684)
		(width 0.1016)
		(layer "In9.Cu")
		(net "P2E_CPU_SAS_RX_DP7")
	)
	(segment
		(start 38.0873 -16.895826)
		(end 37.233098 -16.041624)
		(width 0.1143)
		(layer "In9.Cu")
		(net "P2E_CPU_SAS_RX_DP7")
	)
	(segment
		(start 83.617562 -53.491638)
		(end 83.2358 -53.8734)
		(width 0.1016)
		(layer "In9.Cu")
		(net "P2E_CPU_SAS_RX_DP7")
	)
	(segment
		(start 82.308954 -55.371238)
		(end 82.093562 -55.586884)
		(width 0.1016)
		(layer "In9.Cu")
		(net "P2E_CPU_SAS_RX_DP7")
	)
	(segment
		(start 86.757764 -48.4632)
		(end 86.4616 -48.4632)
		(width 0.1016)
		(layer "In9.Cu")
		(net "P2E_CPU_SAS_RX_DP7")
	)
	(segment
		(start 84.7598 -51.807872)
		(end 84.7598 -52.3494)
		(width 0.1016)
		(layer "In9.Cu")
		(net "P2E_CPU_SAS_RX_DP7")
	)
	(segment
		(start 56.242458 -37.943282)
		(end 56.242458 -37.505132)
		(width 0.1143)
		(layer "In9.Cu")
		(net "P2E_CPU_SAS_RX_DP7")
	)
	(segment
		(start 85.661754 -50.905918)
		(end 84.7598 -51.807872)
		(width 0.1016)
		(layer "In9.Cu")
		(net "P2E_CPU_SAS_RX_DP7")
	)
	(segment
		(start 53.34 -33.02)
		(end 50.165 -33.02)
		(width 0.1143)
		(layer "In9.Cu")
		(net "P2E_CPU_SAS_RX_DP7")
	)
	(segment
		(start 81.556606 -55.9689)
		(end 81.493106 -55.9054)
		(width 0.1016)
		(layer "In9.Cu")
		(net "P2E_CPU_SAS_RX_DP7")
	)
	(segment
		(start 81.3562 -55.9054)
		(end 74.2696 -55.9054)
		(width 0.1143)
		(layer "In9.Cu")
		(net "P2E_CPU_SAS_RX_DP7")
	)
	(segment
		(start 83.2358 -53.8734)
		(end 83.2358 -54.5846)
		(width 0.1016)
		(layer "In9.Cu")
		(net "P2E_CPU_SAS_RX_DP7")
	)
	(segment
		(start 45.15485 -28.00985)
		(end 45.15485 -26.53665)
		(width 0.1143)
		(layer "In9.Cu")
		(net "P2E_CPU_SAS_RX_DP7")
	)
	(segment
		(start 58.80735 -46.282102)
		(end 58.80735 -44.836334)
		(width 0.1143)
		(layer "In9.Cu")
		(net "P2E_CPU_SAS_RX_DP7")
	)
	(segment
		(start 50.165 -33.02)
		(end 45.15485 -28.00985)
		(width 0.1143)
		(layer "In9.Cu")
		(net "P2E_CPU_SAS_RX_DP7")
	)
	(segment
		(start 58.80735 -44.836334)
		(end 57.163208 -43.192192)
		(width 0.1143)
		(layer "In9.Cu")
		(net "P2E_CPU_SAS_RX_DP7")
	)
	(segment
		(start 84.7598 -52.3494)
		(end 84.544154 -52.565046)
		(width 0.1016)
		(layer "In9.Cu")
		(net "P2E_CPU_SAS_RX_DP7")
	)
	(segment
		(start 82.664554 -55.155846)
		(end 82.449162 -55.371238)
		(width 0.1016)
		(layer "In9.Cu")
		(net "P2E_CPU_SAS_RX_DP7")
	)
	(segment
		(start 83.020154 -54.800246)
		(end 82.8802 -54.800246)
		(width 0.1016)
		(layer "In9.Cu")
		(net "P2E_CPU_SAS_RX_DP7")
	)
	(segment
		(start 85.448648 -47.640494)
		(end 85.448648 -47.670212)
		(width 0.1397)
		(layer "F.Cu")
		(net "P2E_CPU_SAS_RX_DP5")
	)
	(segment
		(start 85.448648 -47.670212)
		(end 85.015578 -48.103282)
		(width 0.1397)
		(layer "F.Cu")
		(net "P2E_CPU_SAS_RX_DP5")
	)
	(segment
		(start 44.021502 -8.7757)
		(end 44.021502 -9.944354)
		(width 0.1397)
		(layer "F.Cu")
		(net "P2E_CPU_SAS_RX_DP5")
	)
	(segment
		(start 44.349924 -8.447278)
		(end 44.021502 -8.7757)
		(width 0.1397)
		(layer "F.Cu")
		(net "P2E_CPU_SAS_RX_DP5")
	)
	(segment
		(start 44.349924 -6.195568)
		(end 44.349924 -8.447278)
		(width 0.1397)
		(layer "F.Cu")
		(net "P2E_CPU_SAS_RX_DP5")
	)
	(segment
		(start 44.021502 -9.944354)
		(end 44.327826 -10.250678)
		(width 0.1397)
		(layer "F.Cu")
		(net "P2E_CPU_SAS_RX_DP5")
	)
	(via
		(at 44.327826 -10.250678)
		(size 0.508)
		(drill 0.254)
		(layers "F.Cu" "B.Cu")
		(net "P2E_CPU_SAS_RX_DP5")
	)
	(via
		(at 85.015578 -48.103282)
		(size 0.4318)
		(drill 0.2032)
		(layers "F.Cu" "B.Cu")
		(net "P2E_CPU_SAS_RX_DP5")
	)
	(segment
		(start 65.13195 -47.301912)
		(end 62.425834 -44.595796)
		(width 0.1143)
		(layer "In9.Cu")
		(net "P2E_CPU_SAS_RX_DP5")
	)
	(segment
		(start 53.086 -24.805894)
		(end 53.086 -17.688306)
		(width 0.1143)
		(layer "In9.Cu")
		(net "P2E_CPU_SAS_RX_DP5")
	)
	(segment
		(start 84.201 -50.701194)
		(end 83.564984 -51.33721)
		(width 0.1016)
		(layer "In9.Cu")
		(net "P2E_CPU_SAS_RX_DP5")
	)
	(segment
		(start 83.257898 -52.243228)
		(end 82.850228 -52.243228)
		(width 0.1016)
		(layer "In9.Cu")
		(net "P2E_CPU_SAS_RX_DP5")
	)
	(segment
		(start 46.235112 -11.160252)
		(end 45.892212 -11.160252)
		(width 0.1143)
		(layer "In9.Cu")
		(net "P2E_CPU_SAS_RX_DP5")
	)
	(segment
		(start 72.874632 -51.816)
		(end 70.614032 -49.5554)
		(width 0.1143)
		(layer "In9.Cu")
		(net "P2E_CPU_SAS_RX_DP5")
	)
	(segment
		(start 56.0451 -29.189934)
		(end 56.0451 -27.764994)
		(width 0.1143)
		(layer "In9.Cu")
		(net "P2E_CPU_SAS_RX_DP5")
	)
	(segment
		(start 76.962 -51.816)
		(end 72.874632 -51.816)
		(width 0.1143)
		(layer "In9.Cu")
		(net "P2E_CPU_SAS_RX_DP5")
	)
	(segment
		(start 81.43748 -51.8922)
		(end 81.33842 -51.79314)
		(width 0.1016)
		(layer "In9.Cu")
		(net "P2E_CPU_SAS_RX_DP5")
	)
	(segment
		(start 60.2488 -37.246306)
		(end 60.640976 -36.85413)
		(width 0.1143)
		(layer "In9.Cu")
		(net "P2E_CPU_SAS_RX_DP5")
	)
	(segment
		(start 84.201 -49.031144)
		(end 84.201 -50.701194)
		(width 0.1016)
		(layer "In9.Cu")
		(net "P2E_CPU_SAS_RX_DP5")
	)
	(segment
		(start 53.086 -17.688306)
		(end 54.3687 -16.405606)
		(width 0.1143)
		(layer "In9.Cu")
		(net "P2E_CPU_SAS_RX_DP5")
	)
	(segment
		(start 54.3687 -13.9192)
		(end 52.8447 -12.3952)
		(width 0.1143)
		(layer "In9.Cu")
		(net "P2E_CPU_SAS_RX_DP5")
	)
	(segment
		(start 60.2488 -40.80383)
		(end 60.2488 -37.246306)
		(width 0.1143)
		(layer "In9.Cu")
		(net "P2E_CPU_SAS_RX_DP5")
	)
	(segment
		(start 82.4992 -51.8922)
		(end 82.2452 -51.8922)
		(width 0.1016)
		(layer "In9.Cu")
		(net "P2E_CPU_SAS_RX_DP5")
	)
	(segment
		(start 82.850228 -52.243228)
		(end 82.4992 -51.8922)
		(width 0.1016)
		(layer "In9.Cu")
		(net "P2E_CPU_SAS_RX_DP5")
	)
	(segment
		(start 84.370672 -48.344328)
		(end 84.107528 -48.607472)
		(width 0.1016)
		(layer "In9.Cu")
		(net "P2E_CPU_SAS_RX_DP5")
	)
	(segment
		(start 45.892212 -11.160252)
		(end 45.678852 -11.373612)
		(width 0.1143)
		(layer "In9.Cu")
		(net "P2E_CPU_SAS_RX_DP5")
	)
	(segment
		(start 79.714852 -51.79314)
		(end 79.410052 -51.79314)
		(width 0.1016)
		(layer "In9.Cu")
		(net "P2E_CPU_SAS_RX_DP5")
	)
	(segment
		(start 81.03362 -51.79314)
		(end 80.93456 -51.8922)
		(width 0.1016)
		(layer "In9.Cu")
		(net "P2E_CPU_SAS_RX_DP5")
	)
	(segment
		(start 44.545758 -11.373612)
		(end 44.033186 -10.86104)
		(width 0.1143)
		(layer "In9.Cu")
		(net "P2E_CPU_SAS_RX_DP5")
	)
	(segment
		(start 80.93456 -51.8922)
		(end 79.813912 -51.8922)
		(width 0.1016)
		(layer "In9.Cu")
		(net "P2E_CPU_SAS_RX_DP5")
	)
	(segment
		(start 78.503272 -51.8922)
		(end 78.173072 -51.8922)
		(width 0.1016)
		(layer "In9.Cu")
		(net "P2E_CPU_SAS_RX_DP5")
	)
	(segment
		(start 70.614032 -49.5554)
		(end 68.252848 -49.5554)
		(width 0.1143)
		(layer "In9.Cu")
		(net "P2E_CPU_SAS_RX_DP5")
	)
	(segment
		(start 77.919072 -52.1462)
		(end 77.6605 -52.1462)
		(width 0.1016)
		(layer "In9.Cu")
		(net "P2E_CPU_SAS_RX_DP5")
	)
	(segment
		(start 45.678852 -11.373612)
		(end 44.545758 -11.373612)
		(width 0.1143)
		(layer "In9.Cu")
		(net "P2E_CPU_SAS_RX_DP5")
	)
	(segment
		(start 44.033186 -10.545318)
		(end 44.327826 -10.250678)
		(width 0.1143)
		(layer "In9.Cu")
		(net "P2E_CPU_SAS_RX_DP5")
	)
	(segment
		(start 85.015578 -48.103282)
		(end 84.774532 -48.344328)
		(width 0.1016)
		(layer "In9.Cu")
		(net "P2E_CPU_SAS_RX_DP5")
	)
	(segment
		(start 81.84134 -51.79314)
		(end 81.74228 -51.8922)
		(width 0.1016)
		(layer "In9.Cu")
		(net "P2E_CPU_SAS_RX_DP5")
	)
	(segment
		(start 81.74228 -51.8922)
		(end 81.43748 -51.8922)
		(width 0.1016)
		(layer "In9.Cu")
		(net "P2E_CPU_SAS_RX_DP5")
	)
	(segment
		(start 83.564984 -51.33721)
		(end 83.564984 -51.936142)
		(width 0.1016)
		(layer "In9.Cu")
		(net "P2E_CPU_SAS_RX_DP5")
	)
	(segment
		(start 47.070518 -11.373612)
		(end 46.448472 -11.373612)
		(width 0.1143)
		(layer "In9.Cu")
		(net "P2E_CPU_SAS_RX_DP5")
	)
	(segment
		(start 52.8447 -12.3952)
		(end 48.092106 -12.3952)
		(width 0.1143)
		(layer "In9.Cu")
		(net "P2E_CPU_SAS_RX_DP5")
	)
	(segment
		(start 82.2452 -51.8922)
		(end 82.14614 -51.79314)
		(width 0.1016)
		(layer "In9.Cu")
		(net "P2E_CPU_SAS_RX_DP5")
	)
	(segment
		(start 54.3687 -16.405606)
		(end 54.3687 -13.9192)
		(width 0.1143)
		(layer "In9.Cu")
		(net "P2E_CPU_SAS_RX_DP5")
	)
	(segment
		(start 44.033186 -10.86104)
		(end 44.033186 -10.545318)
		(width 0.1143)
		(layer "In9.Cu")
		(net "P2E_CPU_SAS_RX_DP5")
	)
	(segment
		(start 60.640976 -36.85413)
		(end 60.640976 -33.78581)
		(width 0.1143)
		(layer "In9.Cu")
		(net "P2E_CPU_SAS_RX_DP5")
	)
	(segment
		(start 79.813912 -51.8922)
		(end 79.714852 -51.79314)
		(width 0.1016)
		(layer "In9.Cu")
		(net "P2E_CPU_SAS_RX_DP5")
	)
	(segment
		(start 77.597 -52.0827)
		(end 77.2287 -52.0827)
		(width 0.1143)
		(layer "In9.Cu")
		(net "P2E_CPU_SAS_RX_DP5")
	)
	(segment
		(start 84.107528 -48.607472)
		(end 84.107528 -48.937672)
		(width 0.1016)
		(layer "In9.Cu")
		(net "P2E_CPU_SAS_RX_DP5")
	)
	(segment
		(start 77.6605 -52.1462)
		(end 77.597 -52.0827)
		(width 0.1016)
		(layer "In9.Cu")
		(net "P2E_CPU_SAS_RX_DP5")
	)
	(segment
		(start 81.33842 -51.79314)
		(end 81.03362 -51.79314)
		(width 0.1016)
		(layer "In9.Cu")
		(net "P2E_CPU_SAS_RX_DP5")
	)
	(segment
		(start 84.774532 -48.344328)
		(end 84.370672 -48.344328)
		(width 0.1016)
		(layer "In9.Cu")
		(net "P2E_CPU_SAS_RX_DP5")
	)
	(segment
		(start 83.564984 -51.936142)
		(end 83.257898 -52.243228)
		(width 0.1016)
		(layer "In9.Cu")
		(net "P2E_CPU_SAS_RX_DP5")
	)
	(segment
		(start 79.310992 -51.8922)
		(end 79.006192 -51.8922)
		(width 0.1016)
		(layer "In9.Cu")
		(net "P2E_CPU_SAS_RX_DP5")
	)
	(segment
		(start 65.13195 -48.320198)
		(end 65.13195 -47.301912)
		(width 0.1143)
		(layer "In9.Cu")
		(net "P2E_CPU_SAS_RX_DP5")
	)
	(segment
		(start 60.640976 -33.78581)
		(end 56.0451 -29.189934)
		(width 0.1143)
		(layer "In9.Cu")
		(net "P2E_CPU_SAS_RX_DP5")
	)
	(segment
		(start 66.144902 -49.33315)
		(end 65.13195 -48.320198)
		(width 0.1143)
		(layer "In9.Cu")
		(net "P2E_CPU_SAS_RX_DP5")
	)
	(segment
		(start 79.410052 -51.79314)
		(end 79.310992 -51.8922)
		(width 0.1016)
		(layer "In9.Cu")
		(net "P2E_CPU_SAS_RX_DP5")
	)
	(segment
		(start 48.092106 -12.3952)
		(end 47.070518 -11.373612)
		(width 0.1143)
		(layer "In9.Cu")
		(net "P2E_CPU_SAS_RX_DP5")
	)
	(segment
		(start 46.448472 -11.373612)
		(end 46.235112 -11.160252)
		(width 0.1143)
		(layer "In9.Cu")
		(net "P2E_CPU_SAS_RX_DP5")
	)
	(segment
		(start 62.425834 -42.980864)
		(end 60.2488 -40.80383)
		(width 0.1143)
		(layer "In9.Cu")
		(net "P2E_CPU_SAS_RX_DP5")
	)
	(segment
		(start 56.0451 -27.764994)
		(end 53.086 -24.805894)
		(width 0.1143)
		(layer "In9.Cu")
		(net "P2E_CPU_SAS_RX_DP5")
	)
	(segment
		(start 68.252848 -49.5554)
		(end 68.030598 -49.33315)
		(width 0.1143)
		(layer "In9.Cu")
		(net "P2E_CPU_SAS_RX_DP5")
	)
	(segment
		(start 78.173072 -51.8922)
		(end 77.919072 -52.1462)
		(width 0.1016)
		(layer "In9.Cu")
		(net "P2E_CPU_SAS_RX_DP5")
	)
	(segment
		(start 79.006192 -51.8922)
		(end 78.907132 -51.79314)
		(width 0.1016)
		(layer "In9.Cu")
		(net "P2E_CPU_SAS_RX_DP5")
	)
	(segment
		(start 62.425834 -44.595796)
		(end 62.425834 -42.980864)
		(width 0.1143)
		(layer "In9.Cu")
		(net "P2E_CPU_SAS_RX_DP5")
	)
	(segment
		(start 78.602332 -51.79314)
		(end 78.503272 -51.8922)
		(width 0.1016)
		(layer "In9.Cu")
		(net "P2E_CPU_SAS_RX_DP5")
	)
	(segment
		(start 78.907132 -51.79314)
		(end 78.602332 -51.79314)
		(width 0.1016)
		(layer "In9.Cu")
		(net "P2E_CPU_SAS_RX_DP5")
	)
	(segment
		(start 82.14614 -51.79314)
		(end 81.84134 -51.79314)
		(width 0.1016)
		(layer "In9.Cu")
		(net "P2E_CPU_SAS_RX_DP5")
	)
	(segment
		(start 68.030598 -49.33315)
		(end 66.144902 -49.33315)
		(width 0.1143)
		(layer "In9.Cu")
		(net "P2E_CPU_SAS_RX_DP5")
	)
	(segment
		(start 77.2287 -52.0827)
		(end 76.962 -51.816)
		(width 0.1143)
		(layer "In9.Cu")
		(net "P2E_CPU_SAS_RX_DP5")
	)
	(segment
		(start 84.107528 -48.937672)
		(end 84.201 -49.031144)
		(width 0.1016)
		(layer "In9.Cu")
		(net "P2E_CPU_SAS_RX_DP5")
	)
	(segment
		(start 43.349926 -8.447024)
		(end 43.678602 -8.7757)
		(width 0.1397)
		(layer "F.Cu")
		(net "P2E_CPU_SAS_RX_DN5")
	)
	(segment
		(start 43.349926 -6.195568)
		(end 43.349926 -8.447024)
		(width 0.1397)
		(layer "F.Cu")
		(net "P2E_CPU_SAS_RX_DN5")
	)
	(segment
		(start 85.448648 -48.402494)
		(end 85.06714 -48.784002)
		(width 0.1397)
		(layer "F.Cu")
		(net "P2E_CPU_SAS_RX_DN5")
	)
	(segment
		(start 43.678602 -8.7757)
		(end 43.678602 -9.980422)
		(width 0.1397)
		(layer "F.Cu")
		(net "P2E_CPU_SAS_RX_DN5")
	)
	(segment
		(start 43.678602 -9.980422)
		(end 43.408346 -10.250678)
		(width 0.1397)
		(layer "F.Cu")
		(net "P2E_CPU_SAS_RX_DN5")
	)
	(segment
		(start 85.06714 -48.784002)
		(end 84.834984 -48.784002)
		(width 0.1397)
		(layer "F.Cu")
		(net "P2E_CPU_SAS_RX_DN5")
	)
	(via
		(at 43.408346 -10.250678)
		(size 0.508)
		(drill 0.254)
		(layers "F.Cu" "B.Cu")
		(net "P2E_CPU_SAS_RX_DN5")
	)
	(via
		(at 84.834984 -48.784002)
		(size 0.4318)
		(drill 0.2032)
		(layers "F.Cu" "B.Cu")
		(net "P2E_CPU_SAS_RX_DN5")
	)
	(segment
		(start 84.310728 -48.6918)
		(end 84.310728 -48.853344)
		(width 0.1016)
		(layer "In9.Cu")
		(net "P2E_CPU_SAS_RX_DN5")
	)
	(segment
		(start 84.834984 -48.783748)
		(end 84.598764 -48.547528)
		(width 0.1016)
		(layer "In9.Cu")
		(net "P2E_CPU_SAS_RX_DN5")
	)
	(segment
		(start 83.342226 -52.446428)
		(end 82.7659 -52.446428)
		(width 0.1016)
		(layer "In9.Cu")
		(net "P2E_CPU_SAS_RX_DN5")
	)
	(segment
		(start 83.768184 -51.421538)
		(end 83.768184 -52.02047)
		(width 0.1016)
		(layer "In9.Cu")
		(net "P2E_CPU_SAS_RX_DN5")
	)
	(segment
		(start 76.825094 -52.1462)
		(end 72.737726 -52.1462)
		(width 0.1143)
		(layer "In9.Cu")
		(net "P2E_CPU_SAS_RX_DN5")
	)
	(segment
		(start 52.707794 -12.7254)
		(end 47.9552 -12.7254)
		(width 0.1143)
		(layer "In9.Cu")
		(net "P2E_CPU_SAS_RX_DN5")
	)
	(segment
		(start 62.095634 -44.732702)
		(end 62.095634 -43.11777)
		(width 0.1143)
		(layer "In9.Cu")
		(net "P2E_CPU_SAS_RX_DN5")
	)
	(segment
		(start 84.834984 -48.784002)
		(end 84.834984 -48.783748)
		(width 0.1016)
		(layer "In9.Cu")
		(net "P2E_CPU_SAS_RX_DN5")
	)
	(segment
		(start 78.2574 -52.0954)
		(end 78.0034 -52.3494)
		(width 0.1016)
		(layer "In9.Cu")
		(net "P2E_CPU_SAS_RX_DN5")
	)
	(segment
		(start 55.7149 -27.9019)
		(end 52.7558 -24.9428)
		(width 0.1143)
		(layer "In9.Cu")
		(net "P2E_CPU_SAS_RX_DN5")
	)
	(segment
		(start 46.933612 -11.703812)
		(end 44.408852 -11.703812)
		(width 0.1143)
		(layer "In9.Cu")
		(net "P2E_CPU_SAS_RX_DN5")
	)
	(segment
		(start 43.702986 -10.997946)
		(end 43.702986 -10.545318)
		(width 0.1143)
		(layer "In9.Cu")
		(net "P2E_CPU_SAS_RX_DN5")
	)
	(segment
		(start 59.9186 -40.940736)
		(end 59.9186 -37.1094)
		(width 0.1143)
		(layer "In9.Cu")
		(net "P2E_CPU_SAS_RX_DN5")
	)
	(segment
		(start 78.0034 -52.3494)
		(end 77.6605 -52.3494)
		(width 0.1016)
		(layer "In9.Cu")
		(net "P2E_CPU_SAS_RX_DN5")
	)
	(segment
		(start 66.007996 -49.66335)
		(end 64.80175 -48.457104)
		(width 0.1143)
		(layer "In9.Cu")
		(net "P2E_CPU_SAS_RX_DN5")
	)
	(segment
		(start 84.455 -48.547528)
		(end 84.310728 -48.6918)
		(width 0.1016)
		(layer "In9.Cu")
		(net "P2E_CPU_SAS_RX_DN5")
	)
	(segment
		(start 52.7558 -24.9428)
		(end 52.7558 -17.5514)
		(width 0.1143)
		(layer "In9.Cu")
		(net "P2E_CPU_SAS_RX_DN5")
	)
	(segment
		(start 43.702986 -10.545318)
		(end 43.408346 -10.250678)
		(width 0.1143)
		(layer "In9.Cu")
		(net "P2E_CPU_SAS_RX_DN5")
	)
	(segment
		(start 83.768184 -52.02047)
		(end 83.342226 -52.446428)
		(width 0.1016)
		(layer "In9.Cu")
		(net "P2E_CPU_SAS_RX_DN5")
	)
	(segment
		(start 64.80175 -48.457104)
		(end 64.80175 -47.438818)
		(width 0.1143)
		(layer "In9.Cu")
		(net "P2E_CPU_SAS_RX_DN5")
	)
	(segment
		(start 52.7558 -17.5514)
		(end 54.0385 -16.2687)
		(width 0.1143)
		(layer "In9.Cu")
		(net "P2E_CPU_SAS_RX_DN5")
	)
	(segment
		(start 70.477126 -49.8856)
		(end 68.115942 -49.8856)
		(width 0.1143)
		(layer "In9.Cu")
		(net "P2E_CPU_SAS_RX_DN5")
	)
	(segment
		(start 62.095634 -43.11777)
		(end 59.9186 -40.940736)
		(width 0.1143)
		(layer "In9.Cu")
		(net "P2E_CPU_SAS_RX_DN5")
	)
	(segment
		(start 47.9552 -12.7254)
		(end 46.933612 -11.703812)
		(width 0.1143)
		(layer "In9.Cu")
		(net "P2E_CPU_SAS_RX_DN5")
	)
	(segment
		(start 82.414872 -52.0954)
		(end 78.2574 -52.0954)
		(width 0.1016)
		(layer "In9.Cu")
		(net "P2E_CPU_SAS_RX_DN5")
	)
	(segment
		(start 77.6605 -52.3494)
		(end 77.597 -52.4129)
		(width 0.1016)
		(layer "In9.Cu")
		(net "P2E_CPU_SAS_RX_DN5")
	)
	(segment
		(start 67.893692 -49.66335)
		(end 66.007996 -49.66335)
		(width 0.1143)
		(layer "In9.Cu")
		(net "P2E_CPU_SAS_RX_DN5")
	)
	(segment
		(start 84.598764 -48.547528)
		(end 84.455 -48.547528)
		(width 0.1016)
		(layer "In9.Cu")
		(net "P2E_CPU_SAS_RX_DN5")
	)
	(segment
		(start 77.091794 -52.4129)
		(end 76.825094 -52.1462)
		(width 0.1143)
		(layer "In9.Cu")
		(net "P2E_CPU_SAS_RX_DN5")
	)
	(segment
		(start 64.80175 -47.438818)
		(end 62.095634 -44.732702)
		(width 0.1143)
		(layer "In9.Cu")
		(net "P2E_CPU_SAS_RX_DN5")
	)
	(segment
		(start 84.310728 -48.853344)
		(end 84.4042 -48.946816)
		(width 0.1016)
		(layer "In9.Cu")
		(net "P2E_CPU_SAS_RX_DN5")
	)
	(segment
		(start 44.408852 -11.703812)
		(end 43.702986 -10.997946)
		(width 0.1143)
		(layer "In9.Cu")
		(net "P2E_CPU_SAS_RX_DN5")
	)
	(segment
		(start 68.115942 -49.8856)
		(end 67.893692 -49.66335)
		(width 0.1143)
		(layer "In9.Cu")
		(net "P2E_CPU_SAS_RX_DN5")
	)
	(segment
		(start 59.9186 -37.1094)
		(end 60.310776 -36.717224)
		(width 0.1143)
		(layer "In9.Cu")
		(net "P2E_CPU_SAS_RX_DN5")
	)
	(segment
		(start 82.7659 -52.446428)
		(end 82.414872 -52.0954)
		(width 0.1016)
		(layer "In9.Cu")
		(net "P2E_CPU_SAS_RX_DN5")
	)
	(segment
		(start 60.310776 -36.717224)
		(end 60.310776 -33.922716)
		(width 0.1143)
		(layer "In9.Cu")
		(net "P2E_CPU_SAS_RX_DN5")
	)
	(segment
		(start 72.737726 -52.1462)
		(end 70.477126 -49.8856)
		(width 0.1143)
		(layer "In9.Cu")
		(net "P2E_CPU_SAS_RX_DN5")
	)
	(segment
		(start 60.310776 -33.922716)
		(end 55.7149 -29.32684)
		(width 0.1143)
		(layer "In9.Cu")
		(net "P2E_CPU_SAS_RX_DN5")
	)
	(segment
		(start 77.597 -52.4129)
		(end 77.091794 -52.4129)
		(width 0.1143)
		(layer "In9.Cu")
		(net "P2E_CPU_SAS_RX_DN5")
	)
	(segment
		(start 55.7149 -29.32684)
		(end 55.7149 -27.9019)
		(width 0.1143)
		(layer "In9.Cu")
		(net "P2E_CPU_SAS_RX_DN5")
	)
	(segment
		(start 54.0385 -14.056106)
		(end 52.707794 -12.7254)
		(width 0.1143)
		(layer "In9.Cu")
		(net "P2E_CPU_SAS_RX_DN5")
	)
	(segment
		(start 54.0385 -16.2687)
		(end 54.0385 -14.056106)
		(width 0.1143)
		(layer "In9.Cu")
		(net "P2E_CPU_SAS_RX_DN5")
	)
	(segment
		(start 84.4042 -48.946816)
		(end 84.4042 -50.785522)
		(width 0.1016)
		(layer "In9.Cu")
		(net "P2E_CPU_SAS_RX_DN5")
	)
	(segment
		(start 84.4042 -50.785522)
		(end 83.768184 -51.421538)
		(width 0.1016)
		(layer "In9.Cu")
		(net "P2E_CPU_SAS_RX_DN5")
	)
	(segment
		(start 84.163408 -48.783494)
		(end 83.812888 -49.134014)
		(width 0.1397)
		(layer "F.Cu")
		(net "P2E_CPU_SAS_RX_DP4")
	)
	(segment
		(start 48.021494 -9.944354)
		(end 48.327818 -10.250678)
		(width 0.1397)
		(layer "F.Cu")
		(net "P2E_CPU_SAS_RX_DP4")
	)
	(segment
		(start 48.349916 -8.447278)
		(end 48.021494 -8.7757)
		(width 0.1397)
		(layer "F.Cu")
		(net "P2E_CPU_SAS_RX_DP4")
	)
	(segment
		(start 48.021494 -8.7757)
		(end 48.021494 -9.944354)
		(width 0.1397)
		(layer "F.Cu")
		(net "P2E_CPU_SAS_RX_DP4")
	)
	(segment
		(start 83.812888 -49.134014)
		(end 83.812888 -49.163986)
		(width 0.1397)
		(layer "F.Cu")
		(net "P2E_CPU_SAS_RX_DP4")
	)
	(segment
		(start 48.349916 -6.195568)
		(end 48.349916 -8.447278)
		(width 0.1397)
		(layer "F.Cu")
		(net "P2E_CPU_SAS_RX_DP4")
	)
	(via
		(at 48.327818 -10.250678)
		(size 0.508)
		(drill 0.254)
		(layers "F.Cu" "B.Cu")
		(net "P2E_CPU_SAS_RX_DP4")
	)
	(via
		(at 83.812888 -49.163986)
		(size 0.4318)
		(drill 0.2032)
		(layers "F.Cu" "B.Cu")
		(net "P2E_CPU_SAS_RX_DP4")
	)
	(segment
		(start 60.567062 -29.579062)
		(end 60.132214 -29.579062)
		(width 0.1143)
		(layer "In9.Cu")
		(net "P2E_CPU_SAS_RX_DP4")
	)
	(segment
		(start 81.07426 -50.718212)
		(end 80.76946 -50.718212)
		(width 0.1016)
		(layer "In9.Cu")
		(net "P2E_CPU_SAS_RX_DP4")
	)
	(segment
		(start 81.17332 -50.817272)
		(end 81.07426 -50.718212)
		(width 0.1016)
		(layer "In9.Cu")
		(net "P2E_CPU_SAS_RX_DP4")
	)
	(segment
		(start 55.6006 -10.3378)
		(end 54.498494 -10.3378)
		(width 0.1143)
		(layer "In9.Cu")
		(net "P2E_CPU_SAS_RX_DP4")
	)
	(segment
		(start 55.3466 -13.158216)
		(end 56.5912 -11.91387)
		(width 0.1143)
		(layer "In9.Cu")
		(net "P2E_CPU_SAS_RX_DP4")
	)
	(segment
		(start 83.444588 -49.532286)
		(end 83.444588 -49.905666)
		(width 0.1016)
		(layer "In9.Cu")
		(net "P2E_CPU_SAS_RX_DP4")
	)
	(segment
		(start 80.6704 -50.817272)
		(end 80.3656 -50.817272)
		(width 0.1016)
		(layer "In9.Cu")
		(net "P2E_CPU_SAS_RX_DP4")
	)
	(segment
		(start 54.0766 -11.216894)
		(end 53.850794 -11.4427)
		(width 0.1143)
		(layer "In9.Cu")
		(net "P2E_CPU_SAS_RX_DP4")
	)
	(segment
		(start 48.006 -10.572496)
		(end 48.327818 -10.250678)
		(width 0.1143)
		(layer "In9.Cu")
		(net "P2E_CPU_SAS_RX_DP4")
	)
	(segment
		(start 55.8292 -26.025094)
		(end 55.8292 -17.145)
		(width 0.1143)
		(layer "In9.Cu")
		(net "P2E_CPU_SAS_RX_DP4")
	)
	(segment
		(start 61.084714 -30.096714)
		(end 60.567062 -29.579062)
		(width 0.1143)
		(layer "In9.Cu")
		(net "P2E_CPU_SAS_RX_DP4")
	)
	(segment
		(start 62.105032 -34.190432)
		(end 61.593476 -33.678876)
		(width 0.1143)
		(layer "In9.Cu")
		(net "P2E_CPU_SAS_RX_DP4")
	)
	(segment
		(start 56.9976 -28.795218)
		(end 56.9976 -27.193494)
		(width 0.1143)
		(layer "In9.Cu")
		(net "P2E_CPU_SAS_RX_DP4")
	)
	(segment
		(start 64.46647 -45.2882)
		(end 63.7794 -44.60113)
		(width 0.1143)
		(layer "In9.Cu")
		(net "P2E_CPU_SAS_RX_DP4")
	)
	(segment
		(start 83.167728 -50.182526)
		(end 82.956146 -50.182526)
		(width 0.1016)
		(layer "In9.Cu")
		(net "P2E_CPU_SAS_RX_DP4")
	)
	(segment
		(start 71.008748 -48.6029)
		(end 68.647564 -48.6029)
		(width 0.1143)
		(layer "In9.Cu")
		(net "P2E_CPU_SAS_RX_DP4")
	)
	(segment
		(start 54.498494 -10.3378)
		(end 54.0766 -10.759694)
		(width 0.1143)
		(layer "In9.Cu")
		(net "P2E_CPU_SAS_RX_DP4")
	)
	(segment
		(start 65.332864 -45.2882)
		(end 64.46647 -45.2882)
		(width 0.1143)
		(layer "In9.Cu")
		(net "P2E_CPU_SAS_RX_DP4")
	)
	(segment
		(start 61.593476 -35.6108)
		(end 62.105032 -35.099244)
		(width 0.1143)
		(layer "In9.Cu")
		(net "P2E_CPU_SAS_RX_DP4")
	)
	(segment
		(start 59.129422 -28.141422)
		(end 58.694574 -28.141422)
		(width 0.1143)
		(layer "In9.Cu")
		(net "P2E_CPU_SAS_RX_DP4")
	)
	(segment
		(start 58.87593 -30.673548)
		(end 58.552334 -30.349952)
		(width 0.1143)
		(layer "In9.Cu")
		(net "P2E_CPU_SAS_RX_DP4")
	)
	(segment
		(start 56.5912 -11.91387)
		(end 56.5912 -11.3284)
		(width 0.1143)
		(layer "In9.Cu")
		(net "P2E_CPU_SAS_RX_DP4")
	)
	(segment
		(start 58.552334 -30.188408)
		(end 59.647074 -29.093922)
		(width 0.1143)
		(layer "In9.Cu")
		(net "P2E_CPU_SAS_RX_DP4")
	)
	(segment
		(start 62.105032 -32.357568)
		(end 62.105032 -31.892494)
		(width 0.1143)
		(layer "In9.Cu")
		(net "P2E_CPU_SAS_RX_DP4")
	)
	(segment
		(start 80.76946 -50.718212)
		(end 80.6704 -50.817272)
		(width 0.1016)
		(layer "In9.Cu")
		(net "P2E_CPU_SAS_RX_DP4")
	)
	(segment
		(start 59.989974 -31.787592)
		(end 59.989974 -31.626048)
		(width 0.1143)
		(layer "In9.Cu")
		(net "P2E_CPU_SAS_RX_DP4")
	)
	(segment
		(start 80.2894 -50.753772)
		(end 73.15962 -50.753772)
		(width 0.1143)
		(layer "In9.Cu")
		(net "P2E_CPU_SAS_RX_DP4")
	)
	(segment
		(start 61.2013 -37.641276)
		(end 61.593476 -37.2491)
		(width 0.1143)
		(layer "In9.Cu")
		(net "P2E_CPU_SAS_RX_DP4")
	)
	(segment
		(start 59.989974 -31.626048)
		(end 61.084714 -30.531562)
		(width 0.1143)
		(layer "In9.Cu")
		(net "P2E_CPU_SAS_RX_DP4")
	)
	(segment
		(start 57.43829 -29.235908)
		(end 56.9976 -28.795218)
		(width 0.1143)
		(layer "In9.Cu")
		(net "P2E_CPU_SAS_RX_DP4")
	)
	(segment
		(start 61.2013 -40.409114)
		(end 61.2013 -37.641276)
		(width 0.1143)
		(layer "In9.Cu")
		(net "P2E_CPU_SAS_RX_DP4")
	)
	(segment
		(start 56.9976 -27.193494)
		(end 55.8292 -26.025094)
		(width 0.1143)
		(layer "In9.Cu")
		(net "P2E_CPU_SAS_RX_DP4")
	)
	(segment
		(start 82.3214 -50.817272)
		(end 81.17332 -50.817272)
		(width 0.1016)
		(layer "In9.Cu")
		(net "P2E_CPU_SAS_RX_DP4")
	)
	(segment
		(start 80.3021 -50.753772)
		(end 80.2894 -50.753772)
		(width 0.1016)
		(layer "In9.Cu")
		(net "P2E_CPU_SAS_RX_DP4")
	)
	(segment
		(start 68.647564 -48.6029)
		(end 65.332864 -45.2882)
		(width 0.1143)
		(layer "In9.Cu")
		(net "P2E_CPU_SAS_RX_DP4")
	)
	(segment
		(start 82.956146 -50.182526)
		(end 82.3214 -50.817272)
		(width 0.1016)
		(layer "In9.Cu")
		(net "P2E_CPU_SAS_RX_DP4")
	)
	(segment
		(start 55.8292 -17.145)
		(end 55.3466 -16.6624)
		(width 0.1143)
		(layer "In9.Cu")
		(net "P2E_CPU_SAS_RX_DP4")
	)
	(segment
		(start 60.206382 -32.004)
		(end 59.989974 -31.787592)
		(width 0.1143)
		(layer "In9.Cu")
		(net "P2E_CPU_SAS_RX_DP4")
	)
	(segment
		(start 63.7794 -44.60113)
		(end 63.7794 -42.987214)
		(width 0.1143)
		(layer "In9.Cu")
		(net "P2E_CPU_SAS_RX_DP4")
	)
	(segment
		(start 58.552334 -30.349952)
		(end 58.552334 -30.188408)
		(width 0.1143)
		(layer "In9.Cu")
		(net "P2E_CPU_SAS_RX_DP4")
	)
	(segment
		(start 63.7794 -42.987214)
		(end 61.2013 -40.409114)
		(width 0.1143)
		(layer "In9.Cu")
		(net "P2E_CPU_SAS_RX_DP4")
	)
	(segment
		(start 61.708538 -31.496)
		(end 60.9854 -31.496)
		(width 0.1143)
		(layer "In9.Cu")
		(net "P2E_CPU_SAS_RX_DP4")
	)
	(segment
		(start 73.15962 -50.753772)
		(end 71.008748 -48.6029)
		(width 0.1143)
		(layer "In9.Cu")
		(net "P2E_CPU_SAS_RX_DP4")
	)
	(segment
		(start 54.0766 -10.759694)
		(end 54.0766 -11.216894)
		(width 0.1143)
		(layer "In9.Cu")
		(net "P2E_CPU_SAS_RX_DP4")
	)
	(segment
		(start 61.084714 -30.531562)
		(end 61.084714 -30.096714)
		(width 0.1143)
		(layer "In9.Cu")
		(net "P2E_CPU_SAS_RX_DP4")
	)
	(segment
		(start 59.647074 -29.093922)
		(end 59.647074 -28.659074)
		(width 0.1143)
		(layer "In9.Cu")
		(net "P2E_CPU_SAS_RX_DP4")
	)
	(segment
		(start 58.694574 -28.141422)
		(end 57.599834 -29.235908)
		(width 0.1143)
		(layer "In9.Cu")
		(net "P2E_CPU_SAS_RX_DP4")
	)
	(segment
		(start 52.626006 -11.4427)
		(end 52.11699 -10.933684)
		(width 0.1143)
		(layer "In9.Cu")
		(net "P2E_CPU_SAS_RX_DP4")
	)
	(segment
		(start 80.3656 -50.817272)
		(end 80.3021 -50.753772)
		(width 0.1016)
		(layer "In9.Cu")
		(net "P2E_CPU_SAS_RX_DP4")
	)
	(segment
		(start 57.599834 -29.235908)
		(end 57.43829 -29.235908)
		(width 0.1143)
		(layer "In9.Cu")
		(net "P2E_CPU_SAS_RX_DP4")
	)
	(segment
		(start 53.850794 -11.4427)
		(end 52.626006 -11.4427)
		(width 0.1143)
		(layer "In9.Cu")
		(net "P2E_CPU_SAS_RX_DP4")
	)
	(segment
		(start 56.5912 -11.3284)
		(end 55.6006 -10.3378)
		(width 0.1143)
		(layer "In9.Cu")
		(net "P2E_CPU_SAS_RX_DP4")
	)
	(segment
		(start 60.132214 -29.579062)
		(end 59.037474 -30.673548)
		(width 0.1143)
		(layer "In9.Cu")
		(net "P2E_CPU_SAS_RX_DP4")
	)
	(segment
		(start 59.037474 -30.673548)
		(end 58.87593 -30.673548)
		(width 0.1143)
		(layer "In9.Cu")
		(net "P2E_CPU_SAS_RX_DP4")
	)
	(segment
		(start 61.593476 -32.869124)
		(end 62.105032 -32.357568)
		(width 0.1143)
		(layer "In9.Cu")
		(net "P2E_CPU_SAS_RX_DP4")
	)
	(segment
		(start 62.105032 -35.099244)
		(end 62.105032 -34.190432)
		(width 0.1143)
		(layer "In9.Cu")
		(net "P2E_CPU_SAS_RX_DP4")
	)
	(segment
		(start 62.105032 -31.892494)
		(end 61.708538 -31.496)
		(width 0.1143)
		(layer "In9.Cu")
		(net "P2E_CPU_SAS_RX_DP4")
	)
	(segment
		(start 61.593476 -33.678876)
		(end 61.593476 -32.869124)
		(width 0.1143)
		(layer "In9.Cu")
		(net "P2E_CPU_SAS_RX_DP4")
	)
	(segment
		(start 60.9854 -31.496)
		(end 60.4774 -32.004)
		(width 0.1143)
		(layer "In9.Cu")
		(net "P2E_CPU_SAS_RX_DP4")
	)
	(segment
		(start 48.006 -10.759694)
		(end 48.006 -10.572496)
		(width 0.1143)
		(layer "In9.Cu")
		(net "P2E_CPU_SAS_RX_DP4")
	)
	(segment
		(start 55.3466 -16.6624)
		(end 55.3466 -13.158216)
		(width 0.1143)
		(layer "In9.Cu")
		(net "P2E_CPU_SAS_RX_DP4")
	)
	(segment
		(start 61.593476 -37.2491)
		(end 61.593476 -35.6108)
		(width 0.1143)
		(layer "In9.Cu")
		(net "P2E_CPU_SAS_RX_DP4")
	)
	(segment
		(start 60.4774 -32.004)
		(end 60.206382 -32.004)
		(width 0.1143)
		(layer "In9.Cu")
		(net "P2E_CPU_SAS_RX_DP4")
	)
	(segment
		(start 83.812888 -49.163986)
		(end 83.444588 -49.532286)
		(width 0.1016)
		(layer "In9.Cu")
		(net "P2E_CPU_SAS_RX_DP4")
	)
	(segment
		(start 83.444588 -49.905666)
		(end 83.167728 -50.182526)
		(width 0.1016)
		(layer "In9.Cu")
		(net "P2E_CPU_SAS_RX_DP4")
	)
	(segment
		(start 52.11699 -10.933684)
		(end 48.17999 -10.933684)
		(width 0.1143)
		(layer "In9.Cu")
		(net "P2E_CPU_SAS_RX_DP4")
	)
	(segment
		(start 48.17999 -10.933684)
		(end 48.006 -10.759694)
		(width 0.1143)
		(layer "In9.Cu")
		(net "P2E_CPU_SAS_RX_DP4")
	)
	(segment
		(start 59.647074 -28.659074)
		(end 59.129422 -28.141422)
		(width 0.1143)
		(layer "In9.Cu")
		(net "P2E_CPU_SAS_RX_DP4")
	)
	(segment
		(start 84.163408 -49.545494)
		(end 84.138008 -49.545494)
		(width 0.1397)
		(layer "F.Cu")
		(net "P2E_CPU_SAS_RX_DN4")
	)
	(segment
		(start 47.349918 -6.195568)
		(end 47.349918 -8.447024)
		(width 0.1397)
		(layer "F.Cu")
		(net "P2E_CPU_SAS_RX_DN4")
	)
	(segment
		(start 47.349918 -8.447024)
		(end 47.678594 -8.7757)
		(width 0.1397)
		(layer "F.Cu")
		(net "P2E_CPU_SAS_RX_DN4")
	)
	(segment
		(start 47.678594 -8.7757)
		(end 47.678594 -9.980422)
		(width 0.1397)
		(layer "F.Cu")
		(net "P2E_CPU_SAS_RX_DN4")
	)
	(segment
		(start 47.678594 -9.980422)
		(end 47.408338 -10.250678)
		(width 0.1397)
		(layer "F.Cu")
		(net "P2E_CPU_SAS_RX_DN4")
	)
	(segment
		(start 84.138008 -49.545494)
		(end 83.812888 -49.870614)
		(width 0.1397)
		(layer "F.Cu")
		(net "P2E_CPU_SAS_RX_DN4")
	)
	(segment
		(start 83.812888 -49.870614)
		(end 83.812888 -49.8856)
		(width 0.1397)
		(layer "F.Cu")
		(net "P2E_CPU_SAS_RX_DN4")
	)
	(via
		(at 83.812888 -49.8856)
		(size 0.4318)
		(drill 0.2032)
		(layers "F.Cu" "B.Cu")
		(net "P2E_CPU_SAS_RX_DN4")
	)
	(via
		(at 47.408338 -10.250678)
		(size 0.508)
		(drill 0.254)
		(layers "F.Cu" "B.Cu")
		(net "P2E_CPU_SAS_RX_DN4")
	)
	(segment
		(start 83.252056 -50.385726)
		(end 83.040474 -50.385726)
		(width 0.1016)
		(layer "In9.Cu")
		(net "P2E_CPU_SAS_RX_DN4")
	)
	(segment
		(start 63.4492 -43.12412)
		(end 60.8711 -40.54602)
		(width 0.1143)
		(layer "In9.Cu")
		(net "P2E_CPU_SAS_RX_DN4")
	)
	(segment
		(start 60.754514 -30.23362)
		(end 60.430156 -29.909262)
		(width 0.1143)
		(layer "In9.Cu")
		(net "P2E_CPU_SAS_RX_DN4")
	)
	(segment
		(start 55.0164 -13.02131)
		(end 55.507128 -12.530328)
		(width 0.1143)
		(layer "In9.Cu")
		(net "P2E_CPU_SAS_RX_DN4")
	)
	(segment
		(start 48.043084 -11.263884)
		(end 47.6758 -10.8966)
		(width 0.1143)
		(layer "In9.Cu")
		(net "P2E_CPU_SAS_RX_DN4")
	)
	(segment
		(start 58.992516 -28.471622)
		(end 58.83148 -28.471622)
		(width 0.1143)
		(layer "In9.Cu")
		(net "P2E_CPU_SAS_RX_DN4")
	)
	(segment
		(start 83.752182 -49.8856)
		(end 83.252056 -50.385726)
		(width 0.1016)
		(layer "In9.Cu")
		(net "P2E_CPU_SAS_RX_DN4")
	)
	(segment
		(start 58.222134 -30.486858)
		(end 58.222134 -30.051502)
		(width 0.1143)
		(layer "In9.Cu")
		(net "P2E_CPU_SAS_RX_DN4")
	)
	(segment
		(start 59.316874 -28.957016)
		(end 59.316874 -28.79598)
		(width 0.1143)
		(layer "In9.Cu")
		(net "P2E_CPU_SAS_RX_DN4")
	)
	(segment
		(start 55.499 -17.281906)
		(end 55.0164 -16.799306)
		(width 0.1143)
		(layer "In9.Cu")
		(net "P2E_CPU_SAS_RX_DN4")
	)
	(segment
		(start 59.659774 -31.489142)
		(end 60.754514 -30.394656)
		(width 0.1143)
		(layer "In9.Cu")
		(net "P2E_CPU_SAS_RX_DN4")
	)
	(segment
		(start 60.069476 -32.3342)
		(end 59.659774 -31.924498)
		(width 0.1143)
		(layer "In9.Cu")
		(net "P2E_CPU_SAS_RX_DN4")
	)
	(segment
		(start 61.774832 -32.0294)
		(end 61.571632 -31.8262)
		(width 0.1143)
		(layer "In9.Cu")
		(net "P2E_CPU_SAS_RX_DN4")
	)
	(segment
		(start 80.3656 -51.020472)
		(end 80.3021 -51.083972)
		(width 0.1016)
		(layer "In9.Cu")
		(net "P2E_CPU_SAS_RX_DN4")
	)
	(segment
		(start 59.17438 -31.003748)
		(end 58.739024 -31.003748)
		(width 0.1143)
		(layer "In9.Cu")
		(net "P2E_CPU_SAS_RX_DN4")
	)
	(segment
		(start 63.4492 -44.738036)
		(end 63.4492 -43.12412)
		(width 0.1143)
		(layer "In9.Cu")
		(net "P2E_CPU_SAS_RX_DN4")
	)
	(segment
		(start 65.195958 -45.6184)
		(end 64.329564 -45.6184)
		(width 0.1143)
		(layer "In9.Cu")
		(net "P2E_CPU_SAS_RX_DN4")
	)
	(segment
		(start 61.26353 -32.731964)
		(end 61.774832 -32.220662)
		(width 0.1143)
		(layer "In9.Cu")
		(net "P2E_CPU_SAS_RX_DN4")
	)
	(segment
		(start 61.774832 -34.962338)
		(end 61.774832 -34.327338)
		(width 0.1143)
		(layer "In9.Cu")
		(net "P2E_CPU_SAS_RX_DN4")
	)
	(segment
		(start 61.263022 -32.86887)
		(end 61.263022 -32.731964)
		(width 0.1143)
		(layer "In9.Cu")
		(net "P2E_CPU_SAS_RX_DN4")
	)
	(segment
		(start 60.8711 -40.54602)
		(end 60.8711 -37.50437)
		(width 0.1143)
		(layer "In9.Cu")
		(net "P2E_CPU_SAS_RX_DN4")
	)
	(segment
		(start 54.6354 -10.668)
		(end 54.4068 -10.8966)
		(width 0.1143)
		(layer "In9.Cu")
		(net "P2E_CPU_SAS_RX_DN4")
	)
	(segment
		(start 54.4068 -11.3538)
		(end 53.9877 -11.7729)
		(width 0.1143)
		(layer "In9.Cu")
		(net "P2E_CPU_SAS_RX_DN4")
	)
	(segment
		(start 47.6758 -10.51814)
		(end 47.408338 -10.250678)
		(width 0.1143)
		(layer "In9.Cu")
		(net "P2E_CPU_SAS_RX_DN4")
	)
	(segment
		(start 55.499 -26.162)
		(end 55.499 -17.281906)
		(width 0.1143)
		(layer "In9.Cu")
		(net "P2E_CPU_SAS_RX_DN4")
	)
	(segment
		(start 59.316874 -28.79598)
		(end 58.992516 -28.471622)
		(width 0.1143)
		(layer "In9.Cu")
		(net "P2E_CPU_SAS_RX_DN4")
	)
	(segment
		(start 51.980084 -11.263884)
		(end 48.043084 -11.263884)
		(width 0.1143)
		(layer "In9.Cu")
		(net "P2E_CPU_SAS_RX_DN4")
	)
	(segment
		(start 61.263276 -32.869124)
		(end 61.263022 -32.86887)
		(width 0.1143)
		(layer "In9.Cu")
		(net "P2E_CPU_SAS_RX_DN4")
	)
	(segment
		(start 61.122306 -31.8262)
		(end 60.614306 -32.3342)
		(width 0.1143)
		(layer "In9.Cu")
		(net "P2E_CPU_SAS_RX_DN4")
	)
	(segment
		(start 83.812888 -49.8856)
		(end 83.752182 -49.8856)
		(width 0.1016)
		(layer "In9.Cu")
		(net "P2E_CPU_SAS_RX_DN4")
	)
	(segment
		(start 60.26912 -29.909262)
		(end 59.17438 -31.003748)
		(width 0.1143)
		(layer "In9.Cu")
		(net "P2E_CPU_SAS_RX_DN4")
	)
	(segment
		(start 54.4068 -10.8966)
		(end 54.4068 -11.3538)
		(width 0.1143)
		(layer "In9.Cu")
		(net "P2E_CPU_SAS_RX_DN4")
	)
	(segment
		(start 68.510658 -48.9331)
		(end 65.195958 -45.6184)
		(width 0.1143)
		(layer "In9.Cu")
		(net "P2E_CPU_SAS_RX_DN4")
	)
	(segment
		(start 61.263276 -35.473894)
		(end 61.774832 -34.962338)
		(width 0.1143)
		(layer "In9.Cu")
		(net "P2E_CPU_SAS_RX_DN4")
	)
	(segment
		(start 58.222134 -30.051502)
		(end 59.316874 -28.957016)
		(width 0.1143)
		(layer "In9.Cu")
		(net "P2E_CPU_SAS_RX_DN4")
	)
	(segment
		(start 56.6674 -28.932124)
		(end 56.6674 -27.3304)
		(width 0.1143)
		(layer "In9.Cu")
		(net "P2E_CPU_SAS_RX_DN4")
	)
	(segment
		(start 60.430156 -29.909262)
		(end 60.26912 -29.909262)
		(width 0.1143)
		(layer "In9.Cu")
		(net "P2E_CPU_SAS_RX_DN4")
	)
	(segment
		(start 58.739024 -31.003748)
		(end 58.222134 -30.486858)
		(width 0.1143)
		(layer "In9.Cu")
		(net "P2E_CPU_SAS_RX_DN4")
	)
	(segment
		(start 55.0164 -16.799306)
		(end 55.0164 -13.02131)
		(width 0.1143)
		(layer "In9.Cu")
		(net "P2E_CPU_SAS_RX_DN4")
	)
	(segment
		(start 47.6758 -10.8966)
		(end 47.6758 -10.51814)
		(width 0.1143)
		(layer "In9.Cu")
		(net "P2E_CPU_SAS_RX_DN4")
	)
	(segment
		(start 80.3021 -51.083972)
		(end 80.2894 -51.083972)
		(width 0.1016)
		(layer "In9.Cu")
		(net "P2E_CPU_SAS_RX_DN4")
	)
	(segment
		(start 57.73674 -29.566108)
		(end 57.301384 -29.566108)
		(width 0.1143)
		(layer "In9.Cu")
		(net "P2E_CPU_SAS_RX_DN4")
	)
	(segment
		(start 55.796688 -12.241276)
		(end 55.796688 -12.240768)
		(width 0.1143)
		(layer "In9.Cu")
		(net "P2E_CPU_SAS_RX_DN4")
	)
	(segment
		(start 60.754514 -30.394656)
		(end 60.754514 -30.23362)
		(width 0.1143)
		(layer "In9.Cu")
		(net "P2E_CPU_SAS_RX_DN4")
	)
	(segment
		(start 57.301384 -29.566108)
		(end 56.6674 -28.932124)
		(width 0.1143)
		(layer "In9.Cu")
		(net "P2E_CPU_SAS_RX_DN4")
	)
	(segment
		(start 55.507128 -12.530328)
		(end 55.796688 -12.241276)
		(width 0.1143)
		(layer "In9.Cu")
		(net "P2E_CPU_SAS_RX_DN4")
	)
	(segment
		(start 56.261 -11.776964)
		(end 56.261 -11.465306)
		(width 0.1143)
		(layer "In9.Cu")
		(net "P2E_CPU_SAS_RX_DN4")
	)
	(segment
		(start 59.659774 -31.924498)
		(end 59.659774 -31.489142)
		(width 0.1143)
		(layer "In9.Cu")
		(net "P2E_CPU_SAS_RX_DN4")
	)
	(segment
		(start 58.83148 -28.471622)
		(end 57.73674 -29.566108)
		(width 0.1143)
		(layer "In9.Cu")
		(net "P2E_CPU_SAS_RX_DN4")
	)
	(segment
		(start 83.040474 -50.385726)
		(end 82.405728 -51.020472)
		(width 0.1016)
		(layer "In9.Cu")
		(net "P2E_CPU_SAS_RX_DN4")
	)
	(segment
		(start 55.796688 -12.240768)
		(end 56.261 -11.776964)
		(width 0.1143)
		(layer "In9.Cu")
		(net "P2E_CPU_SAS_RX_DN4")
	)
	(segment
		(start 61.263276 -33.815782)
		(end 61.263276 -32.869124)
		(width 0.1143)
		(layer "In9.Cu")
		(net "P2E_CPU_SAS_RX_DN4")
	)
	(segment
		(start 53.9877 -11.7729)
		(end 52.4891 -11.7729)
		(width 0.1143)
		(layer "In9.Cu")
		(net "P2E_CPU_SAS_RX_DN4")
	)
	(segment
		(start 52.4891 -11.7729)
		(end 51.980084 -11.263884)
		(width 0.1143)
		(layer "In9.Cu")
		(net "P2E_CPU_SAS_RX_DN4")
	)
	(segment
		(start 61.263276 -37.112194)
		(end 61.263276 -35.473894)
		(width 0.1143)
		(layer "In9.Cu")
		(net "P2E_CPU_SAS_RX_DN4")
	)
	(segment
		(start 61.571632 -31.8262)
		(end 61.122306 -31.8262)
		(width 0.1143)
		(layer "In9.Cu")
		(net "P2E_CPU_SAS_RX_DN4")
	)
	(segment
		(start 55.463694 -10.668)
		(end 54.6354 -10.668)
		(width 0.1143)
		(layer "In9.Cu")
		(net "P2E_CPU_SAS_RX_DN4")
	)
	(segment
		(start 60.8711 -37.50437)
		(end 61.263276 -37.112194)
		(width 0.1143)
		(layer "In9.Cu")
		(net "P2E_CPU_SAS_RX_DN4")
	)
	(segment
		(start 70.871842 -48.9331)
		(end 68.510658 -48.9331)
		(width 0.1143)
		(layer "In9.Cu")
		(net "P2E_CPU_SAS_RX_DN4")
	)
	(segment
		(start 56.261 -11.465306)
		(end 55.463694 -10.668)
		(width 0.1143)
		(layer "In9.Cu")
		(net "P2E_CPU_SAS_RX_DN4")
	)
	(segment
		(start 64.329564 -45.6184)
		(end 63.4492 -44.738036)
		(width 0.1143)
		(layer "In9.Cu")
		(net "P2E_CPU_SAS_RX_DN4")
	)
	(segment
		(start 56.6674 -27.3304)
		(end 55.499 -26.162)
		(width 0.1143)
		(layer "In9.Cu")
		(net "P2E_CPU_SAS_RX_DN4")
	)
	(segment
		(start 73.022714 -51.083972)
		(end 70.871842 -48.9331)
		(width 0.1143)
		(layer "In9.Cu")
		(net "P2E_CPU_SAS_RX_DN4")
	)
	(segment
		(start 61.774832 -32.220662)
		(end 61.774832 -32.0294)
		(width 0.1143)
		(layer "In9.Cu")
		(net "P2E_CPU_SAS_RX_DN4")
	)
	(segment
		(start 61.774832 -34.327338)
		(end 61.263276 -33.815782)
		(width 0.1143)
		(layer "In9.Cu")
		(net "P2E_CPU_SAS_RX_DN4")
	)
	(segment
		(start 80.2894 -51.083972)
		(end 73.022714 -51.083972)
		(width 0.1143)
		(layer "In9.Cu")
		(net "P2E_CPU_SAS_RX_DN4")
	)
	(segment
		(start 82.405728 -51.020472)
		(end 80.3656 -51.020472)
		(width 0.1016)
		(layer "In9.Cu")
		(net "P2E_CPU_SAS_RX_DN4")
	)
	(segment
		(start 61.263022 -32.731964)
		(end 61.26353 -32.731964)
		(width 0.1143)
		(layer "In9.Cu")
		(net "P2E_CPU_SAS_RX_DN4")
	)
	(segment
		(start 60.614306 -32.3342)
		(end 60.069476 -32.3342)
		(width 0.1143)
		(layer "In9.Cu")
		(net "P2E_CPU_SAS_RX_DN4")
	)
	(segment
		(start 67.6529 -8.7503)
		(end 67.6529 -9.97712)
		(width 0.1397)
		(layer "F.Cu")
		(net "P2E_CPU_SAS_RX_DN3")
	)
	(segment
		(start 67.6529 -9.97712)
		(end 67.34556 -10.28446)
		(width 0.1397)
		(layer "F.Cu")
		(net "P2E_CPU_SAS_RX_DN3")
	)
	(segment
		(start 67.349878 -6.195568)
		(end 67.349878 -8.447278)
		(width 0.1397)
		(layer "F.Cu")
		(net "P2E_CPU_SAS_RX_DN3")
	)
	(segment
		(start 83.0199 -49.2506)
		(end 83.167474 -49.2506)
		(width 0.1397)
		(layer "F.Cu")
		(net "P2E_CPU_SAS_RX_DN3")
	)
	(segment
		(start 67.349878 -8.447278)
		(end 67.6529 -8.7503)
		(width 0.1397)
		(layer "F.Cu")
		(net "P2E_CPU_SAS_RX_DN3")
	)
	(segment
		(start 83.167474 -49.2506)
		(end 83.462368 -49.545494)
		(width 0.1397)
		(layer "F.Cu")
		(net "P2E_CPU_SAS_RX_DN3")
	)
	(via
		(at 67.34556 -10.28446)
		(size 0.508)
		(drill 0.254)
		(layers "F.Cu" "B.Cu")
		(net "P2E_CPU_SAS_RX_DN3")
	)
	(via
		(at 83.0199 -49.2506)
		(size 0.4318)
		(drill 0.2032)
		(layers "F.Cu" "B.Cu")
		(net "P2E_CPU_SAS_RX_DN3")
	)
	(segment
		(start 65.2526 -33.9344)
		(end 64.721232 -33.403032)
		(width 0.1143)
		(layer "In9.Cu")
		(net "P2E_CPU_SAS_RX_DN3")
	)
	(segment
		(start 82.719164 -49.178464)
		(end 82.520028 -49.3776)
		(width 0.1016)
		(layer "In9.Cu")
		(net "P2E_CPU_SAS_RX_DN3")
	)
	(segment
		(start 81.166716 -50.37328)
		(end 80.2894 -50.37328)
		(width 0.1016)
		(layer "In9.Cu")
		(net "P2E_CPU_SAS_RX_DN3")
	)
	(segment
		(start 82.947764 -49.178464)
		(end 82.719164 -49.178464)
		(width 0.1016)
		(layer "In9.Cu")
		(net "P2E_CPU_SAS_RX_DN3")
	)
	(segment
		(start 65.2526 -40.574722)
		(end 65.2526 -33.9344)
		(width 0.1143)
		(layer "In9.Cu")
		(net "P2E_CPU_SAS_RX_DN3")
	)
	(segment
		(start 64.721232 -33.403032)
		(end 64.721232 -22.654768)
		(width 0.1143)
		(layer "In9.Cu")
		(net "P2E_CPU_SAS_RX_DN3")
	)
	(segment
		(start 65.4558 -21.9202)
		(end 65.4558 -18.450306)
		(width 0.1143)
		(layer "In9.Cu")
		(net "P2E_CPU_SAS_RX_DN3")
	)
	(segment
		(start 64.721232 -22.654768)
		(end 65.4558 -21.9202)
		(width 0.1143)
		(layer "In9.Cu")
		(net "P2E_CPU_SAS_RX_DN3")
	)
	(segment
		(start 82.162396 -49.3776)
		(end 81.166716 -50.37328)
		(width 0.1016)
		(layer "In9.Cu")
		(net "P2E_CPU_SAS_RX_DN3")
	)
	(segment
		(start 65.4558 -18.450306)
		(end 63.039244 -16.03375)
		(width 0.1143)
		(layer "In9.Cu")
		(net "P2E_CPU_SAS_RX_DN3")
	)
	(segment
		(start 67.691 -10.6299)
		(end 67.34556 -10.28446)
		(width 0.1143)
		(layer "In9.Cu")
		(net "P2E_CPU_SAS_RX_DN3")
	)
	(segment
		(start 80.2894 -50.37328)
		(end 80.2259 -50.43678)
		(width 0.1016)
		(layer "In9.Cu")
		(net "P2E_CPU_SAS_RX_DN3")
	)
	(segment
		(start 70.881494 -43.2689)
		(end 67.946778 -43.2689)
		(width 0.1143)
		(layer "In9.Cu")
		(net "P2E_CPU_SAS_RX_DN3")
	)
	(segment
		(start 76.037694 -49.9872)
		(end 74.893932 -49.9872)
		(width 0.1143)
		(layer "In9.Cu")
		(net "P2E_CPU_SAS_RX_DN3")
	)
	(segment
		(start 63.039244 -16.03375)
		(end 62.535816 -16.03375)
		(width 0.1143)
		(layer "In9.Cu")
		(net "P2E_CPU_SAS_RX_DN3")
	)
	(segment
		(start 80.2132 -50.43678)
		(end 76.487274 -50.43678)
		(width 0.1143)
		(layer "In9.Cu")
		(net "P2E_CPU_SAS_RX_DN3")
	)
	(segment
		(start 82.520028 -49.3776)
		(end 82.162396 -49.3776)
		(width 0.1016)
		(layer "In9.Cu")
		(net "P2E_CPU_SAS_RX_DN3")
	)
	(segment
		(start 67.691 -10.8966)
		(end 67.691 -10.6299)
		(width 0.1143)
		(layer "In9.Cu")
		(net "P2E_CPU_SAS_RX_DN3")
	)
	(segment
		(start 66.4464 -12.1412)
		(end 67.691 -10.8966)
		(width 0.1143)
		(layer "In9.Cu")
		(net "P2E_CPU_SAS_RX_DN3")
	)
	(segment
		(start 83.0199 -49.2506)
		(end 82.947764 -49.178464)
		(width 0.1016)
		(layer "In9.Cu")
		(net "P2E_CPU_SAS_RX_DN3")
	)
	(segment
		(start 64.6684 -12.1412)
		(end 66.4464 -12.1412)
		(width 0.1143)
		(layer "In9.Cu")
		(net "P2E_CPU_SAS_RX_DN3")
	)
	(segment
		(start 62.535816 -16.03375)
		(end 62.07125 -15.569184)
		(width 0.1143)
		(layer "In9.Cu")
		(net "P2E_CPU_SAS_RX_DN3")
	)
	(segment
		(start 62.07125 -15.569184)
		(end 62.07125 -14.73835)
		(width 0.1143)
		(layer "In9.Cu")
		(net "P2E_CPU_SAS_RX_DN3")
	)
	(segment
		(start 62.07125 -14.73835)
		(end 64.6684 -12.1412)
		(width 0.1143)
		(layer "In9.Cu")
		(net "P2E_CPU_SAS_RX_DN3")
	)
	(segment
		(start 76.487274 -50.43678)
		(end 76.037694 -49.9872)
		(width 0.1143)
		(layer "In9.Cu")
		(net "P2E_CPU_SAS_RX_DN3")
	)
	(segment
		(start 73.4441 -45.831506)
		(end 70.881494 -43.2689)
		(width 0.1143)
		(layer "In9.Cu")
		(net "P2E_CPU_SAS_RX_DN3")
	)
	(segment
		(start 80.2259 -50.43678)
		(end 80.2132 -50.43678)
		(width 0.1016)
		(layer "In9.Cu")
		(net "P2E_CPU_SAS_RX_DN3")
	)
	(segment
		(start 67.946778 -43.2689)
		(end 65.2526 -40.574722)
		(width 0.1143)
		(layer "In9.Cu")
		(net "P2E_CPU_SAS_RX_DN3")
	)
	(segment
		(start 73.4441 -48.537368)
		(end 73.4441 -45.831506)
		(width 0.1143)
		(layer "In9.Cu")
		(net "P2E_CPU_SAS_RX_DN3")
	)
	(segment
		(start 74.893932 -49.9872)
		(end 73.4441 -48.537368)
		(width 0.1143)
		(layer "In9.Cu")
		(net "P2E_CPU_SAS_RX_DN3")
	)
	(segment
		(start 67.9958 -9.97712)
		(end 68.30314 -10.28446)
		(width 0.1397)
		(layer "F.Cu")
		(net "P2E_CPU_SAS_RX_DP3")
	)
	(segment
		(start 68.349876 -8.447024)
		(end 67.9958 -8.8011)
		(width 0.1397)
		(layer "F.Cu")
		(net "P2E_CPU_SAS_RX_DP3")
	)
	(segment
		(start 68.349876 -6.195568)
		(end 68.349876 -8.447024)
		(width 0.1397)
		(layer "F.Cu")
		(net "P2E_CPU_SAS_RX_DP3")
	)
	(segment
		(start 82.9437 -48.6664)
		(end 83.060794 -48.783494)
		(width 0.1397)
		(layer "F.Cu")
		(net "P2E_CPU_SAS_RX_DP3")
	)
	(segment
		(start 83.060794 -48.783494)
		(end 83.462368 -48.783494)
		(width 0.1397)
		(layer "F.Cu")
		(net "P2E_CPU_SAS_RX_DP3")
	)
	(segment
		(start 67.9958 -8.8011)
		(end 67.9958 -9.97712)
		(width 0.1397)
		(layer "F.Cu")
		(net "P2E_CPU_SAS_RX_DP3")
	)
	(via
		(at 68.30314 -10.28446)
		(size 0.508)
		(drill 0.254)
		(layers "F.Cu" "B.Cu")
		(net "P2E_CPU_SAS_RX_DP3")
	)
	(via
		(at 82.9437 -48.6664)
		(size 0.4318)
		(drill 0.2032)
		(layers "F.Cu" "B.Cu")
		(net "P2E_CPU_SAS_RX_DP3")
	)
	(segment
		(start 76.62418 -50.10658)
		(end 76.1746 -49.657)
		(width 0.1143)
		(layer "In9.Cu")
		(net "P2E_CPU_SAS_RX_DP3")
	)
	(segment
		(start 66.583306 -12.4714)
		(end 66.825876 -12.22883)
		(width 0.1143)
		(layer "In9.Cu")
		(net "P2E_CPU_SAS_RX_DP3")
	)
	(segment
		(start 65.77076 -12.68476)
		(end 65.98412 -12.4714)
		(width 0.1143)
		(layer "In9.Cu")
		(net "P2E_CPU_SAS_RX_DP3")
	)
	(segment
		(start 79.65694 -49.89322)
		(end 79.31404 -49.89322)
		(width 0.1143)
		(layer "In9.Cu")
		(net "P2E_CPU_SAS_RX_DP3")
	)
	(segment
		(start 81.082388 -50.17008)
		(end 80.2894 -50.17008)
		(width 0.1016)
		(layer "In9.Cu")
		(net "P2E_CPU_SAS_RX_DP3")
	)
	(segment
		(start 82.078068 -49.1744)
		(end 81.082388 -50.17008)
		(width 0.1016)
		(layer "In9.Cu")
		(net "P2E_CPU_SAS_RX_DP3")
	)
	(segment
		(start 73.7743 -48.400462)
		(end 73.7743 -45.6946)
		(width 0.1143)
		(layer "In9.Cu")
		(net "P2E_CPU_SAS_RX_DP3")
	)
	(segment
		(start 62.672722 -15.70355)
		(end 62.40145 -15.432278)
		(width 0.1143)
		(layer "In9.Cu")
		(net "P2E_CPU_SAS_RX_DP3")
	)
	(segment
		(start 64.805306 -12.4714)
		(end 65.2145 -12.4714)
		(width 0.1143)
		(layer "In9.Cu")
		(net "P2E_CPU_SAS_RX_DP3")
	)
	(segment
		(start 67.369944 -11.684762)
		(end 68.0212 -11.033506)
		(width 0.1143)
		(layer "In9.Cu")
		(net "P2E_CPU_SAS_RX_DP3")
	)
	(segment
		(start 75.030838 -49.657)
		(end 73.7743 -48.400462)
		(width 0.1143)
		(layer "In9.Cu")
		(net "P2E_CPU_SAS_RX_DP3")
	)
	(segment
		(start 73.7743 -45.6946)
		(end 71.0184 -42.9387)
		(width 0.1143)
		(layer "In9.Cu")
		(net "P2E_CPU_SAS_RX_DP3")
	)
	(segment
		(start 62.40145 -15.432278)
		(end 62.40145 -14.875256)
		(width 0.1143)
		(layer "In9.Cu")
		(net "P2E_CPU_SAS_RX_DP3")
	)
	(segment
		(start 76.1746 -49.657)
		(end 75.030838 -49.657)
		(width 0.1143)
		(layer "In9.Cu")
		(net "P2E_CPU_SAS_RX_DP3")
	)
	(segment
		(start 65.98412 -12.4714)
		(end 66.583306 -12.4714)
		(width 0.1143)
		(layer "In9.Cu")
		(net "P2E_CPU_SAS_RX_DP3")
	)
	(segment
		(start 82.9437 -48.6664)
		(end 82.4357 -49.1744)
		(width 0.1016)
		(layer "In9.Cu")
		(net "P2E_CPU_SAS_RX_DP3")
	)
	(segment
		(start 65.786 -22.057106)
		(end 65.786 -18.3134)
		(width 0.1143)
		(layer "In9.Cu")
		(net "P2E_CPU_SAS_RX_DP3")
	)
	(segment
		(start 80.2894 -50.17008)
		(end 80.2259 -50.10658)
		(width 0.1016)
		(layer "In9.Cu")
		(net "P2E_CPU_SAS_RX_DP3")
	)
	(segment
		(start 68.0212 -11.033506)
		(end 68.0212 -10.5664)
		(width 0.1143)
		(layer "In9.Cu")
		(net "P2E_CPU_SAS_RX_DP3")
	)
	(segment
		(start 68.083684 -42.9387)
		(end 65.5828 -40.437816)
		(width 0.1143)
		(layer "In9.Cu")
		(net "P2E_CPU_SAS_RX_DP3")
	)
	(segment
		(start 79.8703 -50.10658)
		(end 79.65694 -49.89322)
		(width 0.1143)
		(layer "In9.Cu")
		(net "P2E_CPU_SAS_RX_DP3")
	)
	(segment
		(start 82.4357 -49.1744)
		(end 82.078068 -49.1744)
		(width 0.1016)
		(layer "In9.Cu")
		(net "P2E_CPU_SAS_RX_DP3")
	)
	(segment
		(start 67.369944 -11.986514)
		(end 67.369944 -11.684762)
		(width 0.1143)
		(layer "In9.Cu")
		(net "P2E_CPU_SAS_RX_DP3")
	)
	(segment
		(start 65.2145 -12.4714)
		(end 65.42786 -12.68476)
		(width 0.1143)
		(layer "In9.Cu")
		(net "P2E_CPU_SAS_RX_DP3")
	)
	(segment
		(start 65.051432 -33.266126)
		(end 65.051432 -22.791674)
		(width 0.1143)
		(layer "In9.Cu")
		(net "P2E_CPU_SAS_RX_DP3")
	)
	(segment
		(start 66.825876 -12.22883)
		(end 67.127628 -12.22883)
		(width 0.1143)
		(layer "In9.Cu")
		(net "P2E_CPU_SAS_RX_DP3")
	)
	(segment
		(start 63.17615 -15.70355)
		(end 62.672722 -15.70355)
		(width 0.1143)
		(layer "In9.Cu")
		(net "P2E_CPU_SAS_RX_DP3")
	)
	(segment
		(start 65.5828 -40.437816)
		(end 65.5828 -33.797494)
		(width 0.1143)
		(layer "In9.Cu")
		(net "P2E_CPU_SAS_RX_DP3")
	)
	(segment
		(start 79.31404 -49.89322)
		(end 79.10068 -50.10658)
		(width 0.1143)
		(layer "In9.Cu")
		(net "P2E_CPU_SAS_RX_DP3")
	)
	(segment
		(start 65.5828 -33.797494)
		(end 65.051432 -33.266126)
		(width 0.1143)
		(layer "In9.Cu")
		(net "P2E_CPU_SAS_RX_DP3")
	)
	(segment
		(start 80.2132 -50.10658)
		(end 79.8703 -50.10658)
		(width 0.1143)
		(layer "In9.Cu")
		(net "P2E_CPU_SAS_RX_DP3")
	)
	(segment
		(start 65.051432 -22.791674)
		(end 65.786 -22.057106)
		(width 0.1143)
		(layer "In9.Cu")
		(net "P2E_CPU_SAS_RX_DP3")
	)
	(segment
		(start 68.0212 -10.5664)
		(end 68.30314 -10.28446)
		(width 0.1143)
		(layer "In9.Cu")
		(net "P2E_CPU_SAS_RX_DP3")
	)
	(segment
		(start 65.42786 -12.68476)
		(end 65.77076 -12.68476)
		(width 0.1143)
		(layer "In9.Cu")
		(net "P2E_CPU_SAS_RX_DP3")
	)
	(segment
		(start 79.10068 -50.10658)
		(end 76.62418 -50.10658)
		(width 0.1143)
		(layer "In9.Cu")
		(net "P2E_CPU_SAS_RX_DP3")
	)
	(segment
		(start 67.127628 -12.22883)
		(end 67.369944 -11.986514)
		(width 0.1143)
		(layer "In9.Cu")
		(net "P2E_CPU_SAS_RX_DP3")
	)
	(segment
		(start 65.786 -18.3134)
		(end 63.17615 -15.70355)
		(width 0.1143)
		(layer "In9.Cu")
		(net "P2E_CPU_SAS_RX_DP3")
	)
	(segment
		(start 80.2259 -50.10658)
		(end 80.2132 -50.10658)
		(width 0.1016)
		(layer "In9.Cu")
		(net "P2E_CPU_SAS_RX_DP3")
	)
	(segment
		(start 71.0184 -42.9387)
		(end 68.083684 -42.9387)
		(width 0.1143)
		(layer "In9.Cu")
		(net "P2E_CPU_SAS_RX_DP3")
	)
	(segment
		(start 62.40145 -14.875256)
		(end 64.805306 -12.4714)
		(width 0.1143)
		(layer "In9.Cu")
		(net "P2E_CPU_SAS_RX_DP3")
	)
	(segment
		(start 81.229454 -49.59604)
		(end 81.229454 -49.50206)
		(width 0.1397)
		(layer "F.Cu")
		(net "P2E_CPU_SAS_RX_DP2")
	)
	(segment
		(start 72.349868 -6.195568)
		(end 72.349868 -8.447024)
		(width 0.1397)
		(layer "F.Cu")
		(net "P2E_CPU_SAS_RX_DP2")
	)
	(segment
		(start 72.021192 -8.7757)
		(end 72.021192 -9.97712)
		(width 0.1397)
		(layer "F.Cu")
		(net "P2E_CPU_SAS_RX_DP2")
	)
	(segment
		(start 72.021192 -9.97712)
		(end 72.328532 -10.28446)
		(width 0.1397)
		(layer "F.Cu")
		(net "P2E_CPU_SAS_RX_DP2")
	)
	(segment
		(start 72.349868 -8.447024)
		(end 72.021192 -8.7757)
		(width 0.1397)
		(layer "F.Cu")
		(net "P2E_CPU_SAS_RX_DP2")
	)
	(segment
		(start 81.646268 -50.012854)
		(end 81.229454 -49.59604)
		(width 0.1397)
		(layer "F.Cu")
		(net "P2E_CPU_SAS_RX_DP2")
	)
	(via
		(at 81.229454 -49.50206)
		(size 0.4318)
		(drill 0.2032)
		(layers "F.Cu" "B.Cu")
		(net "P2E_CPU_SAS_RX_DP2")
	)
	(via
		(at 72.328532 -10.28446)
		(size 0.508)
		(drill 0.254)
		(layers "F.Cu" "B.Cu")
		(net "P2E_CPU_SAS_RX_DP2")
	)
	(segment
		(start 66.2686 -27.340306)
		(end 68.8721 -24.736806)
		(width 0.1143)
		(layer "In9.Cu")
		(net "P2E_CPU_SAS_RX_DP2")
	)
	(segment
		(start 75.628754 -48.9077)
		(end 74.7395 -48.018446)
		(width 0.1143)
		(layer "In9.Cu")
		(net "P2E_CPU_SAS_RX_DP2")
	)
	(segment
		(start 71.64705 -13.9827)
		(end 72.014842 -13.614908)
		(width 0.1143)
		(layer "In9.Cu")
		(net "P2E_CPU_SAS_RX_DP2")
	)
	(segment
		(start 72.014842 -10.59815)
		(end 72.328532 -10.28446)
		(width 0.1143)
		(layer "In9.Cu")
		(net "P2E_CPU_SAS_RX_DP2")
	)
	(segment
		(start 66.74866 -39.51478)
		(end 66.74866 -39.17188)
		(width 0.1143)
		(layer "In9.Cu")
		(net "P2E_CPU_SAS_RX_DP2")
	)
	(segment
		(start 67.929506 -23.0632)
		(end 67.091306 -23.0632)
		(width 0.1143)
		(layer "In9.Cu")
		(net "P2E_CPU_SAS_RX_DP2")
	)
	(segment
		(start 66.74866 -36.94684)
		(end 66.5353 -36.73348)
		(width 0.1143)
		(layer "In9.Cu")
		(net "P2E_CPU_SAS_RX_DP2")
	)
	(segment
		(start 66.7512 -22.723094)
		(end 66.7512 -21.955506)
		(width 0.1143)
		(layer "In9.Cu")
		(net "P2E_CPU_SAS_RX_DP2")
	)
	(segment
		(start 68.8721 -18.005806)
		(end 69.580506 -17.2974)
		(width 0.1143)
		(layer "In9.Cu")
		(net "P2E_CPU_SAS_RX_DP2")
	)
	(segment
		(start 68.8721 -20.863306)
		(end 68.8721 -18.005806)
		(width 0.1143)
		(layer "In9.Cu")
		(net "P2E_CPU_SAS_RX_DP2")
	)
	(segment
		(start 66.5353 -37.5031)
		(end 66.74866 -37.28974)
		(width 0.1143)
		(layer "In9.Cu")
		(net "P2E_CPU_SAS_RX_DP2")
	)
	(segment
		(start 66.5353 -38.95852)
		(end 66.5353 -38.61562)
		(width 0.1143)
		(layer "In9.Cu")
		(net "P2E_CPU_SAS_RX_DP2")
	)
	(segment
		(start 80.91424 -49.50206)
		(end 80.31988 -48.9077)
		(width 0.1143)
		(layer "In9.Cu")
		(net "P2E_CPU_SAS_RX_DP2")
	)
	(segment
		(start 67.091306 -23.0632)
		(end 66.7512 -22.723094)
		(width 0.1143)
		(layer "In9.Cu")
		(net "P2E_CPU_SAS_RX_DP2")
	)
	(segment
		(start 66.5353 -32.311594)
		(end 66.2686 -32.044894)
		(width 0.1143)
		(layer "In9.Cu")
		(net "P2E_CPU_SAS_RX_DP2")
	)
	(segment
		(start 74.7395 -44.404026)
		(end 72.321674 -41.9862)
		(width 0.1143)
		(layer "In9.Cu")
		(net "P2E_CPU_SAS_RX_DP2")
	)
	(segment
		(start 66.5353 -39.72814)
		(end 66.74866 -39.51478)
		(width 0.1143)
		(layer "In9.Cu")
		(net "P2E_CPU_SAS_RX_DP2")
	)
	(segment
		(start 68.8721 -24.005794)
		(end 67.929506 -23.0632)
		(width 0.1143)
		(layer "In9.Cu")
		(net "P2E_CPU_SAS_RX_DP2")
	)
	(segment
		(start 66.74866 -38.40226)
		(end 66.74866 -38.05936)
		(width 0.1143)
		(layer "In9.Cu")
		(net "P2E_CPU_SAS_RX_DP2")
	)
	(segment
		(start 72.014842 -13.614908)
		(end 72.014842 -10.59815)
		(width 0.1143)
		(layer "In9.Cu")
		(net "P2E_CPU_SAS_RX_DP2")
	)
	(segment
		(start 66.5353 -36.73348)
		(end 66.5353 -32.311594)
		(width 0.1143)
		(layer "In9.Cu")
		(net "P2E_CPU_SAS_RX_DP2")
	)
	(segment
		(start 66.74866 -39.17188)
		(end 66.5353 -38.95852)
		(width 0.1143)
		(layer "In9.Cu")
		(net "P2E_CPU_SAS_RX_DP2")
	)
	(segment
		(start 80.31988 -48.9077)
		(end 75.628754 -48.9077)
		(width 0.1143)
		(layer "In9.Cu")
		(net "P2E_CPU_SAS_RX_DP2")
	)
	(segment
		(start 66.5353 -38.61562)
		(end 66.74866 -38.40226)
		(width 0.1143)
		(layer "In9.Cu")
		(net "P2E_CPU_SAS_RX_DP2")
	)
	(segment
		(start 74.7395 -48.018446)
		(end 74.7395 -44.404026)
		(width 0.1143)
		(layer "In9.Cu")
		(net "P2E_CPU_SAS_RX_DP2")
	)
	(segment
		(start 66.74866 -38.05936)
		(end 66.5353 -37.846)
		(width 0.1143)
		(layer "In9.Cu")
		(net "P2E_CPU_SAS_RX_DP2")
	)
	(segment
		(start 66.7512 -21.955506)
		(end 67.142106 -21.5646)
		(width 0.1143)
		(layer "In9.Cu")
		(net "P2E_CPU_SAS_RX_DP2")
	)
	(segment
		(start 67.142106 -21.5646)
		(end 68.170806 -21.5646)
		(width 0.1143)
		(layer "In9.Cu")
		(net "P2E_CPU_SAS_RX_DP2")
	)
	(segment
		(start 81.229454 -49.50206)
		(end 80.91424 -49.50206)
		(width 0.1143)
		(layer "In9.Cu")
		(net "P2E_CPU_SAS_RX_DP2")
	)
	(segment
		(start 68.170806 -21.5646)
		(end 68.8721 -20.863306)
		(width 0.1143)
		(layer "In9.Cu")
		(net "P2E_CPU_SAS_RX_DP2")
	)
	(segment
		(start 66.2686 -32.044894)
		(end 66.2686 -27.340306)
		(width 0.1143)
		(layer "In9.Cu")
		(net "P2E_CPU_SAS_RX_DP2")
	)
	(segment
		(start 71.64705 -16.392906)
		(end 71.64705 -13.9827)
		(width 0.1143)
		(layer "In9.Cu")
		(net "P2E_CPU_SAS_RX_DP2")
	)
	(segment
		(start 68.8721 -24.736806)
		(end 68.8721 -24.005794)
		(width 0.1143)
		(layer "In9.Cu")
		(net "P2E_CPU_SAS_RX_DP2")
	)
	(segment
		(start 70.742556 -17.2974)
		(end 71.64705 -16.392906)
		(width 0.1143)
		(layer "In9.Cu")
		(net "P2E_CPU_SAS_RX_DP2")
	)
	(segment
		(start 72.321674 -41.9862)
		(end 68.4784 -41.9862)
		(width 0.1143)
		(layer "In9.Cu")
		(net "P2E_CPU_SAS_RX_DP2")
	)
	(segment
		(start 69.580506 -17.2974)
		(end 70.742556 -17.2974)
		(width 0.1143)
		(layer "In9.Cu")
		(net "P2E_CPU_SAS_RX_DP2")
	)
	(segment
		(start 66.5353 -40.0431)
		(end 66.5353 -39.72814)
		(width 0.1143)
		(layer "In9.Cu")
		(net "P2E_CPU_SAS_RX_DP2")
	)
	(segment
		(start 66.74866 -37.28974)
		(end 66.74866 -36.94684)
		(width 0.1143)
		(layer "In9.Cu")
		(net "P2E_CPU_SAS_RX_DP2")
	)
	(segment
		(start 66.5353 -37.846)
		(end 66.5353 -37.5031)
		(width 0.1143)
		(layer "In9.Cu")
		(net "P2E_CPU_SAS_RX_DP2")
	)
	(segment
		(start 68.4784 -41.9862)
		(end 66.5353 -40.0431)
		(width 0.1143)
		(layer "In9.Cu")
		(net "P2E_CPU_SAS_RX_DP2")
	)
	(segment
		(start 71.34987 -8.447278)
		(end 71.678292 -8.7757)
		(width 0.1397)
		(layer "F.Cu")
		(net "P2E_CPU_SAS_RX_DN2")
	)
	(segment
		(start 71.678292 -9.97712)
		(end 71.370952 -10.28446)
		(width 0.1397)
		(layer "F.Cu")
		(net "P2E_CPU_SAS_RX_DN2")
	)
	(segment
		(start 71.678292 -8.7757)
		(end 71.678292 -9.97712)
		(width 0.1397)
		(layer "F.Cu")
		(net "P2E_CPU_SAS_RX_DN2")
	)
	(segment
		(start 80.48244 -49.88814)
		(end 80.48244 -49.790604)
		(width 0.1397)
		(layer "F.Cu")
		(net "P2E_CPU_SAS_RX_DN2")
	)
	(segment
		(start 81.364328 -50.685954)
		(end 81.280254 -50.685954)
		(width 0.1397)
		(layer "F.Cu")
		(net "P2E_CPU_SAS_RX_DN2")
	)
	(segment
		(start 71.34987 -6.195568)
		(end 71.34987 -8.447278)
		(width 0.1397)
		(layer "F.Cu")
		(net "P2E_CPU_SAS_RX_DN2")
	)
	(segment
		(start 81.280254 -50.685954)
		(end 80.48244 -49.88814)
		(width 0.1397)
		(layer "F.Cu")
		(net "P2E_CPU_SAS_RX_DN2")
	)
	(segment
		(start 80.48244 -49.790604)
		(end 80.478376 -49.78654)
		(width 0.1397)
		(layer "F.Cu")
		(net "P2E_CPU_SAS_RX_DN2")
	)
	(via
		(at 80.478376 -49.78654)
		(size 0.4318)
		(drill 0.2032)
		(layers "F.Cu" "B.Cu")
		(net "P2E_CPU_SAS_RX_DN2")
	)
	(via
		(at 71.370952 -10.28446)
		(size 0.508)
		(drill 0.254)
		(layers "F.Cu" "B.Cu")
		(net "P2E_CPU_SAS_RX_DN2")
	)
	(segment
		(start 68.0339 -21.2344)
		(end 68.5419 -20.7264)
		(width 0.1143)
		(layer "In9.Cu")
		(net "P2E_CPU_SAS_RX_DN2")
	)
	(segment
		(start 74.4093 -48.155352)
		(end 74.4093 -44.540932)
		(width 0.1143)
		(layer "In9.Cu")
		(net "P2E_CPU_SAS_RX_DN2")
	)
	(segment
		(start 71.31685 -13.845794)
		(end 71.684642 -13.478002)
		(width 0.1143)
		(layer "In9.Cu")
		(net "P2E_CPU_SAS_RX_DN2")
	)
	(segment
		(start 68.5419 -24.5999)
		(end 68.5419 -24.1427)
		(width 0.1143)
		(layer "In9.Cu")
		(net "P2E_CPU_SAS_RX_DN2")
	)
	(segment
		(start 66.421 -21.8186)
		(end 67.0052 -21.2344)
		(width 0.1143)
		(layer "In9.Cu")
		(net "P2E_CPU_SAS_RX_DN2")
	)
	(segment
		(start 71.31685 -16.256)
		(end 71.31685 -13.845794)
		(width 0.1143)
		(layer "In9.Cu")
		(net "P2E_CPU_SAS_RX_DN2")
	)
	(segment
		(start 66.2051 -32.4485)
		(end 65.9384 -32.1818)
		(width 0.1143)
		(layer "In9.Cu")
		(net "P2E_CPU_SAS_RX_DN2")
	)
	(segment
		(start 66.9544 -23.3934)
		(end 66.421 -22.86)
		(width 0.1143)
		(layer "In9.Cu")
		(net "P2E_CPU_SAS_RX_DN2")
	)
	(segment
		(start 71.684642 -13.478002)
		(end 71.684642 -10.59815)
		(width 0.1143)
		(layer "In9.Cu")
		(net "P2E_CPU_SAS_RX_DN2")
	)
	(segment
		(start 65.9384 -32.1818)
		(end 65.9384 -27.2034)
		(width 0.1143)
		(layer "In9.Cu")
		(net "P2E_CPU_SAS_RX_DN2")
	)
	(segment
		(start 68.5419 -17.8689)
		(end 69.4436 -16.9672)
		(width 0.1143)
		(layer "In9.Cu")
		(net "P2E_CPU_SAS_RX_DN2")
	)
	(segment
		(start 65.9384 -27.2034)
		(end 68.5419 -24.5999)
		(width 0.1143)
		(layer "In9.Cu")
		(net "P2E_CPU_SAS_RX_DN2")
	)
	(segment
		(start 70.60565 -16.9672)
		(end 71.31685 -16.256)
		(width 0.1143)
		(layer "In9.Cu")
		(net "P2E_CPU_SAS_RX_DN2")
	)
	(segment
		(start 72.184768 -42.3164)
		(end 68.341494 -42.3164)
		(width 0.1143)
		(layer "In9.Cu")
		(net "P2E_CPU_SAS_RX_DN2")
	)
	(segment
		(start 66.2051 -40.180006)
		(end 66.2051 -32.4485)
		(width 0.1143)
		(layer "In9.Cu")
		(net "P2E_CPU_SAS_RX_DN2")
	)
	(segment
		(start 80.478376 -49.78654)
		(end 80.478376 -49.533302)
		(width 0.1143)
		(layer "In9.Cu")
		(net "P2E_CPU_SAS_RX_DN2")
	)
	(segment
		(start 68.341494 -42.3164)
		(end 66.2051 -40.180006)
		(width 0.1143)
		(layer "In9.Cu")
		(net "P2E_CPU_SAS_RX_DN2")
	)
	(segment
		(start 74.4093 -44.540932)
		(end 72.184768 -42.3164)
		(width 0.1143)
		(layer "In9.Cu")
		(net "P2E_CPU_SAS_RX_DN2")
	)
	(segment
		(start 69.4436 -16.9672)
		(end 70.60565 -16.9672)
		(width 0.1143)
		(layer "In9.Cu")
		(net "P2E_CPU_SAS_RX_DN2")
	)
	(segment
		(start 80.182974 -49.2379)
		(end 75.491848 -49.2379)
		(width 0.1143)
		(layer "In9.Cu")
		(net "P2E_CPU_SAS_RX_DN2")
	)
	(segment
		(start 68.5419 -24.1427)
		(end 67.7926 -23.3934)
		(width 0.1143)
		(layer "In9.Cu")
		(net "P2E_CPU_SAS_RX_DN2")
	)
	(segment
		(start 67.0052 -21.2344)
		(end 68.0339 -21.2344)
		(width 0.1143)
		(layer "In9.Cu")
		(net "P2E_CPU_SAS_RX_DN2")
	)
	(segment
		(start 75.491848 -49.2379)
		(end 74.4093 -48.155352)
		(width 0.1143)
		(layer "In9.Cu")
		(net "P2E_CPU_SAS_RX_DN2")
	)
	(segment
		(start 67.7926 -23.3934)
		(end 66.9544 -23.3934)
		(width 0.1143)
		(layer "In9.Cu")
		(net "P2E_CPU_SAS_RX_DN2")
	)
	(segment
		(start 66.421 -22.86)
		(end 66.421 -21.8186)
		(width 0.1143)
		(layer "In9.Cu")
		(net "P2E_CPU_SAS_RX_DN2")
	)
	(segment
		(start 80.478376 -49.533302)
		(end 80.182974 -49.2379)
		(width 0.1143)
		(layer "In9.Cu")
		(net "P2E_CPU_SAS_RX_DN2")
	)
	(segment
		(start 71.684642 -10.59815)
		(end 71.370952 -10.28446)
		(width 0.1143)
		(layer "In9.Cu")
		(net "P2E_CPU_SAS_RX_DN2")
	)
	(segment
		(start 68.5419 -20.7264)
		(end 68.5419 -17.8689)
		(width 0.1143)
		(layer "In9.Cu")
		(net "P2E_CPU_SAS_RX_DN2")
	)
	(segment
		(start 76.34986 -6.195568)
		(end 76.34986 -8.447024)
		(width 0.1397)
		(layer "F.Cu")
		(net "P2E_CPU_SAS_RX_DP1")
	)
	(segment
		(start 76.34986 -8.447024)
		(end 76.021184 -8.7757)
		(width 0.1397)
		(layer "F.Cu")
		(net "P2E_CPU_SAS_RX_DP1")
	)
	(segment
		(start 80.67802 -49.004474)
		(end 80.856328 -49.182782)
		(width 0.1016)
		(layer "F.Cu")
		(net "P2E_CPU_SAS_RX_DP1")
	)
	(segment
		(start 77.318108 -48.5013)
		(end 80.05445 -48.5013)
		(width 0.1016)
		(layer "F.Cu")
		(net "P2E_CPU_SAS_RX_DP1")
	)
	(segment
		(start 77.08392 -48.0314)
		(end 77.08392 -48.267112)
		(width 0.1016)
		(layer "F.Cu")
		(net "P2E_CPU_SAS_RX_DP1")
	)
	(segment
		(start 80.05445 -48.5013)
		(end 80.557624 -49.004474)
		(width 0.1016)
		(layer "F.Cu")
		(net "P2E_CPU_SAS_RX_DP1")
	)
	(segment
		(start 76.021184 -9.97712)
		(end 76.328524 -10.28446)
		(width 0.1397)
		(layer "F.Cu")
		(net "P2E_CPU_SAS_RX_DP1")
	)
	(segment
		(start 80.856328 -49.802034)
		(end 80.950308 -49.896014)
		(width 0.1016)
		(layer "F.Cu")
		(net "P2E_CPU_SAS_RX_DP1")
	)
	(segment
		(start 80.856328 -49.182782)
		(end 80.856328 -49.802034)
		(width 0.1016)
		(layer "F.Cu")
		(net "P2E_CPU_SAS_RX_DP1")
	)
	(segment
		(start 76.021184 -8.7757)
		(end 76.021184 -9.97712)
		(width 0.1397)
		(layer "F.Cu")
		(net "P2E_CPU_SAS_RX_DP1")
	)
	(segment
		(start 80.557624 -49.004474)
		(end 80.67802 -49.004474)
		(width 0.1016)
		(layer "F.Cu")
		(net "P2E_CPU_SAS_RX_DP1")
	)
	(segment
		(start 77.08392 -48.267112)
		(end 77.318108 -48.5013)
		(width 0.1016)
		(layer "F.Cu")
		(net "P2E_CPU_SAS_RX_DP1")
	)
	(via
		(at 77.08392 -48.0314)
		(size 0.4318)
		(drill 0.2032)
		(layers "F.Cu" "B.Cu")
		(net "P2E_CPU_SAS_RX_DP1")
	)
	(via
		(at 76.328524 -10.28446)
		(size 0.508)
		(drill 0.254)
		(layers "F.Cu" "B.Cu")
		(net "P2E_CPU_SAS_RX_DP1")
	)
	(segment
		(start 73.339706 -16.3068)
		(end 74.7268 -16.3068)
		(width 0.1143)
		(layer "In9.Cu")
		(net "P2E_CPU_SAS_RX_DP1")
	)
	(segment
		(start 76.014834 -10.59815)
		(end 76.328524 -10.28446)
		(width 0.1143)
		(layer "In9.Cu")
		(net "P2E_CPU_SAS_RX_DP1")
	)
	(segment
		(start 76.66736 -47.5234)
		(end 76.24064 -47.5234)
		(width 0.1143)
		(layer "In9.Cu")
		(net "P2E_CPU_SAS_RX_DP1")
	)
	(segment
		(start 71.40702 -20.54098)
		(end 72.0344 -19.9136)
		(width 0.1143)
		(layer "In9.Cu")
		(net "P2E_CPU_SAS_RX_DP1")
	)
	(segment
		(start 74.7268 -16.3068)
		(end 75.0951 -15.9385)
		(width 0.1143)
		(layer "In9.Cu")
		(net "P2E_CPU_SAS_RX_DP1")
	)
	(segment
		(start 72.0344 -19.9136)
		(end 72.0344 -18.451576)
		(width 0.1143)
		(layer "In9.Cu")
		(net "P2E_CPU_SAS_RX_DP1")
	)
	(segment
		(start 70.4342 -21.249894)
		(end 70.4342 -20.787106)
		(width 0.1143)
		(layer "In9.Cu")
		(net "P2E_CPU_SAS_RX_DP1")
	)
	(segment
		(start 76.014834 -11.117072)
		(end 76.014834 -10.59815)
		(width 0.1143)
		(layer "In9.Cu")
		(net "P2E_CPU_SAS_RX_DP1")
	)
	(segment
		(start 72.61987 -17.026636)
		(end 73.339706 -16.3068)
		(width 0.1143)
		(layer "In9.Cu")
		(net "P2E_CPU_SAS_RX_DP1")
	)
	(segment
		(start 72.0344 -18.451576)
		(end 72.61987 -17.866106)
		(width 0.1143)
		(layer "In9.Cu")
		(net "P2E_CPU_SAS_RX_DP1")
	)
	(segment
		(start 70.621906 -21.4376)
		(end 70.4342 -21.249894)
		(width 0.1143)
		(layer "In9.Cu")
		(net "P2E_CPU_SAS_RX_DP1")
	)
	(segment
		(start 70.4342 -20.787106)
		(end 70.680326 -20.54098)
		(width 0.1143)
		(layer "In9.Cu")
		(net "P2E_CPU_SAS_RX_DP1")
	)
	(segment
		(start 75.4507 -46.73346)
		(end 75.4507 -43.76801)
		(width 0.1143)
		(layer "In9.Cu")
		(net "P2E_CPU_SAS_RX_DP1")
	)
	(segment
		(start 77.08392 -47.93996)
		(end 76.66736 -47.5234)
		(width 0.1143)
		(layer "In9.Cu")
		(net "P2E_CPU_SAS_RX_DP1")
	)
	(segment
		(start 71.93915 -23.092156)
		(end 71.93915 -22.138894)
		(width 0.1143)
		(layer "In9.Cu")
		(net "P2E_CPU_SAS_RX_DP1")
	)
	(segment
		(start 70.12305 -28.88615)
		(end 70.6882 -28.321)
		(width 0.1143)
		(layer "In9.Cu")
		(net "P2E_CPU_SAS_RX_DP1")
	)
	(segment
		(start 76.24064 -47.5234)
		(end 75.4507 -46.73346)
		(width 0.1143)
		(layer "In9.Cu")
		(net "P2E_CPU_SAS_RX_DP1")
	)
	(segment
		(start 74.655426 -12.47648)
		(end 76.014834 -11.117072)
		(width 0.1143)
		(layer "In9.Cu")
		(net "P2E_CPU_SAS_RX_DP1")
	)
	(segment
		(start 75.0951 -14.175994)
		(end 74.655426 -13.73632)
		(width 0.1143)
		(layer "In9.Cu")
		(net "P2E_CPU_SAS_RX_DP1")
	)
	(segment
		(start 70.444106 -26.3906)
		(end 70.12305 -26.069544)
		(width 0.1143)
		(layer "In9.Cu")
		(net "P2E_CPU_SAS_RX_DP1")
	)
	(segment
		(start 70.494906 -23.8252)
		(end 71.206106 -23.8252)
		(width 0.1143)
		(layer "In9.Cu")
		(net "P2E_CPU_SAS_RX_DP1")
	)
	(segment
		(start 70.12305 -24.197056)
		(end 70.494906 -23.8252)
		(width 0.1143)
		(layer "In9.Cu")
		(net "P2E_CPU_SAS_RX_DP1")
	)
	(segment
		(start 71.54799 -27.94381)
		(end 71.54799 -26.859484)
		(width 0.1143)
		(layer "In9.Cu")
		(net "P2E_CPU_SAS_RX_DP1")
	)
	(segment
		(start 71.1708 -28.321)
		(end 71.54799 -27.94381)
		(width 0.1143)
		(layer "In9.Cu")
		(net "P2E_CPU_SAS_RX_DP1")
	)
	(segment
		(start 71.206106 -23.8252)
		(end 71.93915 -23.092156)
		(width 0.1143)
		(layer "In9.Cu")
		(net "P2E_CPU_SAS_RX_DP1")
	)
	(segment
		(start 70.680326 -20.54098)
		(end 71.40702 -20.54098)
		(width 0.1143)
		(layer "In9.Cu")
		(net "P2E_CPU_SAS_RX_DP1")
	)
	(segment
		(start 75.4507 -43.76801)
		(end 73.1012 -41.41851)
		(width 0.1143)
		(layer "In9.Cu")
		(net "P2E_CPU_SAS_RX_DP1")
	)
	(segment
		(start 74.655426 -13.73632)
		(end 74.655426 -12.47648)
		(width 0.1143)
		(layer "In9.Cu")
		(net "P2E_CPU_SAS_RX_DP1")
	)
	(segment
		(start 71.237856 -21.4376)
		(end 70.621906 -21.4376)
		(width 0.1143)
		(layer "In9.Cu")
		(net "P2E_CPU_SAS_RX_DP1")
	)
	(segment
		(start 75.0951 -15.9385)
		(end 75.0951 -14.175994)
		(width 0.1143)
		(layer "In9.Cu")
		(net "P2E_CPU_SAS_RX_DP1")
	)
	(segment
		(start 72.61987 -17.866106)
		(end 72.61987 -17.026636)
		(width 0.1143)
		(layer "In9.Cu")
		(net "P2E_CPU_SAS_RX_DP1")
	)
	(segment
		(start 70.12305 -26.069544)
		(end 70.12305 -24.197056)
		(width 0.1143)
		(layer "In9.Cu")
		(net "P2E_CPU_SAS_RX_DP1")
	)
	(segment
		(start 70.6882 -28.321)
		(end 71.1708 -28.321)
		(width 0.1143)
		(layer "In9.Cu")
		(net "P2E_CPU_SAS_RX_DP1")
	)
	(segment
		(start 77.08392 -48.0314)
		(end 77.08392 -47.93996)
		(width 0.1143)
		(layer "In9.Cu")
		(net "P2E_CPU_SAS_RX_DP1")
	)
	(segment
		(start 70.12305 -33.212278)
		(end 70.12305 -28.88615)
		(width 0.1143)
		(layer "In9.Cu")
		(net "P2E_CPU_SAS_RX_DP1")
	)
	(segment
		(start 71.079106 -26.3906)
		(end 70.444106 -26.3906)
		(width 0.1143)
		(layer "In9.Cu")
		(net "P2E_CPU_SAS_RX_DP1")
	)
	(segment
		(start 71.93915 -22.138894)
		(end 71.237856 -21.4376)
		(width 0.1143)
		(layer "In9.Cu")
		(net "P2E_CPU_SAS_RX_DP1")
	)
	(segment
		(start 73.1012 -41.41851)
		(end 73.1012 -36.190428)
		(width 0.1143)
		(layer "In9.Cu")
		(net "P2E_CPU_SAS_RX_DP1")
	)
	(segment
		(start 73.1012 -36.190428)
		(end 70.12305 -33.212278)
		(width 0.1143)
		(layer "In9.Cu")
		(net "P2E_CPU_SAS_RX_DP1")
	)
	(segment
		(start 71.54799 -26.859484)
		(end 71.079106 -26.3906)
		(width 0.1143)
		(layer "In9.Cu")
		(net "P2E_CPU_SAS_RX_DP1")
	)
	(segment
		(start 75.349862 -6.195568)
		(end 75.349862 -8.447278)
		(width 0.1397)
		(layer "F.Cu")
		(net "P2E_CPU_SAS_RX_DN1")
	)
	(segment
		(start 77.23378 -48.7045)
		(end 79.80172 -48.7045)
		(width 0.1016)
		(layer "F.Cu")
		(net "P2E_CPU_SAS_RX_DN1")
	)
	(segment
		(start 79.80172 -48.7045)
		(end 79.801974 -48.704754)
		(width 0.1016)
		(layer "F.Cu")
		(net "P2E_CPU_SAS_RX_DN1")
	)
	(segment
		(start 75.678284 -9.97712)
		(end 75.370944 -10.28446)
		(width 0.1397)
		(layer "F.Cu")
		(net "P2E_CPU_SAS_RX_DN1")
	)
	(segment
		(start 76.5302 -48.00092)
		(end 77.23378 -48.7045)
		(width 0.1016)
		(layer "F.Cu")
		(net "P2E_CPU_SAS_RX_DN1")
	)
	(segment
		(start 79.886302 -48.7045)
		(end 79.970122 -48.7045)
		(width 0.1016)
		(layer "F.Cu")
		(net "P2E_CPU_SAS_RX_DN1")
	)
	(segment
		(start 76.5302 -47.9298)
		(end 76.5302 -48.00092)
		(width 0.1016)
		(layer "F.Cu")
		(net "P2E_CPU_SAS_RX_DN1")
	)
	(segment
		(start 79.886048 -48.704754)
		(end 79.886302 -48.7045)
		(width 0.1016)
		(layer "F.Cu")
		(net "P2E_CPU_SAS_RX_DN1")
	)
	(segment
		(start 75.349862 -8.447278)
		(end 75.678284 -8.7757)
		(width 0.1397)
		(layer "F.Cu")
		(net "P2E_CPU_SAS_RX_DN1")
	)
	(segment
		(start 80.551528 -49.285906)
		(end 80.551528 -49.309274)
		(width 0.1016)
		(layer "F.Cu")
		(net "P2E_CPU_SAS_RX_DN1")
	)
	(segment
		(start 79.970122 -48.7045)
		(end 80.551528 -49.285906)
		(width 0.1016)
		(layer "F.Cu")
		(net "P2E_CPU_SAS_RX_DN1")
	)
	(segment
		(start 79.801974 -48.704754)
		(end 79.886048 -48.704754)
		(width 0.1016)
		(layer "F.Cu")
		(net "P2E_CPU_SAS_RX_DN1")
	)
	(segment
		(start 75.678284 -8.7757)
		(end 75.678284 -9.97712)
		(width 0.1397)
		(layer "F.Cu")
		(net "P2E_CPU_SAS_RX_DN1")
	)
	(via
		(at 75.370944 -10.28446)
		(size 0.508)
		(drill 0.254)
		(layers "F.Cu" "B.Cu")
		(net "P2E_CPU_SAS_RX_DN1")
	)
	(via
		(at 76.5302 -47.9298)
		(size 0.4318)
		(drill 0.2032)
		(layers "F.Cu" "B.Cu")
		(net "P2E_CPU_SAS_RX_DN1")
	)
	(segment
		(start 75.684634 -10.59815)
		(end 75.370944 -10.28446)
		(width 0.1143)
		(layer "In9.Cu")
		(net "P2E_CPU_SAS_RX_DN1")
	)
	(segment
		(start 70.4469 -20.3073)
		(end 70.54342 -20.21078)
		(width 0.1143)
		(layer "In9.Cu")
		(net "P2E_CPU_SAS_RX_DN1")
	)
	(segment
		(start 76.5302 -47.9298)
		(end 76.454 -47.8536)
		(width 0.1143)
		(layer "In9.Cu")
		(net "P2E_CPU_SAS_RX_DN1")
	)
	(segment
		(start 73.2028 -15.9766)
		(end 74.589894 -15.9766)
		(width 0.1143)
		(layer "In9.Cu")
		(net "P2E_CPU_SAS_RX_DN1")
	)
	(segment
		(start 71.270114 -20.21078)
		(end 71.7042 -19.776694)
		(width 0.1143)
		(layer "In9.Cu")
		(net "P2E_CPU_SAS_RX_DN1")
	)
	(segment
		(start 72.28967 -17.7292)
		(end 72.28967 -16.88973)
		(width 0.1143)
		(layer "In9.Cu")
		(net "P2E_CPU_SAS_RX_DN1")
	)
	(segment
		(start 70.3072 -26.7208)
		(end 69.79285 -26.20645)
		(width 0.1143)
		(layer "In9.Cu")
		(net "P2E_CPU_SAS_RX_DN1")
	)
	(segment
		(start 70.816216 -34.37255)
		(end 70.514464 -34.37255)
		(width 0.1143)
		(layer "In9.Cu")
		(net "P2E_CPU_SAS_RX_DN1")
	)
	(segment
		(start 70.9422 -26.7208)
		(end 70.3072 -26.7208)
		(width 0.1143)
		(layer "In9.Cu")
		(net "P2E_CPU_SAS_RX_DN1")
	)
	(segment
		(start 74.325226 -13.873226)
		(end 74.325226 -12.339574)
		(width 0.1143)
		(layer "In9.Cu")
		(net "P2E_CPU_SAS_RX_DN1")
	)
	(segment
		(start 70.485 -21.7678)
		(end 70.104 -21.3868)
		(width 0.1143)
		(layer "In9.Cu")
		(net "P2E_CPU_SAS_RX_DN1")
	)
	(segment
		(start 75.1205 -43.904916)
		(end 72.771 -41.555416)
		(width 0.1143)
		(layer "In9.Cu")
		(net "P2E_CPU_SAS_RX_DN1")
	)
	(segment
		(start 69.79285 -28.749244)
		(end 70.551294 -27.9908)
		(width 0.1143)
		(layer "In9.Cu")
		(net "P2E_CPU_SAS_RX_DN1")
	)
	(segment
		(start 71.602854 -35.159188)
		(end 71.301102 -35.159188)
		(width 0.1143)
		(layer "In9.Cu")
		(net "P2E_CPU_SAS_RX_DN1")
	)
	(segment
		(start 70.446646 -20.3073)
		(end 70.4469 -20.3073)
		(width 0.1143)
		(layer "In9.Cu")
		(net "P2E_CPU_SAS_RX_DN1")
	)
	(segment
		(start 70.272148 -34.130234)
		(end 70.272148 -33.828482)
		(width 0.1143)
		(layer "In9.Cu")
		(net "P2E_CPU_SAS_RX_DN1")
	)
	(segment
		(start 74.7649 -14.3129)
		(end 74.325226 -13.873226)
		(width 0.1143)
		(layer "In9.Cu")
		(net "P2E_CPU_SAS_RX_DN1")
	)
	(segment
		(start 69.57949 -29.93517)
		(end 69.57949 -29.59227)
		(width 0.1143)
		(layer "In9.Cu")
		(net "P2E_CPU_SAS_RX_DN1")
	)
	(segment
		(start 72.28967 -16.88973)
		(end 73.2028 -15.9766)
		(width 0.1143)
		(layer "In9.Cu")
		(net "P2E_CPU_SAS_RX_DN1")
	)
	(segment
		(start 71.058786 -34.61512)
		(end 70.816216 -34.37255)
		(width 0.1143)
		(layer "In9.Cu")
		(net "P2E_CPU_SAS_RX_DN1")
	)
	(segment
		(start 69.57949 -29.59227)
		(end 69.79285 -29.37891)
		(width 0.1143)
		(layer "In9.Cu")
		(net "P2E_CPU_SAS_RX_DN1")
	)
	(segment
		(start 69.79285 -30.49143)
		(end 69.79285 -30.14853)
		(width 0.1143)
		(layer "In9.Cu")
		(net "P2E_CPU_SAS_RX_DN1")
	)
	(segment
		(start 70.551294 -27.9908)
		(end 71.033894 -27.9908)
		(width 0.1143)
		(layer "In9.Cu")
		(net "P2E_CPU_SAS_RX_DN1")
	)
	(segment
		(start 70.104 -20.6502)
		(end 70.446646 -20.3073)
		(width 0.1143)
		(layer "In9.Cu")
		(net "P2E_CPU_SAS_RX_DN1")
	)
	(segment
		(start 75.1205 -46.870366)
		(end 75.1205 -43.904916)
		(width 0.1143)
		(layer "In9.Cu")
		(net "P2E_CPU_SAS_RX_DN1")
	)
	(segment
		(start 71.0692 -23.495)
		(end 71.60895 -22.95525)
		(width 0.1143)
		(layer "In9.Cu")
		(net "P2E_CPU_SAS_RX_DN1")
	)
	(segment
		(start 69.57949 -31.04769)
		(end 69.57949 -30.70479)
		(width 0.1143)
		(layer "In9.Cu")
		(net "P2E_CPU_SAS_RX_DN1")
	)
	(segment
		(start 74.589894 -15.9766)
		(end 74.7649 -15.801594)
		(width 0.1143)
		(layer "In9.Cu")
		(net "P2E_CPU_SAS_RX_DN1")
	)
	(segment
		(start 69.79285 -26.20645)
		(end 69.79285 -24.06015)
		(width 0.1143)
		(layer "In9.Cu")
		(net "P2E_CPU_SAS_RX_DN1")
	)
	(segment
		(start 69.79285 -29.37891)
		(end 69.79285 -28.749244)
		(width 0.1143)
		(layer "In9.Cu")
		(net "P2E_CPU_SAS_RX_DN1")
	)
	(segment
		(start 74.325226 -12.339574)
		(end 75.684634 -10.980166)
		(width 0.1143)
		(layer "In9.Cu")
		(net "P2E_CPU_SAS_RX_DN1")
	)
	(segment
		(start 69.79285 -24.06015)
		(end 70.358 -23.495)
		(width 0.1143)
		(layer "In9.Cu")
		(net "P2E_CPU_SAS_RX_DN1")
	)
	(segment
		(start 71.7042 -18.31467)
		(end 72.28967 -17.7292)
		(width 0.1143)
		(layer "In9.Cu")
		(net "P2E_CPU_SAS_RX_DN1")
	)
	(segment
		(start 69.79285 -31.26105)
		(end 69.57949 -31.04769)
		(width 0.1143)
		(layer "In9.Cu")
		(net "P2E_CPU_SAS_RX_DN1")
	)
	(segment
		(start 69.79285 -30.14853)
		(end 69.57949 -29.93517)
		(width 0.1143)
		(layer "In9.Cu")
		(net "P2E_CPU_SAS_RX_DN1")
	)
	(segment
		(start 71.301102 -35.159188)
		(end 71.058786 -34.916872)
		(width 0.1143)
		(layer "In9.Cu")
		(net "P2E_CPU_SAS_RX_DN1")
	)
	(segment
		(start 69.79285 -33.349184)
		(end 69.79285 -31.26105)
		(width 0.1143)
		(layer "In9.Cu")
		(net "P2E_CPU_SAS_RX_DN1")
	)
	(segment
		(start 70.358 -23.495)
		(end 71.0692 -23.495)
		(width 0.1143)
		(layer "In9.Cu")
		(net "P2E_CPU_SAS_RX_DN1")
	)
	(segment
		(start 70.54342 -20.21078)
		(end 71.270114 -20.21078)
		(width 0.1143)
		(layer "In9.Cu")
		(net "P2E_CPU_SAS_RX_DN1")
	)
	(segment
		(start 69.57949 -30.70479)
		(end 69.79285 -30.49143)
		(width 0.1143)
		(layer "In9.Cu")
		(net "P2E_CPU_SAS_RX_DN1")
	)
	(segment
		(start 71.10095 -21.7678)
		(end 70.485 -21.7678)
		(width 0.1143)
		(layer "In9.Cu")
		(net "P2E_CPU_SAS_RX_DN1")
	)
	(segment
		(start 71.7042 -19.776694)
		(end 71.7042 -18.31467)
		(width 0.1143)
		(layer "In9.Cu")
		(net "P2E_CPU_SAS_RX_DN1")
	)
	(segment
		(start 71.60895 -22.95525)
		(end 71.60895 -22.2758)
		(width 0.1143)
		(layer "In9.Cu")
		(net "P2E_CPU_SAS_RX_DN1")
	)
	(segment
		(start 71.033894 -27.9908)
		(end 71.21779 -27.806904)
		(width 0.1143)
		(layer "In9.Cu")
		(net "P2E_CPU_SAS_RX_DN1")
	)
	(segment
		(start 71.21779 -27.806904)
		(end 71.21779 -26.99639)
		(width 0.1143)
		(layer "In9.Cu")
		(net "P2E_CPU_SAS_RX_DN1")
	)
	(segment
		(start 70.272148 -33.828482)
		(end 69.79285 -33.349184)
		(width 0.1143)
		(layer "In9.Cu")
		(net "P2E_CPU_SAS_RX_DN1")
	)
	(segment
		(start 74.7649 -15.801594)
		(end 74.7649 -14.3129)
		(width 0.1143)
		(layer "In9.Cu")
		(net "P2E_CPU_SAS_RX_DN1")
	)
	(segment
		(start 76.103734 -47.8536)
		(end 75.1205 -46.870366)
		(width 0.1143)
		(layer "In9.Cu")
		(net "P2E_CPU_SAS_RX_DN1")
	)
	(segment
		(start 76.454 -47.8536)
		(end 76.103734 -47.8536)
		(width 0.1143)
		(layer "In9.Cu")
		(net "P2E_CPU_SAS_RX_DN1")
	)
	(segment
		(start 72.771 -41.555416)
		(end 72.771 -36.327334)
		(width 0.1143)
		(layer "In9.Cu")
		(net "P2E_CPU_SAS_RX_DN1")
	)
	(segment
		(start 70.104 -21.3868)
		(end 70.104 -20.6502)
		(width 0.1143)
		(layer "In9.Cu")
		(net "P2E_CPU_SAS_RX_DN1")
	)
	(segment
		(start 71.058786 -34.916872)
		(end 71.058786 -34.61512)
		(width 0.1143)
		(layer "In9.Cu")
		(net "P2E_CPU_SAS_RX_DN1")
	)
	(segment
		(start 70.514464 -34.37255)
		(end 70.272148 -34.130234)
		(width 0.1143)
		(layer "In9.Cu")
		(net "P2E_CPU_SAS_RX_DN1")
	)
	(segment
		(start 71.21779 -26.99639)
		(end 70.9422 -26.7208)
		(width 0.1143)
		(layer "In9.Cu")
		(net "P2E_CPU_SAS_RX_DN1")
	)
	(segment
		(start 71.60895 -22.2758)
		(end 71.10095 -21.7678)
		(width 0.1143)
		(layer "In9.Cu")
		(net "P2E_CPU_SAS_RX_DN1")
	)
	(segment
		(start 72.771 -36.327334)
		(end 71.602854 -35.159188)
		(width 0.1143)
		(layer "In9.Cu")
		(net "P2E_CPU_SAS_RX_DN1")
	)
	(segment
		(start 75.684634 -10.980166)
		(end 75.684634 -10.59815)
		(width 0.1143)
		(layer "In9.Cu")
		(net "P2E_CPU_SAS_RX_DN1")
	)
	(segment
		(start 79.053944 -47.361094)
		(end 79.342488 -47.361094)
		(width 0.1016)
		(layer "F.Cu")
		(net "P2E_CPU_SAS_RX_DP0")
	)
	(segment
		(start 81.028794 -48.102774)
		(end 81.308448 -48.102774)
		(width 0.1016)
		(layer "F.Cu")
		(net "P2E_CPU_SAS_RX_DP0")
	)
	(segment
		(start 80.021176 -8.7757)
		(end 80.021176 -10.02792)
		(width 0.1397)
		(layer "F.Cu")
		(net "P2E_CPU_SAS_RX_DP0")
	)
	(segment
		(start 80.241648 -48.280066)
		(end 80.419956 -48.458374)
		(width 0.1016)
		(layer "F.Cu")
		(net "P2E_CPU_SAS_RX_DP0")
	)
	(segment
		(start 80.241648 -48.260254)
		(end 80.241648 -48.280066)
		(width 0.1016)
		(layer "F.Cu")
		(net "P2E_CPU_SAS_RX_DP0")
	)
	(segment
		(start 80.021176 -10.02792)
		(end 80.328516 -10.33526)
		(width 0.1397)
		(layer "F.Cu")
		(net "P2E_CPU_SAS_RX_DP0")
	)
	(segment
		(start 80.349852 -6.195568)
		(end 80.349852 -8.447024)
		(width 0.1397)
		(layer "F.Cu")
		(net "P2E_CPU_SAS_RX_DP0")
	)
	(segment
		(start 80.419956 -48.458374)
		(end 80.673194 -48.458374)
		(width 0.1016)
		(layer "F.Cu")
		(net "P2E_CPU_SAS_RX_DP0")
	)
	(segment
		(start 80.349852 -8.447024)
		(end 80.021176 -8.7757)
		(width 0.1397)
		(layer "F.Cu")
		(net "P2E_CPU_SAS_RX_DP0")
	)
	(segment
		(start 79.342488 -47.361094)
		(end 80.241648 -48.260254)
		(width 0.1016)
		(layer "F.Cu")
		(net "P2E_CPU_SAS_RX_DP0")
	)
	(segment
		(start 78.6638 -47.751238)
		(end 79.053944 -47.361094)
		(width 0.1016)
		(layer "F.Cu")
		(net "P2E_CPU_SAS_RX_DP0")
	)
	(segment
		(start 80.673194 -48.458374)
		(end 81.028794 -48.102774)
		(width 0.1016)
		(layer "F.Cu")
		(net "P2E_CPU_SAS_RX_DP0")
	)
	(via
		(at 80.328516 -10.33526)
		(size 0.508)
		(drill 0.254)
		(layers "F.Cu" "B.Cu")
		(net "P2E_CPU_SAS_RX_DP0")
	)
	(via
		(at 78.6638 -47.751238)
		(size 0.4318)
		(drill 0.2032)
		(layers "F.Cu" "B.Cu")
		(net "P2E_CPU_SAS_RX_DP0")
	)
	(segment
		(start 76.157836 -18.6436)
		(end 77.851 -18.6436)
		(width 0.1143)
		(layer "In9.Cu")
		(net "P2E_CPU_SAS_RX_DP0")
	)
	(segment
		(start 73.1139 -21.663406)
		(end 73.621138 -21.156168)
		(width 0.1143)
		(layer "In9.Cu")
		(net "P2E_CPU_SAS_RX_DP0")
	)
	(segment
		(start 79.59852 -16.895318)
		(end 79.59852 -16.002)
		(width 0.1143)
		(layer "In9.Cu")
		(net "P2E_CPU_SAS_RX_DP0")
	)
	(segment
		(start 74.3966 -19.9136)
		(end 74.887836 -19.9136)
		(width 0.1143)
		(layer "In9.Cu")
		(net "P2E_CPU_SAS_RX_DP0")
	)
	(segment
		(start 72.71385 -23.689056)
		(end 73.1139 -23.289006)
		(width 0.1143)
		(layer "In9.Cu")
		(net "P2E_CPU_SAS_RX_DP0")
	)
	(segment
		(start 78.5114 -47.598838)
		(end 78.5114 -47.1678)
		(width 0.1143)
		(layer "In9.Cu")
		(net "P2E_CPU_SAS_RX_DP0")
	)
	(segment
		(start 77.851 -18.6436)
		(end 77.94752 -18.54708)
		(width 0.1143)
		(layer "In9.Cu")
		(net "P2E_CPU_SAS_RX_DP0")
	)
	(segment
		(start 80.01 -11.008106)
		(end 80.01 -10.653776)
		(width 0.1143)
		(layer "In9.Cu")
		(net "P2E_CPU_SAS_RX_DP0")
	)
	(segment
		(start 73.6854 -19.2024)
		(end 74.3966 -19.9136)
		(width 0.1143)
		(layer "In9.Cu")
		(net "P2E_CPU_SAS_RX_DP0")
	)
	(segment
		(start 78.5114 -47.1678)
		(end 78.003908 -46.660308)
		(width 0.1143)
		(layer "In9.Cu")
		(net "P2E_CPU_SAS_RX_DP0")
	)
	(segment
		(start 73.621138 -20.471638)
		(end 73.1139 -19.9644)
		(width 0.1143)
		(layer "In9.Cu")
		(net "P2E_CPU_SAS_RX_DP0")
	)
	(segment
		(start 73.415906 -19.2024)
		(end 73.6854 -19.2024)
		(width 0.1143)
		(layer "In9.Cu")
		(net "P2E_CPU_SAS_RX_DP0")
	)
	(segment
		(start 71.993506 -31.3182)
		(end 73.123806 -31.3182)
		(width 0.1143)
		(layer "In9.Cu")
		(net "P2E_CPU_SAS_RX_DP0")
	)
	(segment
		(start 73.6473 -30.050994)
		(end 72.71385 -29.117544)
		(width 0.1143)
		(layer "In9.Cu")
		(net "P2E_CPU_SAS_RX_DP0")
	)
	(segment
		(start 76.7334 -16.1798)
		(end 76.2 -15.6464)
		(width 0.1143)
		(layer "In9.Cu")
		(net "P2E_CPU_SAS_RX_DP0")
	)
	(segment
		(start 73.6473 -32.692594)
		(end 72.907906 -31.9532)
		(width 0.1143)
		(layer "In9.Cu")
		(net "P2E_CPU_SAS_RX_DP0")
	)
	(segment
		(start 76.2127 -46.3296)
		(end 76.2127 -43.182794)
		(width 0.1143)
		(layer "In9.Cu")
		(net "P2E_CPU_SAS_RX_DP0")
	)
	(segment
		(start 78.3844 -11.3284)
		(end 79.689706 -11.3284)
		(width 0.1143)
		(layer "In9.Cu")
		(net "P2E_CPU_SAS_RX_DP0")
	)
	(segment
		(start 79.06512 -15.4686)
		(end 78.206854 -15.4686)
		(width 0.1143)
		(layer "In9.Cu")
		(net "P2E_CPU_SAS_RX_DP0")
	)
	(segment
		(start 72.907906 -31.9532)
		(end 71.968106 -31.9532)
		(width 0.1143)
		(layer "In9.Cu")
		(net "P2E_CPU_SAS_RX_DP0")
	)
	(segment
		(start 78.6638 -47.751238)
		(end 78.5114 -47.598838)
		(width 0.1143)
		(layer "In9.Cu")
		(net "P2E_CPU_SAS_RX_DP0")
	)
	(segment
		(start 72.71385 -29.117544)
		(end 72.71385 -23.689056)
		(width 0.1143)
		(layer "In9.Cu")
		(net "P2E_CPU_SAS_RX_DP0")
	)
	(segment
		(start 73.1139 -19.9644)
		(end 73.1139 -19.504406)
		(width 0.1143)
		(layer "In9.Cu")
		(net "P2E_CPU_SAS_RX_DP0")
	)
	(segment
		(start 76.2 -15.6464)
		(end 76.2 -13.5128)
		(width 0.1143)
		(layer "In9.Cu")
		(net "P2E_CPU_SAS_RX_DP0")
	)
	(segment
		(start 71.7804 -31.765494)
		(end 71.7804 -31.531306)
		(width 0.1143)
		(layer "In9.Cu")
		(net "P2E_CPU_SAS_RX_DP0")
	)
	(segment
		(start 71.968106 -31.9532)
		(end 71.7804 -31.765494)
		(width 0.1143)
		(layer "In9.Cu")
		(net "P2E_CPU_SAS_RX_DP0")
	)
	(segment
		(start 78.003908 -46.660308)
		(end 76.543408 -46.660308)
		(width 0.1143)
		(layer "In9.Cu")
		(net "P2E_CPU_SAS_RX_DP0")
	)
	(segment
		(start 77.94752 -18.54708)
		(end 77.947266 -18.54708)
		(width 0.1143)
		(layer "In9.Cu")
		(net "P2E_CPU_SAS_RX_DP0")
	)
	(segment
		(start 79.689706 -11.3284)
		(end 80.01 -11.008106)
		(width 0.1143)
		(layer "In9.Cu")
		(net "P2E_CPU_SAS_RX_DP0")
	)
	(segment
		(start 74.0537 -41.023794)
		(end 74.0537 -35.395916)
		(width 0.1143)
		(layer "In9.Cu")
		(net "P2E_CPU_SAS_RX_DP0")
	)
	(segment
		(start 73.6473 -34.989516)
		(end 73.6473 -32.692594)
		(width 0.1143)
		(layer "In9.Cu")
		(net "P2E_CPU_SAS_RX_DP0")
	)
	(segment
		(start 74.887836 -19.9136)
		(end 76.157836 -18.6436)
		(width 0.1143)
		(layer "In9.Cu")
		(net "P2E_CPU_SAS_RX_DP0")
	)
	(segment
		(start 80.01 -10.653776)
		(end 80.328516 -10.33526)
		(width 0.1143)
		(layer "In9.Cu")
		(net "P2E_CPU_SAS_RX_DP0")
	)
	(segment
		(start 77.947266 -18.54708)
		(end 79.59852 -16.895318)
		(width 0.1143)
		(layer "In9.Cu")
		(net "P2E_CPU_SAS_RX_DP0")
	)
	(segment
		(start 74.0537 -35.395916)
		(end 73.6473 -34.989516)
		(width 0.1143)
		(layer "In9.Cu")
		(net "P2E_CPU_SAS_RX_DP0")
	)
	(segment
		(start 73.1139 -19.504406)
		(end 73.415906 -19.2024)
		(width 0.1143)
		(layer "In9.Cu")
		(net "P2E_CPU_SAS_RX_DP0")
	)
	(segment
		(start 76.2127 -43.182794)
		(end 74.0537 -41.023794)
		(width 0.1143)
		(layer "In9.Cu")
		(net "P2E_CPU_SAS_RX_DP0")
	)
	(segment
		(start 79.59852 -16.002)
		(end 79.06512 -15.4686)
		(width 0.1143)
		(layer "In9.Cu")
		(net "P2E_CPU_SAS_RX_DP0")
	)
	(segment
		(start 76.543408 -46.660308)
		(end 76.2127 -46.3296)
		(width 0.1143)
		(layer "In9.Cu")
		(net "P2E_CPU_SAS_RX_DP0")
	)
	(segment
		(start 77.4954 -16.1798)
		(end 76.7334 -16.1798)
		(width 0.1143)
		(layer "In9.Cu")
		(net "P2E_CPU_SAS_RX_DP0")
	)
	(segment
		(start 73.621138 -21.156168)
		(end 73.621138 -20.471638)
		(width 0.1143)
		(layer "In9.Cu")
		(net "P2E_CPU_SAS_RX_DP0")
	)
	(segment
		(start 73.1139 -23.289006)
		(end 73.1139 -21.663406)
		(width 0.1143)
		(layer "In9.Cu")
		(net "P2E_CPU_SAS_RX_DP0")
	)
	(segment
		(start 73.123806 -31.3182)
		(end 73.6473 -30.794706)
		(width 0.1143)
		(layer "In9.Cu")
		(net "P2E_CPU_SAS_RX_DP0")
	)
	(segment
		(start 78.206854 -15.4686)
		(end 77.4954 -16.1798)
		(width 0.1143)
		(layer "In9.Cu")
		(net "P2E_CPU_SAS_RX_DP0")
	)
	(segment
		(start 76.2 -13.5128)
		(end 78.3844 -11.3284)
		(width 0.1143)
		(layer "In9.Cu")
		(net "P2E_CPU_SAS_RX_DP0")
	)
	(segment
		(start 73.6473 -30.794706)
		(end 73.6473 -30.050994)
		(width 0.1143)
		(layer "In9.Cu")
		(net "P2E_CPU_SAS_RX_DP0")
	)
	(segment
		(start 71.7804 -31.531306)
		(end 71.993506 -31.3182)
		(width 0.1143)
		(layer "In9.Cu")
		(net "P2E_CPU_SAS_RX_DP0")
	)
	(segment
		(start 79.678276 -10.02792)
		(end 79.370936 -10.33526)
		(width 0.1397)
		(layer "F.Cu")
		(net "P2E_CPU_SAS_RX_DN0")
	)
	(segment
		(start 79.349854 -6.195568)
		(end 79.349854 -8.447278)
		(width 0.1397)
		(layer "F.Cu")
		(net "P2E_CPU_SAS_RX_DN0")
	)
	(segment
		(start 80.422496 -48.153574)
		(end 80.546448 -48.153574)
		(width 0.1016)
		(layer "F.Cu")
		(net "P2E_CPU_SAS_RX_DN0")
	)
	(segment
		(start 79.426816 -47.157894)
		(end 80.422496 -48.153574)
		(width 0.1016)
		(layer "F.Cu")
		(net "P2E_CPU_SAS_RX_DN0")
	)
	(segment
		(start 79.350616 -47.156624)
		(end 79.351886 -47.157894)
		(width 0.1016)
		(layer "F.Cu")
		(net "P2E_CPU_SAS_RX_DN0")
	)
	(segment
		(start 79.678276 -8.7757)
		(end 79.678276 -10.02792)
		(width 0.1397)
		(layer "F.Cu")
		(net "P2E_CPU_SAS_RX_DN0")
	)
	(segment
		(start 79.349854 -8.447278)
		(end 79.678276 -8.7757)
		(width 0.1397)
		(layer "F.Cu")
		(net "P2E_CPU_SAS_RX_DN0")
	)
	(segment
		(start 78.700376 -47.156624)
		(end 79.350616 -47.156624)
		(width 0.1016)
		(layer "F.Cu")
		(net "P2E_CPU_SAS_RX_DN0")
	)
	(segment
		(start 79.351886 -47.157894)
		(end 79.426816 -47.157894)
		(width 0.1016)
		(layer "F.Cu")
		(net "P2E_CPU_SAS_RX_DN0")
	)
	(segment
		(start 78.105 -47.752)
		(end 78.700376 -47.156624)
		(width 0.1016)
		(layer "F.Cu")
		(net "P2E_CPU_SAS_RX_DN0")
	)
	(via
		(at 78.105 -47.752)
		(size 0.4318)
		(drill 0.2032)
		(layers "F.Cu" "B.Cu")
		(net "P2E_CPU_SAS_RX_DN0")
	)
	(via
		(at 79.370936 -10.33526)
		(size 0.508)
		(drill 0.254)
		(layers "F.Cu" "B.Cu")
		(net "P2E_CPU_SAS_RX_DN0")
	)
	(segment
		(start 72.38365 -23.55215)
		(end 72.7837 -23.1521)
		(width 0.1143)
		(layer "In9.Cu")
		(net "P2E_CPU_SAS_RX_DN0")
	)
	(segment
		(start 72.17029 -26.173176)
		(end 72.17029 -25.830276)
		(width 0.1143)
		(layer "In9.Cu")
		(net "P2E_CPU_SAS_RX_DN0")
	)
	(segment
		(start 72.7837 -19.3675)
		(end 73.279 -18.8722)
		(width 0.1143)
		(layer "In9.Cu")
		(net "P2E_CPU_SAS_RX_DN0")
	)
	(segment
		(start 72.38365 -27.499056)
		(end 72.17029 -27.285696)
		(width 0.1143)
		(layer "In9.Cu")
		(net "P2E_CPU_SAS_RX_DN0")
	)
	(segment
		(start 72.17029 -25.830276)
		(end 72.38365 -25.616916)
		(width 0.1143)
		(layer "In9.Cu")
		(net "P2E_CPU_SAS_RX_DN0")
	)
	(segment
		(start 78.1812 -47.304706)
		(end 77.867002 -46.990508)
		(width 0.1143)
		(layer "In9.Cu")
		(net "P2E_CPU_SAS_RX_DN0")
	)
	(segment
		(start 79.26832 -16.138906)
		(end 78.928214 -15.7988)
		(width 0.1143)
		(layer "In9.Cu")
		(net "P2E_CPU_SAS_RX_DN0")
	)
	(segment
		(start 73.3171 -35.126422)
		(end 73.3171 -32.8295)
		(width 0.1143)
		(layer "In9.Cu")
		(net "P2E_CPU_SAS_RX_DN0")
	)
	(segment
		(start 78.1812 -47.6758)
		(end 78.1812 -47.304706)
		(width 0.1143)
		(layer "In9.Cu")
		(net "P2E_CPU_SAS_RX_DN0")
	)
	(segment
		(start 72.9869 -30.988)
		(end 73.3171 -30.6578)
		(width 0.1143)
		(layer "In9.Cu")
		(net "P2E_CPU_SAS_RX_DN0")
	)
	(segment
		(start 72.38365 -25.616916)
		(end 72.38365 -23.55215)
		(width 0.1143)
		(layer "In9.Cu")
		(net "P2E_CPU_SAS_RX_DN0")
	)
	(segment
		(start 72.17029 -27.285696)
		(end 72.17029 -26.942796)
		(width 0.1143)
		(layer "In9.Cu")
		(net "P2E_CPU_SAS_RX_DN0")
	)
	(segment
		(start 75.8825 -43.3197)
		(end 73.7235 -41.1607)
		(width 0.1143)
		(layer "In9.Cu")
		(net "P2E_CPU_SAS_RX_DN0")
	)
	(segment
		(start 77.867002 -46.990508)
		(end 76.406502 -46.990508)
		(width 0.1143)
		(layer "In9.Cu")
		(net "P2E_CPU_SAS_RX_DN0")
	)
	(segment
		(start 72.771 -32.2834)
		(end 71.8312 -32.2834)
		(width 0.1143)
		(layer "In9.Cu")
		(net "P2E_CPU_SAS_RX_DN0")
	)
	(segment
		(start 79.6798 -10.8712)
		(end 79.6798 -10.644124)
		(width 0.1143)
		(layer "In9.Cu")
		(net "P2E_CPU_SAS_RX_DN0")
	)
	(segment
		(start 73.279 -18.8722)
		(end 73.822306 -18.8722)
		(width 0.1143)
		(layer "In9.Cu")
		(net "P2E_CPU_SAS_RX_DN0")
	)
	(segment
		(start 79.5528 -10.9982)
		(end 79.6798 -10.8712)
		(width 0.1143)
		(layer "In9.Cu")
		(net "P2E_CPU_SAS_RX_DN0")
	)
	(segment
		(start 71.4502 -31.3944)
		(end 71.8566 -30.988)
		(width 0.1143)
		(layer "In9.Cu")
		(net "P2E_CPU_SAS_RX_DN0")
	)
	(segment
		(start 73.290938 -21.019262)
		(end 73.290938 -20.608544)
		(width 0.1143)
		(layer "In9.Cu")
		(net "P2E_CPU_SAS_RX_DN0")
	)
	(segment
		(start 72.17029 -26.942796)
		(end 72.38365 -26.729436)
		(width 0.1143)
		(layer "In9.Cu")
		(net "P2E_CPU_SAS_RX_DN0")
	)
	(segment
		(start 73.3171 -30.6578)
		(end 73.3171 -30.1879)
		(width 0.1143)
		(layer "In9.Cu")
		(net "P2E_CPU_SAS_RX_DN0")
	)
	(segment
		(start 76.406502 -46.990508)
		(end 75.8825 -46.466506)
		(width 0.1143)
		(layer "In9.Cu")
		(net "P2E_CPU_SAS_RX_DN0")
	)
	(segment
		(start 78.105 -47.752)
		(end 78.1812 -47.6758)
		(width 0.1143)
		(layer "In9.Cu")
		(net "P2E_CPU_SAS_RX_DN0")
	)
	(segment
		(start 72.7837 -20.101306)
		(end 72.7837 -19.3675)
		(width 0.1143)
		(layer "In9.Cu")
		(net "P2E_CPU_SAS_RX_DN0")
	)
	(segment
		(start 77.71384 -18.3134)
		(end 79.26832 -16.758412)
		(width 0.1143)
		(layer "In9.Cu")
		(net "P2E_CPU_SAS_RX_DN0")
	)
	(segment
		(start 71.8566 -30.988)
		(end 72.9869 -30.988)
		(width 0.1143)
		(layer "In9.Cu")
		(net "P2E_CPU_SAS_RX_DN0")
	)
	(segment
		(start 71.4502 -31.9024)
		(end 71.4502 -31.3944)
		(width 0.1143)
		(layer "In9.Cu")
		(net "P2E_CPU_SAS_RX_DN0")
	)
	(segment
		(start 73.7235 -35.532822)
		(end 73.3171 -35.126422)
		(width 0.1143)
		(layer "In9.Cu")
		(net "P2E_CPU_SAS_RX_DN0")
	)
	(segment
		(start 75.8698 -15.783306)
		(end 75.8698 -13.375894)
		(width 0.1143)
		(layer "In9.Cu")
		(net "P2E_CPU_SAS_RX_DN0")
	)
	(segment
		(start 72.38365 -26.729436)
		(end 72.38365 -26.386536)
		(width 0.1143)
		(layer "In9.Cu")
		(net "P2E_CPU_SAS_RX_DN0")
	)
	(segment
		(start 78.34376 -15.7988)
		(end 77.632306 -16.51)
		(width 0.1143)
		(layer "In9.Cu")
		(net "P2E_CPU_SAS_RX_DN0")
	)
	(segment
		(start 77.632306 -16.51)
		(end 76.596494 -16.51)
		(width 0.1143)
		(layer "In9.Cu")
		(net "P2E_CPU_SAS_RX_DN0")
	)
	(segment
		(start 73.7235 -41.1607)
		(end 73.7235 -35.532822)
		(width 0.1143)
		(layer "In9.Cu")
		(net "P2E_CPU_SAS_RX_DN0")
	)
	(segment
		(start 73.290938 -20.608544)
		(end 72.7837 -20.101306)
		(width 0.1143)
		(layer "In9.Cu")
		(net "P2E_CPU_SAS_RX_DN0")
	)
	(segment
		(start 76.02093 -18.3134)
		(end 77.71384 -18.3134)
		(width 0.1143)
		(layer "In9.Cu")
		(net "P2E_CPU_SAS_RX_DN0")
	)
	(segment
		(start 72.7837 -21.5265)
		(end 73.290938 -21.019262)
		(width 0.1143)
		(layer "In9.Cu")
		(net "P2E_CPU_SAS_RX_DN0")
	)
	(segment
		(start 75.8825 -46.466506)
		(end 75.8825 -43.3197)
		(width 0.1143)
		(layer "In9.Cu")
		(net "P2E_CPU_SAS_RX_DN0")
	)
	(segment
		(start 72.38365 -29.25445)
		(end 72.38365 -27.499056)
		(width 0.1143)
		(layer "In9.Cu")
		(net "P2E_CPU_SAS_RX_DN0")
	)
	(segment
		(start 79.26832 -16.758412)
		(end 79.26832 -16.138906)
		(width 0.1143)
		(layer "In9.Cu")
		(net "P2E_CPU_SAS_RX_DN0")
	)
	(segment
		(start 71.8312 -32.2834)
		(end 71.4502 -31.9024)
		(width 0.1143)
		(layer "In9.Cu")
		(net "P2E_CPU_SAS_RX_DN0")
	)
	(segment
		(start 78.928214 -15.7988)
		(end 78.34376 -15.7988)
		(width 0.1143)
		(layer "In9.Cu")
		(net "P2E_CPU_SAS_RX_DN0")
	)
	(segment
		(start 74.533506 -19.5834)
		(end 74.75093 -19.5834)
		(width 0.1143)
		(layer "In9.Cu")
		(net "P2E_CPU_SAS_RX_DN0")
	)
	(segment
		(start 72.7837 -23.1521)
		(end 72.7837 -21.5265)
		(width 0.1143)
		(layer "In9.Cu")
		(net "P2E_CPU_SAS_RX_DN0")
	)
	(segment
		(start 75.8698 -13.375894)
		(end 78.247494 -10.9982)
		(width 0.1143)
		(layer "In9.Cu")
		(net "P2E_CPU_SAS_RX_DN0")
	)
	(segment
		(start 74.75093 -19.5834)
		(end 76.02093 -18.3134)
		(width 0.1143)
		(layer "In9.Cu")
		(net "P2E_CPU_SAS_RX_DN0")
	)
	(segment
		(start 76.596494 -16.51)
		(end 75.8698 -15.783306)
		(width 0.1143)
		(layer "In9.Cu")
		(net "P2E_CPU_SAS_RX_DN0")
	)
	(segment
		(start 73.822306 -18.8722)
		(end 74.533506 -19.5834)
		(width 0.1143)
		(layer "In9.Cu")
		(net "P2E_CPU_SAS_RX_DN0")
	)
	(segment
		(start 78.247494 -10.9982)
		(end 79.5528 -10.9982)
		(width 0.1143)
		(layer "In9.Cu")
		(net "P2E_CPU_SAS_RX_DN0")
	)
	(segment
		(start 79.6798 -10.644124)
		(end 79.370936 -10.33526)
		(width 0.1143)
		(layer "In9.Cu")
		(net "P2E_CPU_SAS_RX_DN0")
	)
	(segment
		(start 73.3171 -32.8295)
		(end 72.771 -32.2834)
		(width 0.1143)
		(layer "In9.Cu")
		(net "P2E_CPU_SAS_RX_DN0")
	)
	(segment
		(start 72.38365 -26.386536)
		(end 72.17029 -26.173176)
		(width 0.1143)
		(layer "In9.Cu")
		(net "P2E_CPU_SAS_RX_DN0")
	)
	(segment
		(start 73.3171 -30.1879)
		(end 72.38365 -29.25445)
		(width 0.1143)
		(layer "In9.Cu")
		(net "P2E_CPU_SAS_RX_DN0")
	)
	(segment
		(start 94.094808 -48.402494)
		(end 93.75394 -48.743362)
		(width 0.1397)
		(layer "F.Cu")
		(net "P2E_CPU_NGFF_RX_DN14")
	)
	(segment
		(start 9.6266 -61.849)
		(end 8.9662 -61.849)
		(width 0.1397)
		(layer "F.Cu")
		(net "P2E_CPU_NGFF_RX_DN14")
	)
	(segment
		(start 93.75394 -48.743362)
		(end 93.752924 -48.743362)
		(width 0.1397)
		(layer "F.Cu")
		(net "P2E_CPU_NGFF_RX_DN14")
	)
	(via
		(at 93.752924 -48.743362)
		(size 0.4318)
		(drill 0.2032)
		(layers "F.Cu" "B.Cu")
		(net "P2E_CPU_NGFF_RX_DN14")
	)
	(via
		(at 9.6266 -61.849)
		(size 0.508)
		(drill 0.254)
		(layers "F.Cu" "B.Cu")
		(net "P2E_CPU_NGFF_RX_DN14")
	)
	(segment
		(start 14.0716 -58.099706)
		(end 10.614406 -61.5569)
		(width 0.1143)
		(layer "In7.Cu")
		(net "P2E_CPU_NGFF_RX_DN14")
	)
	(segment
		(start 82.641694 -60.9346)
		(end 82.07375 -60.366656)
		(width 0.1143)
		(layer "In7.Cu")
		(net "P2E_CPU_NGFF_RX_DN14")
	)
	(segment
		(start 22.102572 -51.7906)
		(end 19.6596 -51.7906)
		(width 0.1143)
		(layer "In7.Cu")
		(net "P2E_CPU_NGFF_RX_DN14")
	)
	(segment
		(start 93.31325 -49.594008)
		(end 93.19387 -49.713388)
		(width 0.1016)
		(layer "In7.Cu")
		(net "P2E_CPU_NGFF_RX_DN14")
	)
	(segment
		(start 93.752924 -48.743362)
		(end 93.489526 -48.479964)
		(width 0.1016)
		(layer "In7.Cu")
		(net "P2E_CPU_NGFF_RX_DN14")
	)
	(segment
		(start 86.0044 -57.667906)
		(end 86.0044 -58.760106)
		(width 0.1143)
		(layer "In7.Cu")
		(net "P2E_CPU_NGFF_RX_DN14")
	)
	(segment
		(start 69.726556 -54.5846)
		(end 68.234306 -56.07685)
		(width 0.1143)
		(layer "In7.Cu")
		(net "P2E_CPU_NGFF_RX_DN14")
	)
	(segment
		(start 19.6596 -51.7906)
		(end 18.7325 -52.7177)
		(width 0.1143)
		(layer "In7.Cu")
		(net "P2E_CPU_NGFF_RX_DN14")
	)
	(segment
		(start 82.07375 -60.366656)
		(end 82.07375 -59.97575)
		(width 0.1143)
		(layer "In7.Cu")
		(net "P2E_CPU_NGFF_RX_DN14")
	)
	(segment
		(start 91.676728 -56.3372)
		(end 90.161872 -56.3372)
		(width 0.1016)
		(layer "In7.Cu")
		(net "P2E_CPU_NGFF_RX_DN14")
	)
	(segment
		(start 18.034 -52.7177)
		(end 15.384526 -55.367174)
		(width 0.1143)
		(layer "In7.Cu")
		(net "P2E_CPU_NGFF_RX_DN14")
	)
	(segment
		(start 31.746444 -49.81575)
		(end 27.01925 -49.81575)
		(width 0.1143)
		(layer "In7.Cu")
		(net "P2E_CPU_NGFF_RX_DN14")
	)
	(segment
		(start 86.0044 -58.760106)
		(end 83.829906 -60.9346)
		(width 0.1143)
		(layer "In7.Cu")
		(net "P2E_CPU_NGFF_RX_DN14")
	)
	(segment
		(start 88.071706 -56.2864)
		(end 87.385906 -56.2864)
		(width 0.1143)
		(layer "In7.Cu")
		(net "P2E_CPU_NGFF_RX_DN14")
	)
	(segment
		(start 93.345 -51.7652)
		(end 93.345 -53.246528)
		(width 0.1016)
		(layer "In7.Cu")
		(net "P2E_CPU_NGFF_RX_DN14")
	)
	(segment
		(start 77.587094 -58.4962)
		(end 76.57465 -57.483756)
		(width 0.1143)
		(layer "In7.Cu")
		(net "P2E_CPU_NGFF_RX_DN14")
	)
	(segment
		(start 10.614406 -61.5569)
		(end 9.9187 -61.5569)
		(width 0.1143)
		(layer "In7.Cu")
		(net "P2E_CPU_NGFF_RX_DN14")
	)
	(segment
		(start 92.5576 -54.033928)
		(end 92.5576 -55.456328)
		(width 0.1016)
		(layer "In7.Cu")
		(net "P2E_CPU_NGFF_RX_DN14")
	)
	(segment
		(start 14.35862 -55.367174)
		(end 14.0716 -55.654194)
		(width 0.1143)
		(layer "In7.Cu")
		(net "P2E_CPU_NGFF_RX_DN14")
	)
	(segment
		(start 76.57465 -56.336946)
		(end 75.025504 -54.7878)
		(width 0.1143)
		(layer "In7.Cu")
		(net "P2E_CPU_NGFF_RX_DN14")
	)
	(segment
		(start 15.384526 -55.367174)
		(end 14.35862 -55.367174)
		(width 0.1143)
		(layer "In7.Cu")
		(net "P2E_CPU_NGFF_RX_DN14")
	)
	(segment
		(start 72.39 -54.5846)
		(end 69.726556 -54.5846)
		(width 0.1143)
		(layer "In7.Cu")
		(net "P2E_CPU_NGFF_RX_DN14")
	)
	(segment
		(start 27.01925 -49.81575)
		(end 25.577546 -51.257454)
		(width 0.1143)
		(layer "In7.Cu")
		(net "P2E_CPU_NGFF_RX_DN14")
	)
	(segment
		(start 93.19387 -51.61407)
		(end 93.345 -51.7652)
		(width 0.1016)
		(layer "In7.Cu")
		(net "P2E_CPU_NGFF_RX_DN14")
	)
	(segment
		(start 93.489526 -48.479964)
		(end 93.380814 -48.479964)
		(width 0.1016)
		(layer "In7.Cu")
		(net "P2E_CPU_NGFF_RX_DN14")
	)
	(segment
		(start 93.380814 -48.479964)
		(end 93.31325 -48.547528)
		(width 0.1016)
		(layer "In7.Cu")
		(net "P2E_CPU_NGFF_RX_DN14")
	)
	(segment
		(start 57.311036 -53.3146)
		(end 48.326294 -53.3146)
		(width 0.1143)
		(layer "In7.Cu")
		(net "P2E_CPU_NGFF_RX_DN14")
	)
	(segment
		(start 9.9187 -61.5569)
		(end 9.6266 -61.849)
		(width 0.1143)
		(layer "In7.Cu")
		(net "P2E_CPU_NGFF_RX_DN14")
	)
	(segment
		(start 83.829906 -60.9346)
		(end 82.641694 -60.9346)
		(width 0.1143)
		(layer "In7.Cu")
		(net "P2E_CPU_NGFF_RX_DN14")
	)
	(segment
		(start 38.123622 -52.2859)
		(end 34.216594 -52.2859)
		(width 0.1143)
		(layer "In7.Cu")
		(net "P2E_CPU_NGFF_RX_DN14")
	)
	(segment
		(start 90.161872 -56.3372)
		(end 89.831672 -56.007)
		(width 0.1016)
		(layer "In7.Cu")
		(net "P2E_CPU_NGFF_RX_DN14")
	)
	(segment
		(start 43.189906 -52.1462)
		(end 42.681906 -52.6542)
		(width 0.1143)
		(layer "In7.Cu")
		(net "P2E_CPU_NGFF_RX_DN14")
	)
	(segment
		(start 93.31325 -48.547528)
		(end 93.31325 -49.594008)
		(width 0.1016)
		(layer "In7.Cu")
		(net "P2E_CPU_NGFF_RX_DN14")
	)
	(segment
		(start 89.5858 -56.0705)
		(end 89.5604 -56.0705)
		(width 0.1016)
		(layer "In7.Cu")
		(net "P2E_CPU_NGFF_RX_DN14")
	)
	(segment
		(start 93.345 -53.246528)
		(end 92.5576 -54.033928)
		(width 0.1016)
		(layer "In7.Cu")
		(net "P2E_CPU_NGFF_RX_DN14")
	)
	(segment
		(start 89.831672 -56.007)
		(end 89.6493 -56.007)
		(width 0.1016)
		(layer "In7.Cu")
		(net "P2E_CPU_NGFF_RX_DN14")
	)
	(segment
		(start 93.19387 -49.713388)
		(end 93.19387 -51.61407)
		(width 0.1016)
		(layer "In7.Cu")
		(net "P2E_CPU_NGFF_RX_DN14")
	)
	(segment
		(start 47.157894 -52.1462)
		(end 43.189906 -52.1462)
		(width 0.1143)
		(layer "In7.Cu")
		(net "P2E_CPU_NGFF_RX_DN14")
	)
	(segment
		(start 38.491922 -52.6542)
		(end 38.123622 -52.2859)
		(width 0.1143)
		(layer "In7.Cu")
		(net "P2E_CPU_NGFF_RX_DN14")
	)
	(segment
		(start 89.5604 -56.0705)
		(end 88.287606 -56.0705)
		(width 0.1143)
		(layer "In7.Cu")
		(net "P2E_CPU_NGFF_RX_DN14")
	)
	(segment
		(start 68.234306 -56.07685)
		(end 60.073286 -56.07685)
		(width 0.1143)
		(layer "In7.Cu")
		(net "P2E_CPU_NGFF_RX_DN14")
	)
	(segment
		(start 92.5576 -55.456328)
		(end 91.676728 -56.3372)
		(width 0.1016)
		(layer "In7.Cu")
		(net "P2E_CPU_NGFF_RX_DN14")
	)
	(segment
		(start 25.577546 -51.257454)
		(end 22.635718 -51.257454)
		(width 0.1143)
		(layer "In7.Cu")
		(net "P2E_CPU_NGFF_RX_DN14")
	)
	(segment
		(start 22.635718 -51.257454)
		(end 22.102572 -51.7906)
		(width 0.1143)
		(layer "In7.Cu")
		(net "P2E_CPU_NGFF_RX_DN14")
	)
	(segment
		(start 80.5942 -58.4962)
		(end 77.587094 -58.4962)
		(width 0.1143)
		(layer "In7.Cu")
		(net "P2E_CPU_NGFF_RX_DN14")
	)
	(segment
		(start 89.6493 -56.007)
		(end 89.5858 -56.0705)
		(width 0.1016)
		(layer "In7.Cu")
		(net "P2E_CPU_NGFF_RX_DN14")
	)
	(segment
		(start 18.7325 -52.7177)
		(end 18.034 -52.7177)
		(width 0.1143)
		(layer "In7.Cu")
		(net "P2E_CPU_NGFF_RX_DN14")
	)
	(segment
		(start 82.07375 -59.97575)
		(end 80.5942 -58.4962)
		(width 0.1143)
		(layer "In7.Cu")
		(net "P2E_CPU_NGFF_RX_DN14")
	)
	(segment
		(start 48.326294 -53.3146)
		(end 47.157894 -52.1462)
		(width 0.1143)
		(layer "In7.Cu")
		(net "P2E_CPU_NGFF_RX_DN14")
	)
	(segment
		(start 75.025504 -54.7878)
		(end 72.5932 -54.7878)
		(width 0.1143)
		(layer "In7.Cu")
		(net "P2E_CPU_NGFF_RX_DN14")
	)
	(segment
		(start 14.0716 -55.654194)
		(end 14.0716 -58.099706)
		(width 0.1143)
		(layer "In7.Cu")
		(net "P2E_CPU_NGFF_RX_DN14")
	)
	(segment
		(start 76.57465 -57.483756)
		(end 76.57465 -56.336946)
		(width 0.1143)
		(layer "In7.Cu")
		(net "P2E_CPU_NGFF_RX_DN14")
	)
	(segment
		(start 88.287606 -56.0705)
		(end 88.071706 -56.2864)
		(width 0.1143)
		(layer "In7.Cu")
		(net "P2E_CPU_NGFF_RX_DN14")
	)
	(segment
		(start 60.073286 -56.07685)
		(end 57.311036 -53.3146)
		(width 0.1143)
		(layer "In7.Cu")
		(net "P2E_CPU_NGFF_RX_DN14")
	)
	(segment
		(start 34.216594 -52.2859)
		(end 31.746444 -49.81575)
		(width 0.1143)
		(layer "In7.Cu")
		(net "P2E_CPU_NGFF_RX_DN14")
	)
	(segment
		(start 72.5932 -54.7878)
		(end 72.39 -54.5846)
		(width 0.1143)
		(layer "In7.Cu")
		(net "P2E_CPU_NGFF_RX_DN14")
	)
	(segment
		(start 42.681906 -52.6542)
		(end 38.491922 -52.6542)
		(width 0.1143)
		(layer "In7.Cu")
		(net "P2E_CPU_NGFF_RX_DN14")
	)
	(segment
		(start 87.385906 -56.2864)
		(end 86.0044 -57.667906)
		(width 0.1143)
		(layer "In7.Cu")
		(net "P2E_CPU_NGFF_RX_DN14")
	)
	(segment
		(start 9.6266 -60.96)
		(end 8.9662 -60.96)
		(width 0.1397)
		(layer "F.Cu")
		(net "P2E_CPU_NGFF_RX_DP14")
	)
	(segment
		(start 94.094808 -47.640494)
		(end 93.7768 -47.958248)
		(width 0.1397)
		(layer "F.Cu")
		(net "P2E_CPU_NGFF_RX_DP14")
	)
	(segment
		(start 93.7768 -47.958248)
		(end 93.7768 -48.0314)
		(width 0.1397)
		(layer "F.Cu")
		(net "P2E_CPU_NGFF_RX_DP14")
	)
	(via
		(at 93.7768 -48.0314)
		(size 0.4318)
		(drill 0.2032)
		(layers "F.Cu" "B.Cu")
		(net "P2E_CPU_NGFF_RX_DP14")
	)
	(via
		(at 9.6266 -60.96)
		(size 0.508)
		(drill 0.254)
		(layers "F.Cu" "B.Cu")
		(net "P2E_CPU_NGFF_RX_DP14")
	)
	(segment
		(start 47.2948 -51.816)
		(end 43.053 -51.816)
		(width 0.1143)
		(layer "In7.Cu")
		(net "P2E_CPU_NGFF_RX_DP14")
	)
	(segment
		(start 85.6742 -57.531)
		(end 85.6742 -58.6232)
		(width 0.1143)
		(layer "In7.Cu")
		(net "P2E_CPU_NGFF_RX_DP14")
	)
	(segment
		(start 92.99067 -49.62906)
		(end 92.99067 -51.698398)
		(width 0.1016)
		(layer "In7.Cu")
		(net "P2E_CPU_NGFF_RX_DP14")
	)
	(segment
		(start 77.724 -58.166)
		(end 76.90485 -57.34685)
		(width 0.1143)
		(layer "In7.Cu")
		(net "P2E_CPU_NGFF_RX_DP14")
	)
	(segment
		(start 82.40395 -60.22975)
		(end 82.40395 -59.838844)
		(width 0.1143)
		(layer "In7.Cu")
		(net "P2E_CPU_NGFF_RX_DP14")
	)
	(segment
		(start 82.7786 -60.6044)
		(end 82.40395 -60.22975)
		(width 0.1143)
		(layer "In7.Cu")
		(net "P2E_CPU_NGFF_RX_DP14")
	)
	(segment
		(start 43.053 -51.816)
		(end 42.545 -52.324)
		(width 0.1143)
		(layer "In7.Cu")
		(net "P2E_CPU_NGFF_RX_DP14")
	)
	(segment
		(start 9.8933 -61.2267)
		(end 9.6266 -60.96)
		(width 0.1143)
		(layer "In7.Cu")
		(net "P2E_CPU_NGFF_RX_DP14")
	)
	(segment
		(start 26.882344 -49.48555)
		(end 25.44064 -50.927254)
		(width 0.1143)
		(layer "In7.Cu")
		(net "P2E_CPU_NGFF_RX_DP14")
	)
	(segment
		(start 18.595594 -52.3875)
		(end 17.897094 -52.3875)
		(width 0.1143)
		(layer "In7.Cu")
		(net "P2E_CPU_NGFF_RX_DP14")
	)
	(segment
		(start 88.1507 -55.7403)
		(end 87.9348 -55.9562)
		(width 0.1143)
		(layer "In7.Cu")
		(net "P2E_CPU_NGFF_RX_DP14")
	)
	(segment
		(start 87.249 -55.9562)
		(end 85.6742 -57.531)
		(width 0.1143)
		(layer "In7.Cu")
		(net "P2E_CPU_NGFF_RX_DP14")
	)
	(segment
		(start 93.11005 -48.4632)
		(end 93.11005 -49.50968)
		(width 0.1016)
		(layer "In7.Cu")
		(net "P2E_CPU_NGFF_RX_DP14")
	)
	(segment
		(start 38.260528 -51.9557)
		(end 34.3535 -51.9557)
		(width 0.1143)
		(layer "In7.Cu")
		(net "P2E_CPU_NGFF_RX_DP14")
	)
	(segment
		(start 25.44064 -50.927254)
		(end 22.498812 -50.927254)
		(width 0.1143)
		(layer "In7.Cu")
		(net "P2E_CPU_NGFF_RX_DP14")
	)
	(segment
		(start 48.4632 -52.9844)
		(end 47.2948 -51.816)
		(width 0.1143)
		(layer "In7.Cu")
		(net "P2E_CPU_NGFF_RX_DP14")
	)
	(segment
		(start 69.58965 -54.2544)
		(end 68.0974 -55.74665)
		(width 0.1143)
		(layer "In7.Cu")
		(net "P2E_CPU_NGFF_RX_DP14")
	)
	(segment
		(start 15.24762 -55.036974)
		(end 14.221714 -55.036974)
		(width 0.1143)
		(layer "In7.Cu")
		(net "P2E_CPU_NGFF_RX_DP14")
	)
	(segment
		(start 91.5924 -56.134)
		(end 90.2462 -56.134)
		(width 0.1016)
		(layer "In7.Cu")
		(net "P2E_CPU_NGFF_RX_DP14")
	)
	(segment
		(start 93.1418 -51.849528)
		(end 93.1418 -53.1622)
		(width 0.1016)
		(layer "In7.Cu")
		(net "P2E_CPU_NGFF_RX_DP14")
	)
	(segment
		(start 93.296486 -48.276764)
		(end 93.11005 -48.4632)
		(width 0.1016)
		(layer "In7.Cu")
		(net "P2E_CPU_NGFF_RX_DP14")
	)
	(segment
		(start 76.90485 -56.20004)
		(end 75.16241 -54.4576)
		(width 0.1143)
		(layer "In7.Cu")
		(net "P2E_CPU_NGFF_RX_DP14")
	)
	(segment
		(start 80.731106 -58.166)
		(end 77.724 -58.166)
		(width 0.1143)
		(layer "In7.Cu")
		(net "P2E_CPU_NGFF_RX_DP14")
	)
	(segment
		(start 87.9348 -55.9562)
		(end 87.249 -55.9562)
		(width 0.1143)
		(layer "In7.Cu")
		(net "P2E_CPU_NGFF_RX_DP14")
	)
	(segment
		(start 31.88335 -49.48555)
		(end 26.882344 -49.48555)
		(width 0.1143)
		(layer "In7.Cu")
		(net "P2E_CPU_NGFF_RX_DP14")
	)
	(segment
		(start 21.965666 -51.4604)
		(end 19.522694 -51.4604)
		(width 0.1143)
		(layer "In7.Cu")
		(net "P2E_CPU_NGFF_RX_DP14")
	)
	(segment
		(start 75.16241 -54.4576)
		(end 72.730106 -54.4576)
		(width 0.1143)
		(layer "In7.Cu")
		(net "P2E_CPU_NGFF_RX_DP14")
	)
	(segment
		(start 38.628828 -52.324)
		(end 38.260528 -51.9557)
		(width 0.1143)
		(layer "In7.Cu")
		(net "P2E_CPU_NGFF_RX_DP14")
	)
	(segment
		(start 93.1418 -53.1622)
		(end 92.3544 -53.9496)
		(width 0.1016)
		(layer "In7.Cu")
		(net "P2E_CPU_NGFF_RX_DP14")
	)
	(segment
		(start 76.90485 -57.34685)
		(end 76.90485 -56.20004)
		(width 0.1143)
		(layer "In7.Cu")
		(net "P2E_CPU_NGFF_RX_DP14")
	)
	(segment
		(start 57.447942 -52.9844)
		(end 48.4632 -52.9844)
		(width 0.1143)
		(layer "In7.Cu")
		(net "P2E_CPU_NGFF_RX_DP14")
	)
	(segment
		(start 83.693 -60.6044)
		(end 82.7786 -60.6044)
		(width 0.1143)
		(layer "In7.Cu")
		(net "P2E_CPU_NGFF_RX_DP14")
	)
	(segment
		(start 22.498812 -50.927254)
		(end 21.965666 -51.4604)
		(width 0.1143)
		(layer "In7.Cu")
		(net "P2E_CPU_NGFF_RX_DP14")
	)
	(segment
		(start 17.897094 -52.3875)
		(end 15.24762 -55.036974)
		(width 0.1143)
		(layer "In7.Cu")
		(net "P2E_CPU_NGFF_RX_DP14")
	)
	(segment
		(start 14.221714 -55.036974)
		(end 13.7414 -55.517288)
		(width 0.1143)
		(layer "In7.Cu")
		(net "P2E_CPU_NGFF_RX_DP14")
	)
	(segment
		(start 85.6742 -58.6232)
		(end 83.693 -60.6044)
		(width 0.1143)
		(layer "In7.Cu")
		(net "P2E_CPU_NGFF_RX_DP14")
	)
	(segment
		(start 19.522694 -51.4604)
		(end 18.595594 -52.3875)
		(width 0.1143)
		(layer "In7.Cu")
		(net "P2E_CPU_NGFF_RX_DP14")
	)
	(segment
		(start 72.526906 -54.2544)
		(end 69.58965 -54.2544)
		(width 0.1143)
		(layer "In7.Cu")
		(net "P2E_CPU_NGFF_RX_DP14")
	)
	(segment
		(start 89.916 -55.8038)
		(end 89.6493 -55.8038)
		(width 0.1016)
		(layer "In7.Cu")
		(net "P2E_CPU_NGFF_RX_DP14")
	)
	(segment
		(start 13.7414 -57.9628)
		(end 10.4775 -61.2267)
		(width 0.1143)
		(layer "In7.Cu")
		(net "P2E_CPU_NGFF_RX_DP14")
	)
	(segment
		(start 89.6493 -55.8038)
		(end 89.5858 -55.7403)
		(width 0.1016)
		(layer "In7.Cu")
		(net "P2E_CPU_NGFF_RX_DP14")
	)
	(segment
		(start 92.99067 -51.698398)
		(end 93.1418 -51.849528)
		(width 0.1016)
		(layer "In7.Cu")
		(net "P2E_CPU_NGFF_RX_DP14")
	)
	(segment
		(start 89.5604 -55.7403)
		(end 88.1507 -55.7403)
		(width 0.1143)
		(layer "In7.Cu")
		(net "P2E_CPU_NGFF_RX_DP14")
	)
	(segment
		(start 60.210192 -55.74665)
		(end 57.447942 -52.9844)
		(width 0.1143)
		(layer "In7.Cu")
		(net "P2E_CPU_NGFF_RX_DP14")
	)
	(segment
		(start 92.3544 -53.9496)
		(end 92.3544 -55.372)
		(width 0.1016)
		(layer "In7.Cu")
		(net "P2E_CPU_NGFF_RX_DP14")
	)
	(segment
		(start 93.7768 -48.0314)
		(end 93.531436 -48.276764)
		(width 0.1016)
		(layer "In7.Cu")
		(net "P2E_CPU_NGFF_RX_DP14")
	)
	(segment
		(start 72.730106 -54.4576)
		(end 72.526906 -54.2544)
		(width 0.1143)
		(layer "In7.Cu")
		(net "P2E_CPU_NGFF_RX_DP14")
	)
	(segment
		(start 89.5858 -55.7403)
		(end 89.5604 -55.7403)
		(width 0.1016)
		(layer "In7.Cu")
		(net "P2E_CPU_NGFF_RX_DP14")
	)
	(segment
		(start 68.0974 -55.74665)
		(end 60.210192 -55.74665)
		(width 0.1143)
		(layer "In7.Cu")
		(net "P2E_CPU_NGFF_RX_DP14")
	)
	(segment
		(start 82.40395 -59.838844)
		(end 80.731106 -58.166)
		(width 0.1143)
		(layer "In7.Cu")
		(net "P2E_CPU_NGFF_RX_DP14")
	)
	(segment
		(start 13.7414 -55.517288)
		(end 13.7414 -57.9628)
		(width 0.1143)
		(layer "In7.Cu")
		(net "P2E_CPU_NGFF_RX_DP14")
	)
	(segment
		(start 42.545 -52.324)
		(end 38.628828 -52.324)
		(width 0.1143)
		(layer "In7.Cu")
		(net "P2E_CPU_NGFF_RX_DP14")
	)
	(segment
		(start 92.3544 -55.372)
		(end 91.5924 -56.134)
		(width 0.1016)
		(layer "In7.Cu")
		(net "P2E_CPU_NGFF_RX_DP14")
	)
	(segment
		(start 93.531436 -48.276764)
		(end 93.296486 -48.276764)
		(width 0.1016)
		(layer "In7.Cu")
		(net "P2E_CPU_NGFF_RX_DP14")
	)
	(segment
		(start 93.11005 -49.50968)
		(end 92.99067 -49.62906)
		(width 0.1016)
		(layer "In7.Cu")
		(net "P2E_CPU_NGFF_RX_DP14")
	)
	(segment
		(start 34.3535 -51.9557)
		(end 31.88335 -49.48555)
		(width 0.1143)
		(layer "In7.Cu")
		(net "P2E_CPU_NGFF_RX_DP14")
	)
	(segment
		(start 90.2462 -56.134)
		(end 89.916 -55.8038)
		(width 0.1016)
		(layer "In7.Cu")
		(net "P2E_CPU_NGFF_RX_DP14")
	)
	(segment
		(start 10.4775 -61.2267)
		(end 9.8933 -61.2267)
		(width 0.1143)
		(layer "In7.Cu")
		(net "P2E_CPU_NGFF_RX_DP14")
	)
	(segment
		(start 9.6266 -65.405)
		(end 8.9662 -65.405)
		(width 0.1397)
		(layer "F.Cu")
		(net "P2E_CPU_NGFF_RX_DN15")
	)
	(segment
		(start 95.11538 -49.048162)
		(end 94.976188 -49.048162)
		(width 0.1397)
		(layer "F.Cu")
		(net "P2E_CPU_NGFF_RX_DN15")
	)
	(segment
		(start 95.380048 -48.783494)
		(end 95.11538 -49.048162)
		(width 0.1397)
		(layer "F.Cu")
		(net "P2E_CPU_NGFF_RX_DN15")
	)
	(via
		(at 9.6266 -65.405)
		(size 0.508)
		(drill 0.254)
		(layers "F.Cu" "B.Cu")
		(net "P2E_CPU_NGFF_RX_DN15")
	)
	(via
		(at 94.976188 -49.048162)
		(size 0.4318)
		(drill 0.2032)
		(layers "F.Cu" "B.Cu")
		(net "P2E_CPU_NGFF_RX_DN15")
	)
	(segment
		(start 16.7005 -57.4929)
		(end 20.25015 -53.94325)
		(width 0.1143)
		(layer "In7.Cu")
		(net "P2E_CPU_NGFF_RX_DN15")
	)
	(segment
		(start 94.881446 -52.294282)
		(end 94.881446 -51.97221)
		(width 0.1016)
		(layer "In7.Cu")
		(net "P2E_CPU_NGFF_RX_DN15")
	)
	(segment
		(start 92.081858 -60.074048)
		(end 92.081858 -57.785)
		(width 0.1143)
		(layer "In7.Cu")
		(net "P2E_CPU_NGFF_RX_DN15")
	)
	(segment
		(start 13.1572 -63.763906)
		(end 13.1572 -62.215522)
		(width 0.1143)
		(layer "In7.Cu")
		(net "P2E_CPU_NGFF_RX_DN15")
	)
	(segment
		(start 32.987996 -54.66207)
		(end 33.545526 -55.2196)
		(width 0.1143)
		(layer "In7.Cu")
		(net "P2E_CPU_NGFF_RX_DN15")
	)
	(segment
		(start 74.8284 -58.379106)
		(end 77.866494 -61.4172)
		(width 0.1143)
		(layer "In7.Cu")
		(net "P2E_CPU_NGFF_RX_DN15")
	)
	(segment
		(start 26.503884 -53.94325)
		(end 28.504134 -51.943)
		(width 0.1143)
		(layer "In7.Cu")
		(net "P2E_CPU_NGFF_RX_DN15")
	)
	(segment
		(start 94.881446 -51.16449)
		(end 94.980506 -51.06543)
		(width 0.1016)
		(layer "In7.Cu")
		(net "P2E_CPU_NGFF_RX_DN15")
	)
	(segment
		(start 94.831154 -49.192688)
		(end 94.843092 -49.181004)
		(width 0.1016)
		(layer "In7.Cu")
		(net "P2E_CPU_NGFF_RX_DN15")
	)
	(segment
		(start 20.25015 -53.94325)
		(end 26.503884 -53.94325)
		(width 0.1143)
		(layer "In7.Cu")
		(net "P2E_CPU_NGFF_RX_DN15")
	)
	(segment
		(start 71.969122 -56.6928)
		(end 74.3966 -56.6928)
		(width 0.1143)
		(layer "In7.Cu")
		(net "P2E_CPU_NGFF_RX_DN15")
	)
	(segment
		(start 92.018358 -56.75757)
		(end 93.0402 -55.735728)
		(width 0.1016)
		(layer "In7.Cu")
		(net "P2E_CPU_NGFF_RX_DN15")
	)
	(segment
		(start 94.980506 -51.56835)
		(end 94.881446 -51.46929)
		(width 0.1016)
		(layer "In7.Cu")
		(net "P2E_CPU_NGFF_RX_DN15")
	)
	(segment
		(start 74.8284 -57.1246)
		(end 74.8284 -58.379106)
		(width 0.1143)
		(layer "In7.Cu")
		(net "P2E_CPU_NGFF_RX_DN15")
	)
	(segment
		(start 94.881446 -50.35677)
		(end 94.980506 -50.25771)
		(width 0.1016)
		(layer "In7.Cu")
		(net "P2E_CPU_NGFF_RX_DN15")
	)
	(segment
		(start 9.906 -65.1256)
		(end 11.795506 -65.1256)
		(width 0.1143)
		(layer "In7.Cu")
		(net "P2E_CPU_NGFF_RX_DN15")
	)
	(segment
		(start 94.843092 -49.181004)
		(end 94.976188 -49.048162)
		(width 0.1016)
		(layer "In7.Cu")
		(net "P2E_CPU_NGFF_RX_DN15")
	)
	(segment
		(start 94.980506 -50.76063)
		(end 94.881446 -50.66157)
		(width 0.1016)
		(layer "In7.Cu")
		(net "P2E_CPU_NGFF_RX_DN15")
	)
	(segment
		(start 94.980506 -49.95291)
		(end 94.881446 -49.85385)
		(width 0.1016)
		(layer "In7.Cu")
		(net "P2E_CPU_NGFF_RX_DN15")
	)
	(segment
		(start 92.018358 -57.7088)
		(end 92.018358 -56.75757)
		(width 0.1016)
		(layer "In7.Cu")
		(net "P2E_CPU_NGFF_RX_DN15")
	)
	(segment
		(start 94.881446 -50.66157)
		(end 94.881446 -50.35677)
		(width 0.1016)
		(layer "In7.Cu")
		(net "P2E_CPU_NGFF_RX_DN15")
	)
	(segment
		(start 92.081858 -57.7723)
		(end 92.018358 -57.7088)
		(width 0.1016)
		(layer "In7.Cu")
		(net "P2E_CPU_NGFF_RX_DN15")
	)
	(segment
		(start 94.881446 -49.54905)
		(end 94.811088 -49.478692)
		(width 0.1016)
		(layer "In7.Cu")
		(net "P2E_CPU_NGFF_RX_DN15")
	)
	(segment
		(start 16.7005 -58.672222)
		(end 16.7005 -57.4929)
		(width 0.1143)
		(layer "In7.Cu")
		(net "P2E_CPU_NGFF_RX_DN15")
	)
	(segment
		(start 94.980506 -51.06543)
		(end 94.980506 -50.76063)
		(width 0.1016)
		(layer "In7.Cu")
		(net "P2E_CPU_NGFF_RX_DN15")
	)
	(segment
		(start 94.980506 -51.87315)
		(end 94.980506 -51.56835)
		(width 0.1016)
		(layer "In7.Cu")
		(net "P2E_CPU_NGFF_RX_DN15")
	)
	(segment
		(start 74.3966 -56.6928)
		(end 74.8284 -57.1246)
		(width 0.1143)
		(layer "In7.Cu")
		(net "P2E_CPU_NGFF_RX_DN15")
	)
	(segment
		(start 94.980506 -50.25771)
		(end 94.980506 -49.95291)
		(width 0.1016)
		(layer "In7.Cu")
		(net "P2E_CPU_NGFF_RX_DN15")
	)
	(segment
		(start 82.259678 -61.8998)
		(end 90.256106 -61.8998)
		(width 0.1143)
		(layer "In7.Cu")
		(net "P2E_CPU_NGFF_RX_DN15")
	)
	(segment
		(start 94.881446 -51.97221)
		(end 94.980506 -51.87315)
		(width 0.1016)
		(layer "In7.Cu")
		(net "P2E_CPU_NGFF_RX_DN15")
	)
	(segment
		(start 94.811088 -49.478692)
		(end 94.811088 -49.213262)
		(width 0.1016)
		(layer "In7.Cu")
		(net "P2E_CPU_NGFF_RX_DN15")
	)
	(segment
		(start 94.881446 -51.46929)
		(end 94.881446 -51.16449)
		(width 0.1016)
		(layer "In7.Cu")
		(net "P2E_CPU_NGFF_RX_DN15")
	)
	(segment
		(start 59.690254 -58.38825)
		(end 70.273672 -58.38825)
		(width 0.1143)
		(layer "In7.Cu")
		(net "P2E_CPU_NGFF_RX_DN15")
	)
	(segment
		(start 32.987996 -54.661816)
		(end 32.987996 -54.66207)
		(width 0.1143)
		(layer "In7.Cu")
		(net "P2E_CPU_NGFF_RX_DN15")
	)
	(segment
		(start 77.866494 -61.4172)
		(end 81.777078 -61.4172)
		(width 0.1143)
		(layer "In7.Cu")
		(net "P2E_CPU_NGFF_RX_DN15")
	)
	(segment
		(start 90.256106 -61.8998)
		(end 92.081858 -60.074048)
		(width 0.1143)
		(layer "In7.Cu")
		(net "P2E_CPU_NGFF_RX_DN15")
	)
	(segment
		(start 9.6266 -65.405)
		(end 9.906 -65.1256)
		(width 0.1143)
		(layer "In7.Cu")
		(net "P2E_CPU_NGFF_RX_DN15")
	)
	(segment
		(start 94.881446 -49.85385)
		(end 94.881446 -49.54905)
		(width 0.1016)
		(layer "In7.Cu")
		(net "P2E_CPU_NGFF_RX_DN15")
	)
	(segment
		(start 30.26918 -51.943)
		(end 32.987996 -54.661816)
		(width 0.1143)
		(layer "In7.Cu")
		(net "P2E_CPU_NGFF_RX_DN15")
	)
	(segment
		(start 11.795506 -65.1256)
		(end 13.1572 -63.763906)
		(width 0.1143)
		(layer "In7.Cu")
		(net "P2E_CPU_NGFF_RX_DN15")
	)
	(segment
		(start 81.777078 -61.4172)
		(end 82.259678 -61.8998)
		(width 0.1143)
		(layer "In7.Cu")
		(net "P2E_CPU_NGFF_RX_DN15")
	)
	(segment
		(start 56.521604 -55.2196)
		(end 59.690254 -58.38825)
		(width 0.1143)
		(layer "In7.Cu")
		(net "P2E_CPU_NGFF_RX_DN15")
	)
	(segment
		(start 13.1572 -62.215522)
		(end 16.7005 -58.672222)
		(width 0.1143)
		(layer "In7.Cu")
		(net "P2E_CPU_NGFF_RX_DN15")
	)
	(segment
		(start 93.0402 -55.735728)
		(end 93.0402 -54.135528)
		(width 0.1016)
		(layer "In7.Cu")
		(net "P2E_CPU_NGFF_RX_DN15")
	)
	(segment
		(start 94.811088 -49.213262)
		(end 94.831154 -49.192688)
		(width 0.1016)
		(layer "In7.Cu")
		(net "P2E_CPU_NGFF_RX_DN15")
	)
	(segment
		(start 92.081858 -57.785)
		(end 92.081858 -57.7723)
		(width 0.1016)
		(layer "In7.Cu")
		(net "P2E_CPU_NGFF_RX_DN15")
	)
	(segment
		(start 33.545526 -55.2196)
		(end 56.521604 -55.2196)
		(width 0.1143)
		(layer "In7.Cu")
		(net "P2E_CPU_NGFF_RX_DN15")
	)
	(segment
		(start 28.504134 -51.943)
		(end 30.26918 -51.943)
		(width 0.1143)
		(layer "In7.Cu")
		(net "P2E_CPU_NGFF_RX_DN15")
	)
	(segment
		(start 70.273672 -58.38825)
		(end 71.969122 -56.6928)
		(width 0.1143)
		(layer "In7.Cu")
		(net "P2E_CPU_NGFF_RX_DN15")
	)
	(segment
		(start 93.0402 -54.135528)
		(end 94.881446 -52.294282)
		(width 0.1016)
		(layer "In7.Cu")
		(net "P2E_CPU_NGFF_RX_DN15")
	)
	(segment
		(start 95.380048 -48.021494)
		(end 95.052642 -48.3489)
		(width 0.1397)
		(layer "F.Cu")
		(net "P2E_CPU_NGFF_RX_DP15")
	)
	(segment
		(start 9.6266 -64.516)
		(end 8.9662 -64.516)
		(width 0.1397)
		(layer "F.Cu")
		(net "P2E_CPU_NGFF_RX_DP15")
	)
	(segment
		(start 95.052642 -48.3489)
		(end 94.996 -48.3489)
		(width 0.1397)
		(layer "F.Cu")
		(net "P2E_CPU_NGFF_RX_DP15")
	)
	(via
		(at 94.996 -48.3489)
		(size 0.4318)
		(drill 0.2032)
		(layers "F.Cu" "B.Cu")
		(net "P2E_CPU_NGFF_RX_DP15")
	)
	(via
		(at 9.6266 -64.516)
		(size 0.508)
		(drill 0.254)
		(layers "F.Cu" "B.Cu")
		(net "P2E_CPU_NGFF_RX_DP15")
	)
	(segment
		(start 28.367228 -51.6128)
		(end 30.406086 -51.6128)
		(width 0.1143)
		(layer "In7.Cu")
		(net "P2E_CPU_NGFF_RX_DP15")
	)
	(segment
		(start 12.827 -62.078616)
		(end 16.3703 -58.535316)
		(width 0.1143)
		(layer "In7.Cu")
		(net "P2E_CPU_NGFF_RX_DP15")
	)
	(segment
		(start 82.396584 -61.5696)
		(end 90.1192 -61.5696)
		(width 0.1143)
		(layer "In7.Cu")
		(net "P2E_CPU_NGFF_RX_DP15")
	)
	(segment
		(start 16.3703 -58.535316)
		(end 16.3703 -57.355994)
		(width 0.1143)
		(layer "In7.Cu")
		(net "P2E_CPU_NGFF_RX_DP15")
	)
	(segment
		(start 94.607888 -48.737012)
		(end 94.996 -48.3489)
		(width 0.1016)
		(layer "In7.Cu")
		(net "P2E_CPU_NGFF_RX_DP15")
	)
	(segment
		(start 9.906 -64.7954)
		(end 11.6586 -64.7954)
		(width 0.1143)
		(layer "In7.Cu")
		(net "P2E_CPU_NGFF_RX_DP15")
	)
	(segment
		(start 26.366978 -53.61305)
		(end 28.367228 -51.6128)
		(width 0.1143)
		(layer "In7.Cu")
		(net "P2E_CPU_NGFF_RX_DP15")
	)
	(segment
		(start 75.1586 -56.987694)
		(end 75.1586 -58.2422)
		(width 0.1143)
		(layer "In7.Cu")
		(net "P2E_CPU_NGFF_RX_DP15")
	)
	(segment
		(start 74.533506 -56.3626)
		(end 75.1586 -56.987694)
		(width 0.1143)
		(layer "In7.Cu")
		(net "P2E_CPU_NGFF_RX_DP15")
	)
	(segment
		(start 59.82716 -58.05805)
		(end 70.136766 -58.05805)
		(width 0.1143)
		(layer "In7.Cu")
		(net "P2E_CPU_NGFF_RX_DP15")
	)
	(segment
		(start 91.815158 -56.673242)
		(end 92.837 -55.6514)
		(width 0.1016)
		(layer "In7.Cu")
		(net "P2E_CPU_NGFF_RX_DP15")
	)
	(segment
		(start 30.406086 -51.6128)
		(end 33.318196 -54.52491)
		(width 0.1143)
		(layer "In7.Cu")
		(net "P2E_CPU_NGFF_RX_DP15")
	)
	(segment
		(start 71.832216 -56.3626)
		(end 74.533506 -56.3626)
		(width 0.1143)
		(layer "In7.Cu")
		(net "P2E_CPU_NGFF_RX_DP15")
	)
	(segment
		(start 33.318196 -54.52491)
		(end 33.318196 -54.525164)
		(width 0.1143)
		(layer "In7.Cu")
		(net "P2E_CPU_NGFF_RX_DP15")
	)
	(segment
		(start 81.913984 -61.087)
		(end 82.396584 -61.5696)
		(width 0.1143)
		(layer "In7.Cu")
		(net "P2E_CPU_NGFF_RX_DP15")
	)
	(segment
		(start 16.3703 -57.355994)
		(end 20.113244 -53.61305)
		(width 0.1143)
		(layer "In7.Cu")
		(net "P2E_CPU_NGFF_RX_DP15")
	)
	(segment
		(start 91.751658 -57.7723)
		(end 91.815158 -57.7088)
		(width 0.1016)
		(layer "In7.Cu")
		(net "P2E_CPU_NGFF_RX_DP15")
	)
	(segment
		(start 94.678246 -49.633378)
		(end 94.607888 -49.56302)
		(width 0.1016)
		(layer "In7.Cu")
		(net "P2E_CPU_NGFF_RX_DP15")
	)
	(segment
		(start 90.1192 -61.5696)
		(end 91.751658 -59.937142)
		(width 0.1143)
		(layer "In7.Cu")
		(net "P2E_CPU_NGFF_RX_DP15")
	)
	(segment
		(start 9.6266 -64.516)
		(end 9.906 -64.7954)
		(width 0.1143)
		(layer "In7.Cu")
		(net "P2E_CPU_NGFF_RX_DP15")
	)
	(segment
		(start 12.827 -63.627)
		(end 12.827 -62.078616)
		(width 0.1143)
		(layer "In7.Cu")
		(net "P2E_CPU_NGFF_RX_DP15")
	)
	(segment
		(start 75.1586 -58.2422)
		(end 78.0034 -61.087)
		(width 0.1143)
		(layer "In7.Cu")
		(net "P2E_CPU_NGFF_RX_DP15")
	)
	(segment
		(start 56.65851 -54.8894)
		(end 59.82716 -58.05805)
		(width 0.1143)
		(layer "In7.Cu")
		(net "P2E_CPU_NGFF_RX_DP15")
	)
	(segment
		(start 91.751658 -59.937142)
		(end 91.751658 -57.785)
		(width 0.1143)
		(layer "In7.Cu")
		(net "P2E_CPU_NGFF_RX_DP15")
	)
	(segment
		(start 94.607888 -49.56302)
		(end 94.607888 -48.737012)
		(width 0.1016)
		(layer "In7.Cu")
		(net "P2E_CPU_NGFF_RX_DP15")
	)
	(segment
		(start 94.678246 -52.209954)
		(end 94.678246 -49.633378)
		(width 0.1016)
		(layer "In7.Cu")
		(net "P2E_CPU_NGFF_RX_DP15")
	)
	(segment
		(start 20.113244 -53.61305)
		(end 26.366978 -53.61305)
		(width 0.1143)
		(layer "In7.Cu")
		(net "P2E_CPU_NGFF_RX_DP15")
	)
	(segment
		(start 92.837 -55.6514)
		(end 92.837 -54.0512)
		(width 0.1016)
		(layer "In7.Cu")
		(net "P2E_CPU_NGFF_RX_DP15")
	)
	(segment
		(start 91.751658 -57.785)
		(end 91.751658 -57.7723)
		(width 0.1016)
		(layer "In7.Cu")
		(net "P2E_CPU_NGFF_RX_DP15")
	)
	(segment
		(start 33.682432 -54.8894)
		(end 56.65851 -54.8894)
		(width 0.1143)
		(layer "In7.Cu")
		(net "P2E_CPU_NGFF_RX_DP15")
	)
	(segment
		(start 92.837 -54.0512)
		(end 94.678246 -52.209954)
		(width 0.1016)
		(layer "In7.Cu")
		(net "P2E_CPU_NGFF_RX_DP15")
	)
	(segment
		(start 70.136766 -58.05805)
		(end 71.832216 -56.3626)
		(width 0.1143)
		(layer "In7.Cu")
		(net "P2E_CPU_NGFF_RX_DP15")
	)
	(segment
		(start 33.318196 -54.525164)
		(end 33.682432 -54.8894)
		(width 0.1143)
		(layer "In7.Cu")
		(net "P2E_CPU_NGFF_RX_DP15")
	)
	(segment
		(start 91.815158 -57.7088)
		(end 91.815158 -56.673242)
		(width 0.1016)
		(layer "In7.Cu")
		(net "P2E_CPU_NGFF_RX_DP15")
	)
	(segment
		(start 11.6586 -64.7954)
		(end 12.827 -63.627)
		(width 0.1143)
		(layer "In7.Cu")
		(net "P2E_CPU_NGFF_RX_DP15")
	)
	(segment
		(start 78.0034 -61.087)
		(end 81.913984 -61.087)
		(width 0.1143)
		(layer "In7.Cu")
		(net "P2E_CPU_NGFF_RX_DP15")
	)
	(segment
		(start 9.6266 -58.293)
		(end 8.9662 -58.293)
		(width 0.1397)
		(layer "F.Cu")
		(net "P2E_CPU_NGFF_RX_DN13")
	)
	(segment
		(start 93.383608 -49.174654)
		(end 93.393768 -49.164494)
		(width 0.1397)
		(layer "F.Cu")
		(net "P2E_CPU_NGFF_RX_DN13")
	)
	(segment
		(start 92.696538 -49.057814)
		(end 92.813378 -49.174654)
		(width 0.1397)
		(layer "F.Cu")
		(net "P2E_CPU_NGFF_RX_DN13")
	)
	(segment
		(start 92.813378 -49.174654)
		(end 93.383608 -49.174654)
		(width 0.1397)
		(layer "F.Cu")
		(net "P2E_CPU_NGFF_RX_DN13")
	)
	(via
		(at 9.6266 -58.293)
		(size 0.508)
		(drill 0.254)
		(layers "F.Cu" "B.Cu")
		(net "P2E_CPU_NGFF_RX_DN13")
	)
	(via
		(at 92.696538 -49.057814)
		(size 0.4318)
		(drill 0.2032)
		(layers "F.Cu" "B.Cu")
		(net "P2E_CPU_NGFF_RX_DN13")
	)
	(segment
		(start 92.330778 -49.496472)
		(end 92.533978 -49.699672)
		(width 0.1016)
		(layer "In7.Cu")
		(net "P2E_CPU_NGFF_RX_DN13")
	)
	(segment
		(start 92.12326 -53.2511)
		(end 92.0242 -53.35016)
		(width 0.1016)
		(layer "In7.Cu")
		(net "P2E_CPU_NGFF_RX_DN13")
	)
	(segment
		(start 91.460828 -55.8673)
		(end 90.365072 -55.8673)
		(width 0.1016)
		(layer "In7.Cu")
		(net "P2E_CPU_NGFF_RX_DN13")
	)
	(segment
		(start 85.28939 -57.0484)
		(end 82.184494 -57.0484)
		(width 0.1143)
		(layer "In7.Cu")
		(net "P2E_CPU_NGFF_RX_DN13")
	)
	(segment
		(start 41.9354 -48.2092)
		(end 39.862506 -48.2092)
		(width 0.1143)
		(layer "In7.Cu")
		(net "P2E_CPU_NGFF_RX_DN13")
	)
	(segment
		(start 18.150332 -50.566574)
		(end 15.382748 -50.566574)
		(width 0.1143)
		(layer "In7.Cu")
		(net "P2E_CPU_NGFF_RX_DN13")
	)
	(segment
		(start 39.862506 -48.2092)
		(end 39.227506 -48.8442)
		(width 0.1143)
		(layer "In7.Cu")
		(net "P2E_CPU_NGFF_RX_DN13")
	)
	(segment
		(start 87.955628 -55.6133)
		(end 87.0585 -55.6133)
		(width 0.1016)
		(layer "In7.Cu")
		(net "P2E_CPU_NGFF_RX_DN13")
	)
	(segment
		(start 60.086494 -53.395626)
		(end 60.086494 -52.130452)
		(width 0.1143)
		(layer "In7.Cu")
		(net "P2E_CPU_NGFF_RX_DN13")
	)
	(segment
		(start 92.12326 -52.44338)
		(end 92.0242 -52.54244)
		(width 0.1016)
		(layer "In7.Cu")
		(net "P2E_CPU_NGFF_RX_DN13")
	)
	(segment
		(start 76.571094 -53.1622)
		(end 75.847194 -53.1622)
		(width 0.1143)
		(layer "In7.Cu")
		(net "P2E_CPU_NGFF_RX_DN13")
	)
	(segment
		(start 32.095694 -46.4312)
		(end 25.564338 -46.4312)
		(width 0.1143)
		(layer "In7.Cu")
		(net "P2E_CPU_NGFF_RX_DN13")
	)
	(segment
		(start 39.227506 -48.8442)
		(end 38.471094 -48.8442)
		(width 0.1143)
		(layer "In7.Cu")
		(net "P2E_CPU_NGFF_RX_DN13")
	)
	(segment
		(start 86.995 -55.6768)
		(end 86.9696 -55.6768)
		(width 0.1016)
		(layer "In7.Cu")
		(net "P2E_CPU_NGFF_RX_DN13")
	)
	(segment
		(start 89.945972 -55.4482)
		(end 88.120728 -55.4482)
		(width 0.1016)
		(layer "In7.Cu")
		(net "P2E_CPU_NGFF_RX_DN13")
	)
	(segment
		(start 88.120728 -55.4482)
		(end 87.955628 -55.6133)
		(width 0.1016)
		(layer "In7.Cu")
		(net "P2E_CPU_NGFF_RX_DN13")
	)
	(segment
		(start 60.724034 -54.033166)
		(end 60.086494 -53.395626)
		(width 0.1143)
		(layer "In7.Cu")
		(net "P2E_CPU_NGFF_RX_DN13")
	)
	(segment
		(start 92.672916 -49.034192)
		(end 92.430092 -49.034192)
		(width 0.1016)
		(layer "In7.Cu")
		(net "P2E_CPU_NGFF_RX_DN13")
	)
	(segment
		(start 10.398506 -58.0644)
		(end 9.8552 -58.0644)
		(width 0.1143)
		(layer "In7.Cu")
		(net "P2E_CPU_NGFF_RX_DN13")
	)
	(segment
		(start 86.66099 -55.6768)
		(end 85.28939 -57.0484)
		(width 0.1143)
		(layer "In7.Cu")
		(net "P2E_CPU_NGFF_RX_DN13")
	)
	(segment
		(start 75.075034 -52.39004)
		(end 66.339466 -52.39004)
		(width 0.1143)
		(layer "In7.Cu")
		(net "P2E_CPU_NGFF_RX_DN13")
	)
	(segment
		(start 92.12326 -52.13858)
		(end 92.12326 -52.44338)
		(width 0.1016)
		(layer "In7.Cu")
		(net "P2E_CPU_NGFF_RX_DN13")
	)
	(segment
		(start 66.339466 -52.39004)
		(end 65.446656 -53.28285)
		(width 0.1143)
		(layer "In7.Cu")
		(net "P2E_CPU_NGFF_RX_DN13")
	)
	(segment
		(start 92.533978 -49.699672)
		(end 92.533978 -50.976022)
		(width 0.1016)
		(layer "In7.Cu")
		(net "P2E_CPU_NGFF_RX_DN13")
	)
	(segment
		(start 92.0242 -52.03952)
		(end 92.12326 -52.13858)
		(width 0.1016)
		(layer "In7.Cu")
		(net "P2E_CPU_NGFF_RX_DN13")
	)
	(segment
		(start 92.533978 -50.976022)
		(end 92.0242 -51.4858)
		(width 0.1016)
		(layer "In7.Cu")
		(net "P2E_CPU_NGFF_RX_DN13")
	)
	(segment
		(start 82.184494 -57.0484)
		(end 81.879694 -56.7436)
		(width 0.1143)
		(layer "In7.Cu")
		(net "P2E_CPU_NGFF_RX_DN13")
	)
	(segment
		(start 55.926228 -51.2826)
		(end 54.827678 -50.18405)
		(width 0.1143)
		(layer "In7.Cu")
		(net "P2E_CPU_NGFF_RX_DN13")
	)
	(segment
		(start 92.430092 -49.034192)
		(end 92.330778 -49.133506)
		(width 0.1016)
		(layer "In7.Cu")
		(net "P2E_CPU_NGFF_RX_DN13")
	)
	(segment
		(start 90.365072 -55.8673)
		(end 89.945972 -55.4482)
		(width 0.1016)
		(layer "In7.Cu")
		(net "P2E_CPU_NGFF_RX_DN13")
	)
	(segment
		(start 92.0242 -51.4858)
		(end 92.0242 -52.03952)
		(width 0.1016)
		(layer "In7.Cu")
		(net "P2E_CPU_NGFF_RX_DN13")
	)
	(segment
		(start 54.827678 -50.18405)
		(end 43.91025 -50.18405)
		(width 0.1143)
		(layer "In7.Cu")
		(net "P2E_CPU_NGFF_RX_DN13")
	)
	(segment
		(start 75.847194 -53.1622)
		(end 75.075034 -52.39004)
		(width 0.1143)
		(layer "In7.Cu")
		(net "P2E_CPU_NGFF_RX_DN13")
	)
	(segment
		(start 92.0242 -52.54244)
		(end 92.0242 -52.84724)
		(width 0.1016)
		(layer "In7.Cu")
		(net "P2E_CPU_NGFF_RX_DN13")
	)
	(segment
		(start 92.0242 -52.84724)
		(end 92.12326 -52.9463)
		(width 0.1016)
		(layer "In7.Cu")
		(net "P2E_CPU_NGFF_RX_DN13")
	)
	(segment
		(start 92.696538 -49.057814)
		(end 92.672916 -49.034192)
		(width 0.1016)
		(layer "In7.Cu")
		(net "P2E_CPU_NGFF_RX_DN13")
	)
	(segment
		(start 87.0585 -55.6133)
		(end 86.995 -55.6768)
		(width 0.1016)
		(layer "In7.Cu")
		(net "P2E_CPU_NGFF_RX_DN13")
	)
	(segment
		(start 37.836094 -48.2092)
		(end 36.357306 -48.2092)
		(width 0.1143)
		(layer "In7.Cu")
		(net "P2E_CPU_NGFF_RX_DN13")
	)
	(segment
		(start 24.065738 -47.9298)
		(end 20.787106 -47.9298)
		(width 0.1143)
		(layer "In7.Cu")
		(net "P2E_CPU_NGFF_RX_DN13")
	)
	(segment
		(start 80.152494 -56.7436)
		(end 76.571094 -53.1622)
		(width 0.1143)
		(layer "In7.Cu")
		(net "P2E_CPU_NGFF_RX_DN13")
	)
	(segment
		(start 43.91025 -50.18405)
		(end 41.9354 -48.2092)
		(width 0.1143)
		(layer "In7.Cu")
		(net "P2E_CPU_NGFF_RX_DN13")
	)
	(segment
		(start 65.446656 -53.28285)
		(end 62.0522 -53.28285)
		(width 0.1143)
		(layer "In7.Cu")
		(net "P2E_CPU_NGFF_RX_DN13")
	)
	(segment
		(start 81.879694 -56.7436)
		(end 80.152494 -56.7436)
		(width 0.1143)
		(layer "In7.Cu")
		(net "P2E_CPU_NGFF_RX_DN13")
	)
	(segment
		(start 34.508694 -48.8442)
		(end 32.095694 -46.4312)
		(width 0.1143)
		(layer "In7.Cu")
		(net "P2E_CPU_NGFF_RX_DN13")
	)
	(segment
		(start 12.1666 -53.782722)
		(end 12.1666 -56.296306)
		(width 0.1143)
		(layer "In7.Cu")
		(net "P2E_CPU_NGFF_RX_DN13")
	)
	(segment
		(start 20.787106 -47.9298)
		(end 18.150332 -50.566574)
		(width 0.1143)
		(layer "In7.Cu")
		(net "P2E_CPU_NGFF_RX_DN13")
	)
	(segment
		(start 86.9696 -55.6768)
		(end 86.66099 -55.6768)
		(width 0.1143)
		(layer "In7.Cu")
		(net "P2E_CPU_NGFF_RX_DN13")
	)
	(segment
		(start 15.382748 -50.566574)
		(end 12.1666 -53.782722)
		(width 0.1143)
		(layer "In7.Cu")
		(net "P2E_CPU_NGFF_RX_DN13")
	)
	(segment
		(start 61.301884 -54.033166)
		(end 60.724034 -54.033166)
		(width 0.1143)
		(layer "In7.Cu")
		(net "P2E_CPU_NGFF_RX_DN13")
	)
	(segment
		(start 92.12326 -52.9463)
		(end 92.12326 -53.2511)
		(width 0.1016)
		(layer "In7.Cu")
		(net "P2E_CPU_NGFF_RX_DN13")
	)
	(segment
		(start 92.330778 -49.133506)
		(end 92.330778 -49.496472)
		(width 0.1016)
		(layer "In7.Cu")
		(net "P2E_CPU_NGFF_RX_DN13")
	)
	(segment
		(start 38.471094 -48.8442)
		(end 37.836094 -48.2092)
		(width 0.1143)
		(layer "In7.Cu")
		(net "P2E_CPU_NGFF_RX_DN13")
	)
	(segment
		(start 25.564338 -46.4312)
		(end 24.065738 -47.9298)
		(width 0.1143)
		(layer "In7.Cu")
		(net "P2E_CPU_NGFF_RX_DN13")
	)
	(segment
		(start 60.086494 -52.130452)
		(end 59.238642 -51.2826)
		(width 0.1143)
		(layer "In7.Cu")
		(net "P2E_CPU_NGFF_RX_DN13")
	)
	(segment
		(start 35.722306 -48.8442)
		(end 34.508694 -48.8442)
		(width 0.1143)
		(layer "In7.Cu")
		(net "P2E_CPU_NGFF_RX_DN13")
	)
	(segment
		(start 36.357306 -48.2092)
		(end 35.722306 -48.8442)
		(width 0.1143)
		(layer "In7.Cu")
		(net "P2E_CPU_NGFF_RX_DN13")
	)
	(segment
		(start 92.0242 -53.35016)
		(end 92.0242 -55.303928)
		(width 0.1016)
		(layer "In7.Cu")
		(net "P2E_CPU_NGFF_RX_DN13")
	)
	(segment
		(start 9.8552 -58.0644)
		(end 9.6266 -58.293)
		(width 0.1143)
		(layer "In7.Cu")
		(net "P2E_CPU_NGFF_RX_DN13")
	)
	(segment
		(start 59.238642 -51.2826)
		(end 55.926228 -51.2826)
		(width 0.1143)
		(layer "In7.Cu")
		(net "P2E_CPU_NGFF_RX_DN13")
	)
	(segment
		(start 12.1666 -56.296306)
		(end 10.398506 -58.0644)
		(width 0.1143)
		(layer "In7.Cu")
		(net "P2E_CPU_NGFF_RX_DN13")
	)
	(segment
		(start 62.0522 -53.28285)
		(end 61.301884 -54.033166)
		(width 0.1143)
		(layer "In7.Cu")
		(net "P2E_CPU_NGFF_RX_DN13")
	)
	(segment
		(start 92.0242 -55.303928)
		(end 91.460828 -55.8673)
		(width 0.1016)
		(layer "In7.Cu")
		(net "P2E_CPU_NGFF_RX_DN13")
	)
	(segment
		(start 9.6266 -57.404)
		(end 8.9662 -57.404)
		(width 0.1397)
		(layer "F.Cu")
		(net "P2E_CPU_NGFF_RX_DP13")
	)
	(segment
		(start 93.393768 -48.402494)
		(end 92.77985 -48.402494)
		(width 0.1397)
		(layer "F.Cu")
		(net "P2E_CPU_NGFF_RX_DP13")
	)
	(segment
		(start 92.77985 -48.402494)
		(end 92.68333 -48.499014)
		(width 0.1397)
		(layer "F.Cu")
		(net "P2E_CPU_NGFF_RX_DP13")
	)
	(via
		(at 9.6266 -57.404)
		(size 0.508)
		(drill 0.254)
		(layers "F.Cu" "B.Cu")
		(net "P2E_CPU_NGFF_RX_DP13")
	)
	(via
		(at 92.68333 -48.499014)
		(size 0.4318)
		(drill 0.2032)
		(layers "F.Cu" "B.Cu")
		(net "P2E_CPU_NGFF_RX_DP13")
	)
	(segment
		(start 10.2616 -57.7342)
		(end 9.9568 -57.7342)
		(width 0.1143)
		(layer "In7.Cu")
		(net "P2E_CPU_NGFF_RX_DP13")
	)
	(segment
		(start 15.245842 -50.236374)
		(end 11.8364 -53.645816)
		(width 0.1143)
		(layer "In7.Cu")
		(net "P2E_CPU_NGFF_RX_DP13")
	)
	(segment
		(start 80.2894 -56.4134)
		(end 76.708 -52.832)
		(width 0.1143)
		(layer "In7.Cu")
		(net "P2E_CPU_NGFF_RX_DP13")
	)
	(segment
		(start 36.2204 -47.879)
		(end 35.5854 -48.514)
		(width 0.1143)
		(layer "In7.Cu")
		(net "P2E_CPU_NGFF_RX_DP13")
	)
	(segment
		(start 92.127578 -49.049178)
		(end 92.127578 -49.5808)
		(width 0.1016)
		(layer "In7.Cu")
		(net "P2E_CPU_NGFF_RX_DP13")
	)
	(segment
		(start 34.6456 -48.514)
		(end 32.2326 -46.101)
		(width 0.1143)
		(layer "In7.Cu")
		(net "P2E_CPU_NGFF_RX_DP13")
	)
	(segment
		(start 37.973 -47.879)
		(end 36.2204 -47.879)
		(width 0.1143)
		(layer "In7.Cu")
		(net "P2E_CPU_NGFF_RX_DP13")
	)
	(segment
		(start 60.416694 -51.993546)
		(end 59.375548 -50.9524)
		(width 0.1143)
		(layer "In7.Cu")
		(net "P2E_CPU_NGFF_RX_DP13")
	)
	(segment
		(start 92.68333 -48.499014)
		(end 92.677742 -48.499014)
		(width 0.1016)
		(layer "In7.Cu")
		(net "P2E_CPU_NGFF_RX_DP13")
	)
	(segment
		(start 60.86094 -53.702966)
		(end 60.416694 -53.25872)
		(width 0.1143)
		(layer "In7.Cu")
		(net "P2E_CPU_NGFF_RX_DP13")
	)
	(segment
		(start 76.708 -52.832)
		(end 75.9841 -52.832)
		(width 0.1143)
		(layer "In7.Cu")
		(net "P2E_CPU_NGFF_RX_DP13")
	)
	(segment
		(start 87.0585 -55.4101)
		(end 86.995 -55.3466)
		(width 0.1016)
		(layer "In7.Cu")
		(net "P2E_CPU_NGFF_RX_DP13")
	)
	(segment
		(start 9.9568 -57.7342)
		(end 9.6266 -57.404)
		(width 0.1143)
		(layer "In7.Cu")
		(net "P2E_CPU_NGFF_RX_DP13")
	)
	(segment
		(start 87.8713 -55.4101)
		(end 87.0585 -55.4101)
		(width 0.1016)
		(layer "In7.Cu")
		(net "P2E_CPU_NGFF_RX_DP13")
	)
	(segment
		(start 38.608 -48.514)
		(end 37.973 -47.879)
		(width 0.1143)
		(layer "In7.Cu")
		(net "P2E_CPU_NGFF_RX_DP13")
	)
	(segment
		(start 86.995 -55.3466)
		(end 86.9696 -55.3466)
		(width 0.1016)
		(layer "In7.Cu")
		(net "P2E_CPU_NGFF_RX_DP13")
	)
	(segment
		(start 85.152484 -56.7182)
		(end 82.3214 -56.7182)
		(width 0.1143)
		(layer "In7.Cu")
		(net "P2E_CPU_NGFF_RX_DP13")
	)
	(segment
		(start 92.330778 -50.891694)
		(end 91.821 -51.401472)
		(width 0.1016)
		(layer "In7.Cu")
		(net "P2E_CPU_NGFF_RX_DP13")
	)
	(segment
		(start 11.8364 -56.1594)
		(end 10.2616 -57.7342)
		(width 0.1143)
		(layer "In7.Cu")
		(net "P2E_CPU_NGFF_RX_DP13")
	)
	(segment
		(start 82.0166 -56.4134)
		(end 80.2894 -56.4134)
		(width 0.1143)
		(layer "In7.Cu")
		(net "P2E_CPU_NGFF_RX_DP13")
	)
	(segment
		(start 75.9841 -52.832)
		(end 75.21194 -52.05984)
		(width 0.1143)
		(layer "In7.Cu")
		(net "P2E_CPU_NGFF_RX_DP13")
	)
	(segment
		(start 20.6502 -47.5996)
		(end 18.013426 -50.236374)
		(width 0.1143)
		(layer "In7.Cu")
		(net "P2E_CPU_NGFF_RX_DP13")
	)
	(segment
		(start 61.915294 -52.95265)
		(end 61.164978 -53.702966)
		(width 0.1143)
		(layer "In7.Cu")
		(net "P2E_CPU_NGFF_RX_DP13")
	)
	(segment
		(start 91.821 -51.401472)
		(end 91.821 -55.2196)
		(width 0.1016)
		(layer "In7.Cu")
		(net "P2E_CPU_NGFF_RX_DP13")
	)
	(segment
		(start 92.677742 -48.499014)
		(end 92.127578 -49.049178)
		(width 0.1016)
		(layer "In7.Cu")
		(net "P2E_CPU_NGFF_RX_DP13")
	)
	(segment
		(start 11.8364 -53.645816)
		(end 11.8364 -56.1594)
		(width 0.1143)
		(layer "In7.Cu")
		(net "P2E_CPU_NGFF_RX_DP13")
	)
	(segment
		(start 23.928832 -47.5996)
		(end 20.6502 -47.5996)
		(width 0.1143)
		(layer "In7.Cu")
		(net "P2E_CPU_NGFF_RX_DP13")
	)
	(segment
		(start 90.4494 -55.6641)
		(end 90.0303 -55.245)
		(width 0.1016)
		(layer "In7.Cu")
		(net "P2E_CPU_NGFF_RX_DP13")
	)
	(segment
		(start 32.2326 -46.101)
		(end 25.427432 -46.101)
		(width 0.1143)
		(layer "In7.Cu")
		(net "P2E_CPU_NGFF_RX_DP13")
	)
	(segment
		(start 86.524084 -55.3466)
		(end 85.152484 -56.7182)
		(width 0.1143)
		(layer "In7.Cu")
		(net "P2E_CPU_NGFF_RX_DP13")
	)
	(segment
		(start 88.0364 -55.245)
		(end 87.8713 -55.4101)
		(width 0.1016)
		(layer "In7.Cu")
		(net "P2E_CPU_NGFF_RX_DP13")
	)
	(segment
		(start 25.427432 -46.101)
		(end 23.928832 -47.5996)
		(width 0.1143)
		(layer "In7.Cu")
		(net "P2E_CPU_NGFF_RX_DP13")
	)
	(segment
		(start 39.7256 -47.879)
		(end 39.0906 -48.514)
		(width 0.1143)
		(layer "In7.Cu")
		(net "P2E_CPU_NGFF_RX_DP13")
	)
	(segment
		(start 91.821 -55.2196)
		(end 91.3765 -55.6641)
		(width 0.1016)
		(layer "In7.Cu")
		(net "P2E_CPU_NGFF_RX_DP13")
	)
	(segment
		(start 91.3765 -55.6641)
		(end 90.4494 -55.6641)
		(width 0.1016)
		(layer "In7.Cu")
		(net "P2E_CPU_NGFF_RX_DP13")
	)
	(segment
		(start 65.30975 -52.95265)
		(end 61.915294 -52.95265)
		(width 0.1143)
		(layer "In7.Cu")
		(net "P2E_CPU_NGFF_RX_DP13")
	)
	(segment
		(start 66.20256 -52.05984)
		(end 65.30975 -52.95265)
		(width 0.1143)
		(layer "In7.Cu")
		(net "P2E_CPU_NGFF_RX_DP13")
	)
	(segment
		(start 86.9696 -55.3466)
		(end 86.524084 -55.3466)
		(width 0.1143)
		(layer "In7.Cu")
		(net "P2E_CPU_NGFF_RX_DP13")
	)
	(segment
		(start 39.0906 -48.514)
		(end 38.608 -48.514)
		(width 0.1143)
		(layer "In7.Cu")
		(net "P2E_CPU_NGFF_RX_DP13")
	)
	(segment
		(start 18.013426 -50.236374)
		(end 15.245842 -50.236374)
		(width 0.1143)
		(layer "In7.Cu")
		(net "P2E_CPU_NGFF_RX_DP13")
	)
	(segment
		(start 92.127578 -49.5808)
		(end 92.330778 -49.784)
		(width 0.1016)
		(layer "In7.Cu")
		(net "P2E_CPU_NGFF_RX_DP13")
	)
	(segment
		(start 42.072306 -47.879)
		(end 39.7256 -47.879)
		(width 0.1143)
		(layer "In7.Cu")
		(net "P2E_CPU_NGFF_RX_DP13")
	)
	(segment
		(start 60.416694 -53.25872)
		(end 60.416694 -51.993546)
		(width 0.1143)
		(layer "In7.Cu")
		(net "P2E_CPU_NGFF_RX_DP13")
	)
	(segment
		(start 61.164978 -53.702966)
		(end 60.86094 -53.702966)
		(width 0.1143)
		(layer "In7.Cu")
		(net "P2E_CPU_NGFF_RX_DP13")
	)
	(segment
		(start 90.0303 -55.245)
		(end 88.0364 -55.245)
		(width 0.1016)
		(layer "In7.Cu")
		(net "P2E_CPU_NGFF_RX_DP13")
	)
	(segment
		(start 59.375548 -50.9524)
		(end 56.063134 -50.9524)
		(width 0.1143)
		(layer "In7.Cu")
		(net "P2E_CPU_NGFF_RX_DP13")
	)
	(segment
		(start 75.21194 -52.05984)
		(end 66.20256 -52.05984)
		(width 0.1143)
		(layer "In7.Cu")
		(net "P2E_CPU_NGFF_RX_DP13")
	)
	(segment
		(start 92.330778 -49.784)
		(end 92.330778 -50.891694)
		(width 0.1016)
		(layer "In7.Cu")
		(net "P2E_CPU_NGFF_RX_DP13")
	)
	(segment
		(start 56.063134 -50.9524)
		(end 54.964584 -49.85385)
		(width 0.1143)
		(layer "In7.Cu")
		(net "P2E_CPU_NGFF_RX_DP13")
	)
	(segment
		(start 35.5854 -48.514)
		(end 34.6456 -48.514)
		(width 0.1143)
		(layer "In7.Cu")
		(net "P2E_CPU_NGFF_RX_DP13")
	)
	(segment
		(start 44.047156 -49.85385)
		(end 42.072306 -47.879)
		(width 0.1143)
		(layer "In7.Cu")
		(net "P2E_CPU_NGFF_RX_DP13")
	)
	(segment
		(start 82.3214 -56.7182)
		(end 82.0166 -56.4134)
		(width 0.1143)
		(layer "In7.Cu")
		(net "P2E_CPU_NGFF_RX_DP13")
	)
	(segment
		(start 54.964584 -49.85385)
		(end 44.047156 -49.85385)
		(width 0.1143)
		(layer "In7.Cu")
		(net "P2E_CPU_NGFF_RX_DP13")
	)
	(segment
		(start 4.62661 -65.014094)
		(end 3.7592 -65.014094)
		(width 0.1397)
		(layer "F.Cu")
		(net "P2E_CPU_NGFF_TX_DP15")
	)
	(segment
		(start 3.7592 -65.014094)
		(end 3.45186 -64.706754)
		(width 0.1397)
		(layer "F.Cu")
		(net "P2E_CPU_NGFF_TX_DP15")
	)
	(segment
		(start 6.604254 -63.03645)
		(end 4.62661 -65.014094)
		(width 0.1397)
		(layer "F.Cu")
		(net "P2E_CPU_NGFF_TX_DP15")
	)
	(segment
		(start 8.0518 -62.738)
		(end 7.75335 -63.03645)
		(width 0.1397)
		(layer "F.Cu")
		(net "P2E_CPU_NGFF_TX_DP15")
	)
	(segment
		(start 7.75335 -63.03645)
		(end 6.604254 -63.03645)
		(width 0.1397)
		(layer "F.Cu")
		(net "P2E_CPU_NGFF_TX_DP15")
	)
	(via
		(at 3.45186 -64.706754)
		(size 0.508)
		(drill 0.254)
		(layers "F.Cu" "B.Cu")
		(net "P2E_CPU_NGFF_TX_DP15")
	)
	(segment
		(start 3.7592 -65.014094)
		(end 3.45186 -64.706754)
		(width 0.1397)
		(layer "B.Cu")
		(net "P2E_CPU_NGFF_TX_DP15")
	)
	(segment
		(start 4.890262 -64.949832)
		(end 4.826 -65.014094)
		(width 0.1397)
		(layer "B.Cu")
		(net "P2E_CPU_NGFF_TX_DP15")
	)
	(segment
		(start 5.575046 -64.949832)
		(end 4.890262 -64.949832)
		(width 0.1397)
		(layer "B.Cu")
		(net "P2E_CPU_NGFF_TX_DP15")
	)
	(segment
		(start 4.826 -65.014094)
		(end 3.7592 -65.014094)
		(width 0.1397)
		(layer "B.Cu")
		(net "P2E_CPU_NGFF_TX_DP15")
	)
	(segment
		(start 7.80415 -63.37935)
		(end 6.746494 -63.37935)
		(width 0.1397)
		(layer "F.Cu")
		(net "P2E_CPU_NGFF_TX_DN15")
	)
	(segment
		(start 6.746494 -63.37935)
		(end 4.76885 -65.356994)
		(width 0.1397)
		(layer "F.Cu")
		(net "P2E_CPU_NGFF_TX_DN15")
	)
	(segment
		(start 4.76885 -65.356994)
		(end 3.7592 -65.356994)
		(width 0.1397)
		(layer "F.Cu")
		(net "P2E_CPU_NGFF_TX_DN15")
	)
	(segment
		(start 3.7592 -65.356994)
		(end 3.45186 -65.664334)
		(width 0.1397)
		(layer "F.Cu")
		(net "P2E_CPU_NGFF_TX_DN15")
	)
	(segment
		(start 8.0518 -63.627)
		(end 7.80415 -63.37935)
		(width 0.1397)
		(layer "F.Cu")
		(net "P2E_CPU_NGFF_TX_DN15")
	)
	(via
		(at 3.45186 -65.664334)
		(size 0.508)
		(drill 0.254)
		(layers "F.Cu" "B.Cu")
		(net "P2E_CPU_NGFF_TX_DN15")
	)
	(segment
		(start 4.7752 -65.356994)
		(end 3.7592 -65.356994)
		(width 0.1397)
		(layer "B.Cu")
		(net "P2E_CPU_NGFF_TX_DN15")
	)
	(segment
		(start 5.575046 -65.449958)
		(end 4.868164 -65.449958)
		(width 0.1397)
		(layer "B.Cu")
		(net "P2E_CPU_NGFF_TX_DN15")
	)
	(segment
		(start 3.7592 -65.356994)
		(end 3.45186 -65.664334)
		(width 0.1397)
		(layer "B.Cu")
		(net "P2E_CPU_NGFF_TX_DN15")
	)
	(segment
		(start 4.868164 -65.449958)
		(end 4.7752 -65.356994)
		(width 0.1397)
		(layer "B.Cu")
		(net "P2E_CPU_NGFF_TX_DN15")
	)
	(segment
		(start 7.191248 -59.82335)
		(end 4.657598 -62.357)
		(width 0.1397)
		(layer "F.Cu")
		(net "P2E_CPU_NGFF_TX_DN14")
	)
	(segment
		(start 4.657598 -62.357)
		(end 3.7592 -62.357)
		(width 0.1397)
		(layer "F.Cu")
		(net "P2E_CPU_NGFF_TX_DN14")
	)
	(segment
		(start 7.80415 -59.82335)
		(end 7.191248 -59.82335)
		(width 0.1397)
		(layer "F.Cu")
		(net "P2E_CPU_NGFF_TX_DN14")
	)
	(segment
		(start 8.0518 -60.071)
		(end 7.80415 -59.82335)
		(width 0.1397)
		(layer "F.Cu")
		(net "P2E_CPU_NGFF_TX_DN14")
	)
	(segment
		(start 3.7592 -62.357)
		(end 3.45186 -62.66434)
		(width 0.1397)
		(layer "F.Cu")
		(net "P2E_CPU_NGFF_TX_DN14")
	)
	(via
		(at 3.45186 -62.66434)
		(size 0.508)
		(drill 0.254)
		(layers "F.Cu" "B.Cu")
		(net "P2E_CPU_NGFF_TX_DN14")
	)
	(segment
		(start 4.490466 -62.357)
		(end 3.7592 -62.357)
		(width 0.1397)
		(layer "B.Cu")
		(net "P2E_CPU_NGFF_TX_DN14")
	)
	(segment
		(start 5.575046 -62.449964)
		(end 4.58343 -62.449964)
		(width 0.1397)
		(layer "B.Cu")
		(net "P2E_CPU_NGFF_TX_DN14")
	)
	(segment
		(start 3.7592 -62.357)
		(end 3.45186 -62.66434)
		(width 0.1397)
		(layer "B.Cu")
		(net "P2E_CPU_NGFF_TX_DN14")
	)
	(segment
		(start 4.58343 -62.449964)
		(end 4.490466 -62.357)
		(width 0.1397)
		(layer "B.Cu")
		(net "P2E_CPU_NGFF_TX_DN14")
	)
	(segment
		(start 8.0518 -59.182)
		(end 7.75335 -59.48045)
		(width 0.1397)
		(layer "F.Cu")
		(net "P2E_CPU_NGFF_TX_DP14")
	)
	(segment
		(start 7.75335 -59.48045)
		(end 7.049008 -59.48045)
		(width 0.1397)
		(layer "F.Cu")
		(net "P2E_CPU_NGFF_TX_DP14")
	)
	(segment
		(start 7.049008 -59.48045)
		(end 4.515358 -62.0141)
		(width 0.1397)
		(layer "F.Cu")
		(net "P2E_CPU_NGFF_TX_DP14")
	)
	(segment
		(start 3.7592 -62.0141)
		(end 3.45186 -61.70676)
		(width 0.1397)
		(layer "F.Cu")
		(net "P2E_CPU_NGFF_TX_DP14")
	)
	(segment
		(start 4.515358 -62.0141)
		(end 3.7592 -62.0141)
		(width 0.1397)
		(layer "F.Cu")
		(net "P2E_CPU_NGFF_TX_DP14")
	)
	(via
		(at 3.45186 -61.70676)
		(size 0.508)
		(drill 0.254)
		(layers "F.Cu" "B.Cu")
		(net "P2E_CPU_NGFF_TX_DP14")
	)
	(segment
		(start 3.7592 -62.0141)
		(end 3.45186 -61.70676)
		(width 0.1397)
		(layer "B.Cu")
		(net "P2E_CPU_NGFF_TX_DP14")
	)
	(segment
		(start 4.583176 -61.949838)
		(end 4.518914 -62.0141)
		(width 0.1397)
		(layer "B.Cu")
		(net "P2E_CPU_NGFF_TX_DP14")
	)
	(segment
		(start 5.575046 -61.949838)
		(end 4.583176 -61.949838)
		(width 0.1397)
		(layer "B.Cu")
		(net "P2E_CPU_NGFF_TX_DP14")
	)
	(segment
		(start 4.518914 -62.0141)
		(end 3.7592 -62.0141)
		(width 0.1397)
		(layer "B.Cu")
		(net "P2E_CPU_NGFF_TX_DP14")
	)
	(segment
		(start 3.6322 -59.357006)
		(end 3.32486 -59.664346)
		(width 0.1397)
		(layer "F.Cu")
		(net "P2E_CPU_NGFF_TX_DN13")
	)
	(segment
		(start 8.0518 -56.515)
		(end 7.77875 -56.24195)
		(width 0.1397)
		(layer "F.Cu")
		(net "P2E_CPU_NGFF_TX_DN13")
	)
	(segment
		(start 4.399534 -59.357006)
		(end 3.6322 -59.357006)
		(width 0.1397)
		(layer "F.Cu")
		(net "P2E_CPU_NGFF_TX_DN13")
	)
	(segment
		(start 7.51459 -56.24195)
		(end 4.399534 -59.357006)
		(width 0.1397)
		(layer "F.Cu")
		(net "P2E_CPU_NGFF_TX_DN13")
	)
	(segment
		(start 7.77875 -56.24195)
		(end 7.51459 -56.24195)
		(width 0.1397)
		(layer "F.Cu")
		(net "P2E_CPU_NGFF_TX_DN13")
	)
	(via
		(at 3.32486 -59.664346)
		(size 0.508)
		(drill 0.254)
		(layers "F.Cu" "B.Cu")
		(net "P2E_CPU_NGFF_TX_DN13")
	)
	(segment
		(start 4.826 -59.357006)
		(end 3.6322 -59.357006)
		(width 0.1397)
		(layer "B.Cu")
		(net "P2E_CPU_NGFF_TX_DN13")
	)
	(segment
		(start 4.918964 -59.44997)
		(end 4.826 -59.357006)
		(width 0.1397)
		(layer "B.Cu")
		(net "P2E_CPU_NGFF_TX_DN13")
	)
	(segment
		(start 5.575046 -59.44997)
		(end 4.918964 -59.44997)
		(width 0.1397)
		(layer "B.Cu")
		(net "P2E_CPU_NGFF_TX_DN13")
	)
	(segment
		(start 3.6322 -59.357006)
		(end 3.32486 -59.664346)
		(width 0.1397)
		(layer "B.Cu")
		(net "P2E_CPU_NGFF_TX_DN13")
	)
	(segment
		(start 8.0518 -55.626)
		(end 7.77875 -55.89905)
		(width 0.1397)
		(layer "F.Cu")
		(net "P2E_CPU_NGFF_TX_DP13")
	)
	(segment
		(start 4.257294 -59.014106)
		(end 3.6322 -59.014106)
		(width 0.1397)
		(layer "F.Cu")
		(net "P2E_CPU_NGFF_TX_DP13")
	)
	(segment
		(start 7.37235 -55.89905)
		(end 4.257294 -59.014106)
		(width 0.1397)
		(layer "F.Cu")
		(net "P2E_CPU_NGFF_TX_DP13")
	)
	(segment
		(start 7.77875 -55.89905)
		(end 7.37235 -55.89905)
		(width 0.1397)
		(layer "F.Cu")
		(net "P2E_CPU_NGFF_TX_DP13")
	)
	(segment
		(start 3.6322 -59.014106)
		(end 3.32486 -58.706766)
		(width 0.1397)
		(layer "F.Cu")
		(net "P2E_CPU_NGFF_TX_DP13")
	)
	(via
		(at 3.32486 -58.706766)
		(size 0.508)
		(drill 0.254)
		(layers "F.Cu" "B.Cu")
		(net "P2E_CPU_NGFF_TX_DP13")
	)
	(segment
		(start 4.890262 -58.949844)
		(end 4.826 -59.014106)
		(width 0.1397)
		(layer "B.Cu")
		(net "P2E_CPU_NGFF_TX_DP13")
	)
	(segment
		(start 4.826 -59.014106)
		(end 3.6322 -59.014106)
		(width 0.1397)
		(layer "B.Cu")
		(net "P2E_CPU_NGFF_TX_DP13")
	)
	(segment
		(start 5.575046 -58.949844)
		(end 4.890262 -58.949844)
		(width 0.1397)
		(layer "B.Cu")
		(net "P2E_CPU_NGFF_TX_DP13")
	)
	(segment
		(start 3.6322 -59.014106)
		(end 3.32486 -58.706766)
		(width 0.1397)
		(layer "B.Cu")
		(net "P2E_CPU_NGFF_TX_DP13")
	)
	(segment
		(start 13.35024 -53.6829)
		(end 14.224 -52.80914)
		(width 0.1397)
		(layer "F.Cu")
		(net "P2E_CPU_NGFF_RX_DN12")
	)
	(segment
		(start 14.224 -52.80914)
		(end 14.224 -49.647348)
		(width 0.1397)
		(layer "F.Cu")
		(net "P2E_CPU_NGFF_RX_DN12")
	)
	(segment
		(start 14.8336 -49.037748)
		(end 14.8336 -47.081186)
		(width 0.1397)
		(layer "F.Cu")
		(net "P2E_CPU_NGFF_RX_DN12")
	)
	(segment
		(start 92.108528 -48.805846)
		(end 92.108528 -48.783494)
		(width 0.1397)
		(layer "F.Cu")
		(net "P2E_CPU_NGFF_RX_DN12")
	)
	(segment
		(start 14.224 -49.647348)
		(end 14.8336 -49.037748)
		(width 0.1397)
		(layer "F.Cu")
		(net "P2E_CPU_NGFF_RX_DN12")
	)
	(segment
		(start 12.5984 -54.0258)
		(end 12.5984 -53.86451)
		(width 0.1397)
		(layer "F.Cu")
		(net "P2E_CPU_NGFF_RX_DN12")
	)
	(segment
		(start 14.8336 -47.081186)
		(end 15.082266 -46.83252)
		(width 0.1397)
		(layer "F.Cu")
		(net "P2E_CPU_NGFF_RX_DN12")
	)
	(segment
		(start 91.759278 -49.155096)
		(end 92.108528 -48.805846)
		(width 0.1397)
		(layer "F.Cu")
		(net "P2E_CPU_NGFF_RX_DN12")
	)
	(segment
		(start 12.78001 -53.6829)
		(end 13.35024 -53.6829)
		(width 0.1397)
		(layer "F.Cu")
		(net "P2E_CPU_NGFF_RX_DN12")
	)
	(segment
		(start 12.5984 -53.86451)
		(end 12.78001 -53.6829)
		(width 0.1397)
		(layer "F.Cu")
		(net "P2E_CPU_NGFF_RX_DN12")
	)
	(via
		(at 91.759278 -49.155096)
		(size 0.4318)
		(drill 0.2032)
		(layers "F.Cu" "B.Cu")
		(net "P2E_CPU_NGFF_RX_DN12")
	)
	(via
		(at 15.082266 -46.83252)
		(size 0.508)
		(drill 0.254)
		(layers "F.Cu" "B.Cu")
		(net "P2E_CPU_NGFF_RX_DN12")
	)
	(segment
		(start 28.826206 -39.8399)
		(end 29.867606 -38.7985)
		(width 0.1143)
		(layer "In7.Cu")
		(net "P2E_CPU_NGFF_RX_DN12")
	)
	(segment
		(start 82.1817 -51.1429)
		(end 82.42935 -51.1429)
		(width 0.1016)
		(layer "In7.Cu")
		(net "P2E_CPU_NGFF_RX_DN12")
	)
	(segment
		(start 15.082266 -46.83252)
		(end 14.7828 -46.533054)
		(width 0.1143)
		(layer "In7.Cu")
		(net "P2E_CPU_NGFF_RX_DN12")
	)
	(segment
		(start 91.186 -52.07)
		(end 91.44 -51.816)
		(width 0.1016)
		(layer "In7.Cu")
		(net "P2E_CPU_NGFF_RX_DN12")
	)
	(segment
		(start 84.7344 -51.5874)
		(end 86.5378 -51.5874)
		(width 0.1016)
		(layer "In7.Cu")
		(net "P2E_CPU_NGFF_RX_DN12")
	)
	(segment
		(start 79.263494 -51.2064)
		(end 79.816706 -51.2064)
		(width 0.1143)
		(layer "In7.Cu")
		(net "P2E_CPU_NGFF_RX_DN12")
	)
	(segment
		(start 48.4886 -44.2976)
		(end 51.0032 -44.2976)
		(width 0.1143)
		(layer "In7.Cu")
		(net "P2E_CPU_NGFF_RX_DN12")
	)
	(segment
		(start 62.004194 -48.4759)
		(end 63.47333 -48.4759)
		(width 0.1143)
		(layer "In7.Cu")
		(net "P2E_CPU_NGFF_RX_DN12")
	)
	(segment
		(start 64.52997 -49.53254)
		(end 75.811634 -49.53254)
		(width 0.1143)
		(layer "In7.Cu")
		(net "P2E_CPU_NGFF_RX_DN12")
	)
	(segment
		(start 55.414418 -44.5262)
		(end 55.627778 -44.73956)
		(width 0.1143)
		(layer "In7.Cu")
		(net "P2E_CPU_NGFF_RX_DN12")
	)
	(segment
		(start 91.594178 -49.65065)
		(end 91.594178 -49.320196)
		(width 0.1016)
		(layer "In7.Cu")
		(net "P2E_CPU_NGFF_RX_DN12")
	)
	(segment
		(start 53.189378 -44.5262)
		(end 53.402738 -44.73956)
		(width 0.1143)
		(layer "In7.Cu")
		(net "P2E_CPU_NGFF_RX_DN12")
	)
	(segment
		(start 44.239434 -41.826434)
		(end 46.017434 -41.826434)
		(width 0.1143)
		(layer "In7.Cu")
		(net "P2E_CPU_NGFF_RX_DN12")
	)
	(segment
		(start 91.813888 -50.578512)
		(end 91.813888 -49.87036)
		(width 0.1016)
		(layer "In7.Cu")
		(net "P2E_CPU_NGFF_RX_DN12")
	)
	(segment
		(start 55.627778 -44.73956)
		(end 55.970678 -44.73956)
		(width 0.1143)
		(layer "In7.Cu")
		(net "P2E_CPU_NGFF_RX_DN12")
	)
	(segment
		(start 91.813888 -49.87036)
		(end 91.594178 -49.65065)
		(width 0.1016)
		(layer "In7.Cu")
		(net "P2E_CPU_NGFF_RX_DN12")
	)
	(segment
		(start 86.5378 -51.5874)
		(end 86.7664 -51.3588)
		(width 0.1016)
		(layer "In7.Cu")
		(net "P2E_CPU_NGFF_RX_DN12")
	)
	(segment
		(start 91.44 -51.816)
		(end 91.44 -50.9524)
		(width 0.1016)
		(layer "In7.Cu")
		(net "P2E_CPU_NGFF_RX_DN12")
	)
	(segment
		(start 27.4574 -38.2016)
		(end 27.6352 -38.3794)
		(width 0.1143)
		(layer "In7.Cu")
		(net "P2E_CPU_NGFF_RX_DN12")
	)
	(segment
		(start 83.329272 -51.3588)
		(end 84.5058 -51.3588)
		(width 0.1016)
		(layer "In7.Cu")
		(net "P2E_CPU_NGFF_RX_DN12")
	)
	(segment
		(start 29.867606 -38.7985)
		(end 38.9255 -38.7985)
		(width 0.1143)
		(layer "In7.Cu")
		(net "P2E_CPU_NGFF_RX_DN12")
	)
	(segment
		(start 63.47333 -48.4759)
		(end 64.52997 -49.53254)
		(width 0.1143)
		(layer "In7.Cu")
		(net "P2E_CPU_NGFF_RX_DN12")
	)
	(segment
		(start 54.515258 -44.73956)
		(end 54.858158 -44.73956)
		(width 0.1143)
		(layer "In7.Cu")
		(net "P2E_CPU_NGFF_RX_DN12")
	)
	(segment
		(start 82.992722 -51.02225)
		(end 83.329272 -51.3588)
		(width 0.1016)
		(layer "In7.Cu")
		(net "P2E_CPU_NGFF_RX_DN12")
	)
	(segment
		(start 82.1182 -51.2064)
		(end 82.1817 -51.1429)
		(width 0.1016)
		(layer "In7.Cu")
		(net "P2E_CPU_NGFF_RX_DN12")
	)
	(segment
		(start 15.812008 -45.249592)
		(end 16.11376 -45.249592)
		(width 0.1143)
		(layer "In7.Cu")
		(net "P2E_CPU_NGFF_RX_DN12")
	)
	(segment
		(start 56.184038 -44.5262)
		(end 56.526938 -44.5262)
		(width 0.1143)
		(layer "In7.Cu")
		(net "P2E_CPU_NGFF_RX_DN12")
	)
	(segment
		(start 16.11376 -45.249592)
		(end 16.356076 -45.007276)
		(width 0.1143)
		(layer "In7.Cu")
		(net "P2E_CPU_NGFF_RX_DN12")
	)
	(segment
		(start 14.7828 -46.2788)
		(end 15.02537 -46.03623)
		(width 0.1143)
		(layer "In7.Cu")
		(net "P2E_CPU_NGFF_RX_DN12")
	)
	(segment
		(start 41.13784 -39.96436)
		(end 41.3512 -39.751)
		(width 0.1143)
		(layer "In7.Cu")
		(net "P2E_CPU_NGFF_RX_DN12")
	)
	(segment
		(start 80.812894 -50.8762)
		(end 81.143094 -51.2064)
		(width 0.1143)
		(layer "In7.Cu")
		(net "P2E_CPU_NGFF_RX_DN12")
	)
	(segment
		(start 42.164 -39.751)
		(end 44.239434 -41.826434)
		(width 0.1143)
		(layer "In7.Cu")
		(net "P2E_CPU_NGFF_RX_DN12")
	)
	(segment
		(start 27.6352 -39.341806)
		(end 28.133294 -39.8399)
		(width 0.1143)
		(layer "In7.Cu")
		(net "P2E_CPU_NGFF_RX_DN12")
	)
	(segment
		(start 61.559694 -48.0314)
		(end 62.004194 -48.4759)
		(width 0.1143)
		(layer "In7.Cu")
		(net "P2E_CPU_NGFF_RX_DN12")
	)
	(segment
		(start 16.356076 -44.705524)
		(end 16.8275 -44.2341)
		(width 0.1143)
		(layer "In7.Cu")
		(net "P2E_CPU_NGFF_RX_DN12")
	)
	(segment
		(start 14.7828 -46.533054)
		(end 14.7828 -46.2788)
		(width 0.1143)
		(layer "In7.Cu")
		(net "P2E_CPU_NGFF_RX_DN12")
	)
	(segment
		(start 15.569438 -45.492162)
		(end 15.812008 -45.249592)
		(width 0.1143)
		(layer "In7.Cu")
		(net "P2E_CPU_NGFF_RX_DN12")
	)
	(segment
		(start 78.552294 -50.4952)
		(end 79.263494 -51.2064)
		(width 0.1143)
		(layer "In7.Cu")
		(net "P2E_CPU_NGFF_RX_DN12")
	)
	(segment
		(start 23.0759 -44.2341)
		(end 24.59482 -42.71518)
		(width 0.1143)
		(layer "In7.Cu")
		(net "P2E_CPU_NGFF_RX_DN12")
	)
	(segment
		(start 82.42935 -51.1429)
		(end 82.55 -51.02225)
		(width 0.1016)
		(layer "In7.Cu")
		(net "P2E_CPU_NGFF_RX_DN12")
	)
	(segment
		(start 24.59482 -42.71518)
		(end 24.59482 -40.820086)
		(width 0.1143)
		(layer "In7.Cu")
		(net "P2E_CPU_NGFF_RX_DN12")
	)
	(segment
		(start 82.0928 -51.2064)
		(end 82.1182 -51.2064)
		(width 0.1016)
		(layer "In7.Cu")
		(net "P2E_CPU_NGFF_RX_DN12")
	)
	(segment
		(start 55.071518 -44.5262)
		(end 55.414418 -44.5262)
		(width 0.1143)
		(layer "In7.Cu")
		(net "P2E_CPU_NGFF_RX_DN12")
	)
	(segment
		(start 16.356076 -45.007276)
		(end 16.356076 -44.705524)
		(width 0.1143)
		(layer "In7.Cu")
		(net "P2E_CPU_NGFF_RX_DN12")
	)
	(segment
		(start 60.032138 -48.0314)
		(end 61.559694 -48.0314)
		(width 0.1143)
		(layer "In7.Cu")
		(net "P2E_CPU_NGFF_RX_DN12")
	)
	(segment
		(start 86.7664 -51.3588)
		(end 89.8398 -51.3588)
		(width 0.1016)
		(layer "In7.Cu")
		(net "P2E_CPU_NGFF_RX_DN12")
	)
	(segment
		(start 91.44 -50.9524)
		(end 91.813888 -50.578512)
		(width 0.1016)
		(layer "In7.Cu")
		(net "P2E_CPU_NGFF_RX_DN12")
	)
	(segment
		(start 46.017434 -41.826434)
		(end 48.4886 -44.2976)
		(width 0.1143)
		(layer "In7.Cu")
		(net "P2E_CPU_NGFF_RX_DN12")
	)
	(segment
		(start 51.2318 -44.5262)
		(end 53.189378 -44.5262)
		(width 0.1143)
		(layer "In7.Cu")
		(net "P2E_CPU_NGFF_RX_DN12")
	)
	(segment
		(start 16.8275 -44.2341)
		(end 23.0759 -44.2341)
		(width 0.1143)
		(layer "In7.Cu")
		(net "P2E_CPU_NGFF_RX_DN12")
	)
	(segment
		(start 82.55 -51.02225)
		(end 82.992722 -51.02225)
		(width 0.1016)
		(layer "In7.Cu")
		(net "P2E_CPU_NGFF_RX_DN12")
	)
	(segment
		(start 27.213306 -38.2016)
		(end 27.4574 -38.2016)
		(width 0.1143)
		(layer "In7.Cu")
		(net "P2E_CPU_NGFF_RX_DN12")
	)
	(segment
		(start 24.59482 -40.820086)
		(end 27.213306 -38.2016)
		(width 0.1143)
		(layer "In7.Cu")
		(net "P2E_CPU_NGFF_RX_DN12")
	)
	(segment
		(start 15.02537 -46.03623)
		(end 15.327122 -46.03623)
		(width 0.1143)
		(layer "In7.Cu")
		(net "P2E_CPU_NGFF_RX_DN12")
	)
	(segment
		(start 15.327122 -46.03623)
		(end 15.569438 -45.793914)
		(width 0.1143)
		(layer "In7.Cu")
		(net "P2E_CPU_NGFF_RX_DN12")
	)
	(segment
		(start 39.878 -39.751)
		(end 40.58158 -39.751)
		(width 0.1143)
		(layer "In7.Cu")
		(net "P2E_CPU_NGFF_RX_DN12")
	)
	(segment
		(start 76.774294 -50.4952)
		(end 78.552294 -50.4952)
		(width 0.1143)
		(layer "In7.Cu")
		(net "P2E_CPU_NGFF_RX_DN12")
	)
	(segment
		(start 53.958998 -44.5262)
		(end 54.301898 -44.5262)
		(width 0.1143)
		(layer "In7.Cu")
		(net "P2E_CPU_NGFF_RX_DN12")
	)
	(segment
		(start 27.6352 -38.3794)
		(end 27.6352 -39.341806)
		(width 0.1143)
		(layer "In7.Cu")
		(net "P2E_CPU_NGFF_RX_DN12")
	)
	(segment
		(start 81.143094 -51.2064)
		(end 82.0928 -51.2064)
		(width 0.1143)
		(layer "In7.Cu")
		(net "P2E_CPU_NGFF_RX_DN12")
	)
	(segment
		(start 15.569438 -45.793914)
		(end 15.569438 -45.492162)
		(width 0.1143)
		(layer "In7.Cu")
		(net "P2E_CPU_NGFF_RX_DN12")
	)
	(segment
		(start 53.402738 -44.73956)
		(end 53.745638 -44.73956)
		(width 0.1143)
		(layer "In7.Cu")
		(net "P2E_CPU_NGFF_RX_DN12")
	)
	(segment
		(start 53.745638 -44.73956)
		(end 53.958998 -44.5262)
		(width 0.1143)
		(layer "In7.Cu")
		(net "P2E_CPU_NGFF_RX_DN12")
	)
	(segment
		(start 51.0032 -44.2976)
		(end 51.2318 -44.5262)
		(width 0.1143)
		(layer "In7.Cu")
		(net "P2E_CPU_NGFF_RX_DN12")
	)
	(segment
		(start 89.8398 -51.3588)
		(end 90.551 -52.07)
		(width 0.1016)
		(layer "In7.Cu")
		(net "P2E_CPU_NGFF_RX_DN12")
	)
	(segment
		(start 79.816706 -51.2064)
		(end 80.146906 -50.8762)
		(width 0.1143)
		(layer "In7.Cu")
		(net "P2E_CPU_NGFF_RX_DN12")
	)
	(segment
		(start 91.594178 -49.320196)
		(end 91.759278 -49.155096)
		(width 0.1016)
		(layer "In7.Cu")
		(net "P2E_CPU_NGFF_RX_DN12")
	)
	(segment
		(start 55.970678 -44.73956)
		(end 56.184038 -44.5262)
		(width 0.1143)
		(layer "In7.Cu")
		(net "P2E_CPU_NGFF_RX_DN12")
	)
	(segment
		(start 41.3512 -39.751)
		(end 42.164 -39.751)
		(width 0.1143)
		(layer "In7.Cu")
		(net "P2E_CPU_NGFF_RX_DN12")
	)
	(segment
		(start 54.858158 -44.73956)
		(end 55.071518 -44.5262)
		(width 0.1143)
		(layer "In7.Cu")
		(net "P2E_CPU_NGFF_RX_DN12")
	)
	(segment
		(start 80.146906 -50.8762)
		(end 80.812894 -50.8762)
		(width 0.1143)
		(layer "In7.Cu")
		(net "P2E_CPU_NGFF_RX_DN12")
	)
	(segment
		(start 40.79494 -39.96436)
		(end 41.13784 -39.96436)
		(width 0.1143)
		(layer "In7.Cu")
		(net "P2E_CPU_NGFF_RX_DN12")
	)
	(segment
		(start 28.133294 -39.8399)
		(end 28.826206 -39.8399)
		(width 0.1143)
		(layer "In7.Cu")
		(net "P2E_CPU_NGFF_RX_DN12")
	)
	(segment
		(start 75.811634 -49.53254)
		(end 76.774294 -50.4952)
		(width 0.1143)
		(layer "In7.Cu")
		(net "P2E_CPU_NGFF_RX_DN12")
	)
	(segment
		(start 54.301898 -44.5262)
		(end 54.515258 -44.73956)
		(width 0.1143)
		(layer "In7.Cu")
		(net "P2E_CPU_NGFF_RX_DN12")
	)
	(segment
		(start 40.58158 -39.751)
		(end 40.79494 -39.96436)
		(width 0.1143)
		(layer "In7.Cu")
		(net "P2E_CPU_NGFF_RX_DN12")
	)
	(segment
		(start 84.5058 -51.3588)
		(end 84.7344 -51.5874)
		(width 0.1016)
		(layer "In7.Cu")
		(net "P2E_CPU_NGFF_RX_DN12")
	)
	(segment
		(start 38.9255 -38.7985)
		(end 39.878 -39.751)
		(width 0.1143)
		(layer "In7.Cu")
		(net "P2E_CPU_NGFF_RX_DN12")
	)
	(segment
		(start 90.551 -52.07)
		(end 91.186 -52.07)
		(width 0.1016)
		(layer "In7.Cu")
		(net "P2E_CPU_NGFF_RX_DN12")
	)
	(segment
		(start 56.526938 -44.5262)
		(end 60.032138 -48.0314)
		(width 0.1143)
		(layer "In7.Cu")
		(net "P2E_CPU_NGFF_RX_DN12")
	)
	(segment
		(start 14.4907 -47.17034)
		(end 14.15288 -46.83252)
		(width 0.1397)
		(layer "F.Cu")
		(net "P2E_CPU_NGFF_RX_DP12")
	)
	(segment
		(start 12.8016 -53.34)
		(end 13.208 -53.34)
		(width 0.1397)
		(layer "F.Cu")
		(net "P2E_CPU_NGFF_RX_DP12")
	)
	(segment
		(start 92.108528 -48.021494)
		(end 92.108528 -48.08855)
		(width 0.1397)
		(layer "F.Cu")
		(net "P2E_CPU_NGFF_RX_DP12")
	)
	(segment
		(start 12.5984 -52.7812)
		(end 12.5984 -53.1368)
		(width 0.1397)
		(layer "F.Cu")
		(net "P2E_CPU_NGFF_RX_DP12")
	)
	(segment
		(start 13.8811 -52.2478)
		(end 13.68044 -52.04714)
		(width 0.1397)
		(layer "F.Cu")
		(net "P2E_CPU_NGFF_RX_DP12")
	)
	(segment
		(start 13.68044 -50.38852)
		(end 13.8811 -50.18786)
		(width 0.1397)
		(layer "F.Cu")
		(net "P2E_CPU_NGFF_RX_DP12")
	)
	(segment
		(start 13.8811 -52.6669)
		(end 13.8811 -52.2478)
		(width 0.1397)
		(layer "F.Cu")
		(net "P2E_CPU_NGFF_RX_DP12")
	)
	(segment
		(start 13.8811 -49.505108)
		(end 14.4907 -48.895508)
		(width 0.1397)
		(layer "F.Cu")
		(net "P2E_CPU_NGFF_RX_DP12")
	)
	(segment
		(start 13.208 -53.34)
		(end 13.8811 -52.6669)
		(width 0.1397)
		(layer "F.Cu")
		(net "P2E_CPU_NGFF_RX_DP12")
	)
	(segment
		(start 13.68044 -52.04714)
		(end 13.68044 -51.62804)
		(width 0.1397)
		(layer "F.Cu")
		(net "P2E_CPU_NGFF_RX_DP12")
	)
	(segment
		(start 13.8811 -51.42738)
		(end 13.8811 -51.00828)
		(width 0.1397)
		(layer "F.Cu")
		(net "P2E_CPU_NGFF_RX_DP12")
	)
	(segment
		(start 12.5984 -53.1368)
		(end 12.8016 -53.34)
		(width 0.1397)
		(layer "F.Cu")
		(net "P2E_CPU_NGFF_RX_DP12")
	)
	(segment
		(start 13.68044 -51.62804)
		(end 13.8811 -51.42738)
		(width 0.1397)
		(layer "F.Cu")
		(net "P2E_CPU_NGFF_RX_DP12")
	)
	(segment
		(start 13.68044 -50.80762)
		(end 13.68044 -50.38852)
		(width 0.1397)
		(layer "F.Cu")
		(net "P2E_CPU_NGFF_RX_DP12")
	)
	(segment
		(start 13.8811 -50.18786)
		(end 13.8811 -49.505108)
		(width 0.1397)
		(layer "F.Cu")
		(net "P2E_CPU_NGFF_RX_DP12")
	)
	(segment
		(start 14.4907 -48.895508)
		(end 14.4907 -47.17034)
		(width 0.1397)
		(layer "F.Cu")
		(net "P2E_CPU_NGFF_RX_DP12")
	)
	(segment
		(start 92.108528 -48.08855)
		(end 91.759278 -48.4378)
		(width 0.1397)
		(layer "F.Cu")
		(net "P2E_CPU_NGFF_RX_DP12")
	)
	(segment
		(start 13.8811 -51.00828)
		(end 13.68044 -50.80762)
		(width 0.1397)
		(layer "F.Cu")
		(net "P2E_CPU_NGFF_RX_DP12")
	)
	(via
		(at 14.15288 -46.83252)
		(size 0.508)
		(drill 0.254)
		(layers "F.Cu" "B.Cu")
		(net "P2E_CPU_NGFF_RX_DP12")
	)
	(via
		(at 91.759278 -48.4378)
		(size 0.4318)
		(drill 0.2032)
		(layers "F.Cu" "B.Cu")
		(net "P2E_CPU_NGFF_RX_DP12")
	)
	(segment
		(start 82.345022 -50.9397)
		(end 82.465672 -50.81905)
		(width 0.1016)
		(layer "In7.Cu")
		(net "P2E_CPU_NGFF_RX_DP12")
	)
	(segment
		(start 24.26462 -40.68318)
		(end 27.0764 -37.8714)
		(width 0.1143)
		(layer "In7.Cu")
		(net "P2E_CPU_NGFF_RX_DP12")
	)
	(segment
		(start 29.7307 -38.4683)
		(end 39.062406 -38.4683)
		(width 0.1143)
		(layer "In7.Cu")
		(net "P2E_CPU_NGFF_RX_DP12")
	)
	(segment
		(start 80.9498 -50.546)
		(end 81.28 -50.8762)
		(width 0.1143)
		(layer "In7.Cu")
		(net "P2E_CPU_NGFF_RX_DP12")
	)
	(segment
		(start 76.9112 -50.165)
		(end 78.6892 -50.165)
		(width 0.1143)
		(layer "In7.Cu")
		(net "P2E_CPU_NGFF_RX_DP12")
	)
	(segment
		(start 27.9654 -39.2049)
		(end 28.2702 -39.5097)
		(width 0.1143)
		(layer "In7.Cu")
		(net "P2E_CPU_NGFF_RX_DP12")
	)
	(segment
		(start 82.1817 -50.9397)
		(end 82.345022 -50.9397)
		(width 0.1016)
		(layer "In7.Cu")
		(net "P2E_CPU_NGFF_RX_DP12")
	)
	(segment
		(start 82.1182 -50.8762)
		(end 82.1817 -50.9397)
		(width 0.1016)
		(layer "In7.Cu")
		(net "P2E_CPU_NGFF_RX_DP12")
	)
	(segment
		(start 48.625506 -43.9674)
		(end 51.140106 -43.9674)
		(width 0.1143)
		(layer "In7.Cu")
		(net "P2E_CPU_NGFF_RX_DP12")
	)
	(segment
		(start 83.4136 -51.1556)
		(end 84.590128 -51.1556)
		(width 0.1016)
		(layer "In7.Cu")
		(net "P2E_CPU_NGFF_RX_DP12")
	)
	(segment
		(start 62.1411 -48.1457)
		(end 63.610236 -48.1457)
		(width 0.1143)
		(layer "In7.Cu")
		(net "P2E_CPU_NGFF_RX_DP12")
	)
	(segment
		(start 75.94854 -49.20234)
		(end 76.9112 -50.165)
		(width 0.1143)
		(layer "In7.Cu")
		(net "P2E_CPU_NGFF_RX_DP12")
	)
	(segment
		(start 89.924128 -51.1556)
		(end 90.635328 -51.8668)
		(width 0.1016)
		(layer "In7.Cu")
		(net "P2E_CPU_NGFF_RX_DP12")
	)
	(segment
		(start 82.0928 -50.8762)
		(end 82.1182 -50.8762)
		(width 0.1016)
		(layer "In7.Cu")
		(net "P2E_CPU_NGFF_RX_DP12")
	)
	(segment
		(start 90.635328 -51.8668)
		(end 91.101672 -51.8668)
		(width 0.1016)
		(layer "In7.Cu")
		(net "P2E_CPU_NGFF_RX_DP12")
	)
	(segment
		(start 80.01 -50.546)
		(end 80.9498 -50.546)
		(width 0.1143)
		(layer "In7.Cu")
		(net "P2E_CPU_NGFF_RX_DP12")
	)
	(segment
		(start 91.2368 -50.868072)
		(end 91.610688 -50.494184)
		(width 0.1016)
		(layer "In7.Cu")
		(net "P2E_CPU_NGFF_RX_DP12")
	)
	(segment
		(start 14.4526 -46.5328)
		(end 14.4526 -46.141894)
		(width 0.1143)
		(layer "In7.Cu")
		(net "P2E_CPU_NGFF_RX_DP12")
	)
	(segment
		(start 42.300906 -39.4208)
		(end 44.37634 -41.496234)
		(width 0.1143)
		(layer "In7.Cu")
		(net "P2E_CPU_NGFF_RX_DP12")
	)
	(segment
		(start 28.2702 -39.5097)
		(end 28.6893 -39.5097)
		(width 0.1143)
		(layer "In7.Cu")
		(net "P2E_CPU_NGFF_RX_DP12")
	)
	(segment
		(start 61.6966 -47.7012)
		(end 62.1411 -48.1457)
		(width 0.1143)
		(layer "In7.Cu")
		(net "P2E_CPU_NGFF_RX_DP12")
	)
	(segment
		(start 91.610688 -50.494184)
		(end 91.610688 -49.954688)
		(width 0.1016)
		(layer "In7.Cu")
		(net "P2E_CPU_NGFF_RX_DP12")
	)
	(segment
		(start 51.140106 -43.9674)
		(end 51.368706 -44.196)
		(width 0.1143)
		(layer "In7.Cu")
		(net "P2E_CPU_NGFF_RX_DP12")
	)
	(segment
		(start 51.368706 -44.196)
		(end 56.663844 -44.196)
		(width 0.1143)
		(layer "In7.Cu")
		(net "P2E_CPU_NGFF_RX_DP12")
	)
	(segment
		(start 91.2368 -51.731672)
		(end 91.2368 -50.868072)
		(width 0.1016)
		(layer "In7.Cu")
		(net "P2E_CPU_NGFF_RX_DP12")
	)
	(segment
		(start 14.15288 -46.83252)
		(end 14.4526 -46.5328)
		(width 0.1143)
		(layer "In7.Cu")
		(net "P2E_CPU_NGFF_RX_DP12")
	)
	(segment
		(start 91.610688 -49.954688)
		(end 91.390978 -49.734978)
		(width 0.1016)
		(layer "In7.Cu")
		(net "P2E_CPU_NGFF_RX_DP12")
	)
	(segment
		(start 91.390978 -49.734978)
		(end 91.390978 -48.8061)
		(width 0.1016)
		(layer "In7.Cu")
		(net "P2E_CPU_NGFF_RX_DP12")
	)
	(segment
		(start 27.0764 -37.8714)
		(end 27.594306 -37.8714)
		(width 0.1143)
		(layer "In7.Cu")
		(net "P2E_CPU_NGFF_RX_DP12")
	)
	(segment
		(start 24.26462 -42.578274)
		(end 24.26462 -40.68318)
		(width 0.1143)
		(layer "In7.Cu")
		(net "P2E_CPU_NGFF_RX_DP12")
	)
	(segment
		(start 28.6893 -39.5097)
		(end 29.7307 -38.4683)
		(width 0.1143)
		(layer "In7.Cu")
		(net "P2E_CPU_NGFF_RX_DP12")
	)
	(segment
		(start 44.37634 -41.496234)
		(end 46.15434 -41.496234)
		(width 0.1143)
		(layer "In7.Cu")
		(net "P2E_CPU_NGFF_RX_DP12")
	)
	(segment
		(start 60.169044 -47.7012)
		(end 61.6966 -47.7012)
		(width 0.1143)
		(layer "In7.Cu")
		(net "P2E_CPU_NGFF_RX_DP12")
	)
	(segment
		(start 79.6798 -50.8762)
		(end 80.01 -50.546)
		(width 0.1143)
		(layer "In7.Cu")
		(net "P2E_CPU_NGFF_RX_DP12")
	)
	(segment
		(start 86.453472 -51.3842)
		(end 86.682072 -51.1556)
		(width 0.1016)
		(layer "In7.Cu")
		(net "P2E_CPU_NGFF_RX_DP12")
	)
	(segment
		(start 16.690594 -43.9039)
		(end 22.938994 -43.9039)
		(width 0.1143)
		(layer "In7.Cu")
		(net "P2E_CPU_NGFF_RX_DP12")
	)
	(segment
		(start 63.610236 -48.1457)
		(end 64.666876 -49.20234)
		(width 0.1143)
		(layer "In7.Cu")
		(net "P2E_CPU_NGFF_RX_DP12")
	)
	(segment
		(start 46.15434 -41.496234)
		(end 48.625506 -43.9674)
		(width 0.1143)
		(layer "In7.Cu")
		(net "P2E_CPU_NGFF_RX_DP12")
	)
	(segment
		(start 27.594306 -37.8714)
		(end 27.9654 -38.242494)
		(width 0.1143)
		(layer "In7.Cu")
		(net "P2E_CPU_NGFF_RX_DP12")
	)
	(segment
		(start 84.818728 -51.3842)
		(end 86.453472 -51.3842)
		(width 0.1016)
		(layer "In7.Cu")
		(net "P2E_CPU_NGFF_RX_DP12")
	)
	(segment
		(start 27.9654 -38.242494)
		(end 27.9654 -39.2049)
		(width 0.1143)
		(layer "In7.Cu")
		(net "P2E_CPU_NGFF_RX_DP12")
	)
	(segment
		(start 82.465672 -50.81905)
		(end 83.07705 -50.81905)
		(width 0.1016)
		(layer "In7.Cu")
		(net "P2E_CPU_NGFF_RX_DP12")
	)
	(segment
		(start 39.062406 -38.4683)
		(end 40.014906 -39.4208)
		(width 0.1143)
		(layer "In7.Cu")
		(net "P2E_CPU_NGFF_RX_DP12")
	)
	(segment
		(start 91.390978 -48.8061)
		(end 91.759278 -48.4378)
		(width 0.1016)
		(layer "In7.Cu")
		(net "P2E_CPU_NGFF_RX_DP12")
	)
	(segment
		(start 78.6892 -50.165)
		(end 79.4004 -50.8762)
		(width 0.1143)
		(layer "In7.Cu")
		(net "P2E_CPU_NGFF_RX_DP12")
	)
	(segment
		(start 86.682072 -51.1556)
		(end 89.924128 -51.1556)
		(width 0.1016)
		(layer "In7.Cu")
		(net "P2E_CPU_NGFF_RX_DP12")
	)
	(segment
		(start 91.101672 -51.8668)
		(end 91.2368 -51.731672)
		(width 0.1016)
		(layer "In7.Cu")
		(net "P2E_CPU_NGFF_RX_DP12")
	)
	(segment
		(start 83.07705 -50.81905)
		(end 83.4136 -51.1556)
		(width 0.1016)
		(layer "In7.Cu")
		(net "P2E_CPU_NGFF_RX_DP12")
	)
	(segment
		(start 81.28 -50.8762)
		(end 82.0928 -50.8762)
		(width 0.1143)
		(layer "In7.Cu")
		(net "P2E_CPU_NGFF_RX_DP12")
	)
	(segment
		(start 40.014906 -39.4208)
		(end 42.300906 -39.4208)
		(width 0.1143)
		(layer "In7.Cu")
		(net "P2E_CPU_NGFF_RX_DP12")
	)
	(segment
		(start 84.590128 -51.1556)
		(end 84.818728 -51.3842)
		(width 0.1016)
		(layer "In7.Cu")
		(net "P2E_CPU_NGFF_RX_DP12")
	)
	(segment
		(start 14.4526 -46.141894)
		(end 16.690594 -43.9039)
		(width 0.1143)
		(layer "In7.Cu")
		(net "P2E_CPU_NGFF_RX_DP12")
	)
	(segment
		(start 64.666876 -49.20234)
		(end 75.94854 -49.20234)
		(width 0.1143)
		(layer "In7.Cu")
		(net "P2E_CPU_NGFF_RX_DP12")
	)
	(segment
		(start 56.663844 -44.196)
		(end 60.169044 -47.7012)
		(width 0.1143)
		(layer "In7.Cu")
		(net "P2E_CPU_NGFF_RX_DP12")
	)
	(segment
		(start 22.938994 -43.9039)
		(end 24.26462 -42.578274)
		(width 0.1143)
		(layer "In7.Cu")
		(net "P2E_CPU_NGFF_RX_DP12")
	)
	(segment
		(start 79.4004 -50.8762)
		(end 79.6798 -50.8762)
		(width 0.1143)
		(layer "In7.Cu")
		(net "P2E_CPU_NGFF_RX_DP12")
	)
	(segment
		(start 8.45185 -51.28895)
		(end 8.128 -51.6128)
		(width 0.1397)
		(layer "F.Cu")
		(net "P2E_CPU_NGFF_TX_DN12")
	)
	(segment
		(start 10.72515 -51.28895)
		(end 8.45185 -51.28895)
		(width 0.1397)
		(layer "F.Cu")
		(net "P2E_CPU_NGFF_TX_DN12")
	)
	(segment
		(start 10.9728 -51.7398)
		(end 10.9728 -51.5366)
		(width 0.1397)
		(layer "F.Cu")
		(net "P2E_CPU_NGFF_TX_DN12")
	)
	(segment
		(start 10.9728 -51.5366)
		(end 10.72515 -51.28895)
		(width 0.1397)
		(layer "F.Cu")
		(net "P2E_CPU_NGFF_TX_DN12")
	)
	(via
		(at 8.128 -51.6128)
		(size 0.508)
		(drill 0.254)
		(layers "F.Cu" "B.Cu")
		(net "P2E_CPU_NGFF_TX_DN12")
	)
	(segment
		(start 7.2009 -51.4731)
		(end 7.2009 -55.94604)
		(width 0.1397)
		(layer "B.Cu")
		(net "P2E_CPU_NGFF_TX_DN12")
	)
	(segment
		(start 6.288024 -56.449976)
		(end 5.575046 -56.449976)
		(width 0.1397)
		(layer "B.Cu")
		(net "P2E_CPU_NGFF_TX_DN12")
	)
	(segment
		(start 7.2009 -55.94604)
		(end 6.775704 -56.371236)
		(width 0.1397)
		(layer "B.Cu")
		(net "P2E_CPU_NGFF_TX_DN12")
	)
	(segment
		(start 8.128 -51.6128)
		(end 7.8232 -51.308)
		(width 0.1397)
		(layer "B.Cu")
		(net "P2E_CPU_NGFF_TX_DN12")
	)
	(segment
		(start 7.8232 -51.308)
		(end 7.366 -51.308)
		(width 0.1397)
		(layer "B.Cu")
		(net "P2E_CPU_NGFF_TX_DN12")
	)
	(segment
		(start 6.775704 -56.371236)
		(end 6.366764 -56.371236)
		(width 0.1397)
		(layer "B.Cu")
		(net "P2E_CPU_NGFF_TX_DN12")
	)
	(segment
		(start 7.366 -51.308)
		(end 7.2009 -51.4731)
		(width 0.1397)
		(layer "B.Cu")
		(net "P2E_CPU_NGFF_TX_DN12")
	)
	(segment
		(start 6.366764 -56.371236)
		(end 6.288024 -56.449976)
		(width 0.1397)
		(layer "B.Cu")
		(net "P2E_CPU_NGFF_TX_DN12")
	)
	(segment
		(start 10.9728 -50.4952)
		(end 10.9728 -50.6476)
		(width 0.1397)
		(layer "F.Cu")
		(net "P2E_CPU_NGFF_TX_DP12")
	)
	(segment
		(start 10.9728 -50.6476)
		(end 10.67435 -50.94605)
		(width 0.1397)
		(layer "F.Cu")
		(net "P2E_CPU_NGFF_TX_DP12")
	)
	(segment
		(start 8.45185 -50.94605)
		(end 8.128 -50.6222)
		(width 0.1397)
		(layer "F.Cu")
		(net "P2E_CPU_NGFF_TX_DP12")
	)
	(segment
		(start 10.67435 -50.94605)
		(end 8.45185 -50.94605)
		(width 0.1397)
		(layer "F.Cu")
		(net "P2E_CPU_NGFF_TX_DP12")
	)
	(via
		(at 8.128 -50.6222)
		(size 0.508)
		(drill 0.254)
		(layers "F.Cu" "B.Cu")
		(net "P2E_CPU_NGFF_TX_DP12")
	)
	(segment
		(start 6.371336 -56.028336)
		(end 6.29285 -55.94985)
		(width 0.1397)
		(layer "B.Cu")
		(net "P2E_CPU_NGFF_TX_DP12")
	)
	(segment
		(start 6.858 -51.33086)
		(end 6.858 -55.8038)
		(width 0.1397)
		(layer "B.Cu")
		(net "P2E_CPU_NGFF_TX_DP12")
	)
	(segment
		(start 7.7851 -50.9651)
		(end 7.22376 -50.9651)
		(width 0.1397)
		(layer "B.Cu")
		(net "P2E_CPU_NGFF_TX_DP12")
	)
	(segment
		(start 8.128 -50.6222)
		(end 7.7851 -50.9651)
		(width 0.1397)
		(layer "B.Cu")
		(net "P2E_CPU_NGFF_TX_DP12")
	)
	(segment
		(start 6.633464 -56.028336)
		(end 6.371336 -56.028336)
		(width 0.1397)
		(layer "B.Cu")
		(net "P2E_CPU_NGFF_TX_DP12")
	)
	(segment
		(start 6.858 -55.8038)
		(end 6.633464 -56.028336)
		(width 0.1397)
		(layer "B.Cu")
		(net "P2E_CPU_NGFF_TX_DP12")
	)
	(segment
		(start 7.22376 -50.9651)
		(end 6.858 -51.33086)
		(width 0.1397)
		(layer "B.Cu")
		(net "P2E_CPU_NGFF_TX_DP12")
	)
	(segment
		(start 6.29285 -55.94985)
		(end 5.575046 -55.94985)
		(width 0.1397)
		(layer "B.Cu")
		(net "P2E_CPU_NGFF_TX_DP12")
	)
	(segment
		(start 9.6266 -62.738)
		(end 8.9662 -62.738)
		(width 0.1397)
		(layer "F.Cu")
		(net "P2E_CPU_NGFF_C_TX_DP15")
	)
	(segment
		(start 96.647 -59.12866)
		(end 96.647 -62.513718)
		(width 0.1397)
		(layer "F.Cu")
		(net "P2E_CPU_NGFF_C_TX_DP15")
	)
	(segment
		(start 96.647 -62.513718)
		(end 94.51086 -64.649858)
		(width 0.1397)
		(layer "F.Cu")
		(net "P2E_CPU_NGFF_C_TX_DP15")
	)
	(segment
		(start 94.51086 -64.649858)
		(end 86.282022 -64.649858)
		(width 0.1397)
		(layer "F.Cu")
		(net "P2E_CPU_NGFF_C_TX_DP15")
	)
	(segment
		(start 93.030548 -51.839114)
		(end 93.2053 -52.013866)
		(width 0.1016)
		(layer "F.Cu")
		(net "P2E_CPU_NGFF_C_TX_DP15")
	)
	(segment
		(start 95.311214 -57.693814)
		(end 95.311214 -57.792874)
		(width 0.1016)
		(layer "F.Cu")
		(net "P2E_CPU_NGFF_C_TX_DP15")
	)
	(segment
		(start 82.922364 -61.2902)
		(end 81.1022 -61.2902)
		(width 0.1397)
		(layer "F.Cu")
		(net "P2E_CPU_NGFF_C_TX_DP15")
	)
	(segment
		(start 95.0976 -57.4802)
		(end 95.311214 -57.693814)
		(width 0.1016)
		(layer "F.Cu")
		(net "P2E_CPU_NGFF_C_TX_DP15")
	)
	(segment
		(start 80.8228 -60.6044)
		(end 81.0514 -60.3758)
		(width 0.1397)
		(layer "F.Cu")
		(net "P2E_CPU_NGFF_C_TX_DP15")
	)
	(segment
		(start 95.311214 -57.792874)
		(end 96.647 -59.12866)
		(width 0.1397)
		(layer "F.Cu")
		(net "P2E_CPU_NGFF_C_TX_DP15")
	)
	(segment
		(start 81.1022 -61.2902)
		(end 80.8228 -61.0108)
		(width 0.1397)
		(layer "F.Cu")
		(net "P2E_CPU_NGFF_C_TX_DP15")
	)
	(segment
		(start 93.2053 -52.013866)
		(end 93.2053 -55.951628)
		(width 0.1016)
		(layer "F.Cu")
		(net "P2E_CPU_NGFF_C_TX_DP15")
	)
	(segment
		(start 86.282022 -64.649858)
		(end 82.922364 -61.2902)
		(width 0.1397)
		(layer "F.Cu")
		(net "P2E_CPU_NGFF_C_TX_DP15")
	)
	(segment
		(start 93.2053 -55.951628)
		(end 94.733872 -57.4802)
		(width 0.1016)
		(layer "F.Cu")
		(net "P2E_CPU_NGFF_C_TX_DP15")
	)
	(segment
		(start 94.733872 -57.4802)
		(end 95.0976 -57.4802)
		(width 0.1016)
		(layer "F.Cu")
		(net "P2E_CPU_NGFF_C_TX_DP15")
	)
	(segment
		(start 80.8228 -61.0108)
		(end 80.8228 -60.6044)
		(width 0.1397)
		(layer "F.Cu")
		(net "P2E_CPU_NGFF_C_TX_DP15")
	)
	(via
		(at 9.6266 -62.738)
		(size 0.508)
		(drill 0.254)
		(layers "F.Cu" "B.Cu")
		(net "P2E_CPU_NGFF_C_TX_DP15")
	)
	(via
		(at 81.0514 -60.3758)
		(size 0.4318)
		(drill 0.2032)
		(layers "F.Cu" "B.Cu")
		(net "P2E_CPU_NGFF_C_TX_DP15")
	)
	(segment
		(start 34.077402 -53.9369)
		(end 39.047928 -53.9369)
		(width 0.1143)
		(layer "In7.Cu")
		(net "P2E_CPU_NGFF_C_TX_DP15")
	)
	(segment
		(start 65.668906 -56.89219)
		(end 66.011806 -56.89219)
		(width 0.1143)
		(layer "In7.Cu")
		(net "P2E_CPU_NGFF_C_TX_DP15")
	)
	(segment
		(start 31.122874 -50.68062)
		(end 31.36519 -50.922936)
		(width 0.1143)
		(layer "In7.Cu")
		(net "P2E_CPU_NGFF_C_TX_DP15")
	)
	(segment
		(start 68.236846 -56.89219)
		(end 68.450206 -57.10555)
		(width 0.1143)
		(layer "In7.Cu")
		(net "P2E_CPU_NGFF_C_TX_DP15")
	)
	(segment
		(start 16.991076 -55.388002)
		(end 17.233646 -55.145432)
		(width 0.1143)
		(layer "In7.Cu")
		(net "P2E_CPU_NGFF_C_TX_DP15")
	)
	(segment
		(start 30.821122 -50.68062)
		(end 31.122874 -50.68062)
		(width 0.1143)
		(layer "In7.Cu")
		(net "P2E_CPU_NGFF_C_TX_DP15")
	)
	(segment
		(start 44.704 -53.9369)
		(end 57.053226 -53.9369)
		(width 0.1143)
		(layer "In7.Cu")
		(net "P2E_CPU_NGFF_C_TX_DP15")
	)
	(segment
		(start 57.053226 -53.9369)
		(end 60.221876 -57.10555)
		(width 0.1143)
		(layer "In7.Cu")
		(net "P2E_CPU_NGFF_C_TX_DP15")
	)
	(segment
		(start 63.346076 -56.89219)
		(end 63.559436 -57.10555)
		(width 0.1143)
		(layer "In7.Cu")
		(net "P2E_CPU_NGFF_C_TX_DP15")
	)
	(segment
		(start 77.420216 -59.1566)
		(end 80.2894 -59.1566)
		(width 0.1143)
		(layer "In7.Cu")
		(net "P2E_CPU_NGFF_C_TX_DP15")
	)
	(segment
		(start 15.4178 -58.1406)
		(end 15.4178 -56.961278)
		(width 0.1143)
		(layer "In7.Cu")
		(net "P2E_CPU_NGFF_C_TX_DP15")
	)
	(segment
		(start 80.84312 -60.16752)
		(end 81.0514 -60.3758)
		(width 0.1143)
		(layer "In7.Cu")
		(net "P2E_CPU_NGFF_C_TX_DP15")
	)
	(segment
		(start 16.447008 -55.93207)
		(end 16.447008 -55.630318)
		(width 0.1143)
		(layer "In7.Cu")
		(net "P2E_CPU_NGFF_C_TX_DP15")
	)
	(segment
		(start 27.27706 -50.43805)
		(end 30.578552 -50.43805)
		(width 0.1143)
		(layer "In7.Cu")
		(net "P2E_CPU_NGFF_C_TX_DP15")
	)
	(segment
		(start 61.677296 -57.10555)
		(end 61.890656 -56.89219)
		(width 0.1143)
		(layer "In7.Cu")
		(net "P2E_CPU_NGFF_C_TX_DP15")
	)
	(segment
		(start 68.450206 -57.10555)
		(end 69.74205 -57.10555)
		(width 0.1143)
		(layer "In7.Cu")
		(net "P2E_CPU_NGFF_C_TX_DP15")
	)
	(segment
		(start 61.890656 -56.89219)
		(end 62.233556 -56.89219)
		(width 0.1143)
		(layer "In7.Cu")
		(net "P2E_CPU_NGFF_C_TX_DP15")
	)
	(segment
		(start 60.221876 -57.10555)
		(end 61.677296 -57.10555)
		(width 0.1143)
		(layer "In7.Cu")
		(net "P2E_CPU_NGFF_C_TX_DP15")
	)
	(segment
		(start 17.233646 -54.84368)
		(end 17.475962 -54.601364)
		(width 0.1143)
		(layer "In7.Cu")
		(net "P2E_CPU_NGFF_C_TX_DP15")
	)
	(segment
		(start 63.559436 -57.10555)
		(end 65.455546 -57.10555)
		(width 0.1143)
		(layer "In7.Cu")
		(net "P2E_CPU_NGFF_C_TX_DP15")
	)
	(segment
		(start 63.003176 -56.89219)
		(end 63.346076 -56.89219)
		(width 0.1143)
		(layer "In7.Cu")
		(net "P2E_CPU_NGFF_C_TX_DP15")
	)
	(segment
		(start 25.77465 -52.66055)
		(end 26.543 -51.8922)
		(width 0.1143)
		(layer "In7.Cu")
		(net "P2E_CPU_NGFF_C_TX_DP15")
	)
	(segment
		(start 80.84312 -59.71032)
		(end 80.84312 -60.16752)
		(width 0.1143)
		(layer "In7.Cu")
		(net "P2E_CPU_NGFF_C_TX_DP15")
	)
	(segment
		(start 26.543 -51.8922)
		(end 26.543 -51.17211)
		(width 0.1143)
		(layer "In7.Cu")
		(net "P2E_CPU_NGFF_C_TX_DP15")
	)
	(segment
		(start 66.225166 -57.10555)
		(end 66.568066 -57.10555)
		(width 0.1143)
		(layer "In7.Cu")
		(net "P2E_CPU_NGFF_C_TX_DP15")
	)
	(segment
		(start 67.680586 -57.10555)
		(end 67.893946 -56.89219)
		(width 0.1143)
		(layer "In7.Cu")
		(net "P2E_CPU_NGFF_C_TX_DP15")
	)
	(segment
		(start 66.781426 -56.89219)
		(end 67.124326 -56.89219)
		(width 0.1143)
		(layer "In7.Cu")
		(net "P2E_CPU_NGFF_C_TX_DP15")
	)
	(segment
		(start 66.011806 -56.89219)
		(end 66.225166 -57.10555)
		(width 0.1143)
		(layer "In7.Cu")
		(net "P2E_CPU_NGFF_C_TX_DP15")
	)
	(segment
		(start 66.568066 -57.10555)
		(end 66.781426 -56.89219)
		(width 0.1143)
		(layer "In7.Cu")
		(net "P2E_CPU_NGFF_C_TX_DP15")
	)
	(segment
		(start 80.2894 -59.1566)
		(end 80.84312 -59.71032)
		(width 0.1143)
		(layer "In7.Cu")
		(net "P2E_CPU_NGFF_C_TX_DP15")
	)
	(segment
		(start 17.475962 -54.601364)
		(end 17.777714 -54.601364)
		(width 0.1143)
		(layer "In7.Cu")
		(net "P2E_CPU_NGFF_C_TX_DP15")
	)
	(segment
		(start 17.777714 -54.601364)
		(end 19.718528 -52.66055)
		(width 0.1143)
		(layer "In7.Cu")
		(net "P2E_CPU_NGFF_C_TX_DP15")
	)
	(segment
		(start 62.233556 -56.89219)
		(end 62.446916 -57.10555)
		(width 0.1143)
		(layer "In7.Cu")
		(net "P2E_CPU_NGFF_C_TX_DP15")
	)
	(segment
		(start 15.4178 -56.961278)
		(end 16.447008 -55.93207)
		(width 0.1143)
		(layer "In7.Cu")
		(net "P2E_CPU_NGFF_C_TX_DP15")
	)
	(segment
		(start 39.047928 -53.9369)
		(end 39.708328 -53.2765)
		(width 0.1143)
		(layer "In7.Cu")
		(net "P2E_CPU_NGFF_C_TX_DP15")
	)
	(segment
		(start 31.36519 -50.922936)
		(end 31.36519 -51.224688)
		(width 0.1143)
		(layer "In7.Cu")
		(net "P2E_CPU_NGFF_C_TX_DP15")
	)
	(segment
		(start 74.877422 -55.4101)
		(end 76.05268 -56.585358)
		(width 0.1143)
		(layer "In7.Cu")
		(net "P2E_CPU_NGFF_C_TX_DP15")
	)
	(segment
		(start 76.05268 -57.789064)
		(end 77.420216 -59.1566)
		(width 0.1143)
		(layer "In7.Cu")
		(net "P2E_CPU_NGFF_C_TX_DP15")
	)
	(segment
		(start 62.789816 -57.10555)
		(end 63.003176 -56.89219)
		(width 0.1143)
		(layer "In7.Cu")
		(net "P2E_CPU_NGFF_C_TX_DP15")
	)
	(segment
		(start 39.708328 -53.2765)
		(end 44.0436 -53.2765)
		(width 0.1143)
		(layer "In7.Cu")
		(net "P2E_CPU_NGFF_C_TX_DP15")
	)
	(segment
		(start 69.74205 -57.10555)
		(end 70.905116 -55.942484)
		(width 0.1143)
		(layer "In7.Cu")
		(net "P2E_CPU_NGFF_C_TX_DP15")
	)
	(segment
		(start 70.905116 -55.942484)
		(end 70.905116 -55.94223)
		(width 0.1143)
		(layer "In7.Cu")
		(net "P2E_CPU_NGFF_C_TX_DP15")
	)
	(segment
		(start 71.437246 -55.4101)
		(end 74.877422 -55.4101)
		(width 0.1143)
		(layer "In7.Cu")
		(net "P2E_CPU_NGFF_C_TX_DP15")
	)
	(segment
		(start 67.124326 -56.89219)
		(end 67.337686 -57.10555)
		(width 0.1143)
		(layer "In7.Cu")
		(net "P2E_CPU_NGFF_C_TX_DP15")
	)
	(segment
		(start 16.689324 -55.388002)
		(end 16.991076 -55.388002)
		(width 0.1143)
		(layer "In7.Cu")
		(net "P2E_CPU_NGFF_C_TX_DP15")
	)
	(segment
		(start 9.9441 -63.0555)
		(end 10.5029 -63.0555)
		(width 0.1143)
		(layer "In7.Cu")
		(net "P2E_CPU_NGFF_C_TX_DP15")
	)
	(segment
		(start 31.36519 -51.224688)
		(end 34.077402 -53.9369)
		(width 0.1143)
		(layer "In7.Cu")
		(net "P2E_CPU_NGFF_C_TX_DP15")
	)
	(segment
		(start 44.0436 -53.2765)
		(end 44.704 -53.9369)
		(width 0.1143)
		(layer "In7.Cu")
		(net "P2E_CPU_NGFF_C_TX_DP15")
	)
	(segment
		(start 9.6266 -62.738)
		(end 9.9441 -63.0555)
		(width 0.1143)
		(layer "In7.Cu")
		(net "P2E_CPU_NGFF_C_TX_DP15")
	)
	(segment
		(start 70.905116 -55.94223)
		(end 71.437246 -55.4101)
		(width 0.1143)
		(layer "In7.Cu")
		(net "P2E_CPU_NGFF_C_TX_DP15")
	)
	(segment
		(start 19.718528 -52.66055)
		(end 25.77465 -52.66055)
		(width 0.1143)
		(layer "In7.Cu")
		(net "P2E_CPU_NGFF_C_TX_DP15")
	)
	(segment
		(start 17.233646 -55.145432)
		(end 17.233646 -54.84368)
		(width 0.1143)
		(layer "In7.Cu")
		(net "P2E_CPU_NGFF_C_TX_DP15")
	)
	(segment
		(start 67.893946 -56.89219)
		(end 68.236846 -56.89219)
		(width 0.1143)
		(layer "In7.Cu")
		(net "P2E_CPU_NGFF_C_TX_DP15")
	)
	(segment
		(start 16.447008 -55.630318)
		(end 16.689324 -55.388002)
		(width 0.1143)
		(layer "In7.Cu")
		(net "P2E_CPU_NGFF_C_TX_DP15")
	)
	(segment
		(start 10.5029 -63.0555)
		(end 15.4178 -58.1406)
		(width 0.1143)
		(layer "In7.Cu")
		(net "P2E_CPU_NGFF_C_TX_DP15")
	)
	(segment
		(start 76.05268 -56.585358)
		(end 76.05268 -57.789064)
		(width 0.1143)
		(layer "In7.Cu")
		(net "P2E_CPU_NGFF_C_TX_DP15")
	)
	(segment
		(start 62.446916 -57.10555)
		(end 62.789816 -57.10555)
		(width 0.1143)
		(layer "In7.Cu")
		(net "P2E_CPU_NGFF_C_TX_DP15")
	)
	(segment
		(start 30.578552 -50.43805)
		(end 30.821122 -50.68062)
		(width 0.1143)
		(layer "In7.Cu")
		(net "P2E_CPU_NGFF_C_TX_DP15")
	)
	(segment
		(start 67.337686 -57.10555)
		(end 67.680586 -57.10555)
		(width 0.1143)
		(layer "In7.Cu")
		(net "P2E_CPU_NGFF_C_TX_DP15")
	)
	(segment
		(start 65.455546 -57.10555)
		(end 65.668906 -56.89219)
		(width 0.1143)
		(layer "In7.Cu")
		(net "P2E_CPU_NGFF_C_TX_DP15")
	)
	(segment
		(start 26.543 -51.17211)
		(end 27.27706 -50.43805)
		(width 0.1143)
		(layer "In7.Cu")
		(net "P2E_CPU_NGFF_C_TX_DP15")
	)
	(segment
		(start 93.063568 -51.099974)
		(end 93.4085 -51.7906)
		(width 0.1016)
		(layer "F.Cu")
		(net "P2E_CPU_NGFF_C_TX_DN15")
	)
	(segment
		(start 95.54464 -57.54116)
		(end 95.553784 -57.550304)
		(width 0.1016)
		(layer "F.Cu")
		(net "P2E_CPU_NGFF_C_TX_DN15")
	)
	(segment
		(start 80.95996 -61.6331)
		(end 80.4799 -61.15304)
		(width 0.1397)
		(layer "F.Cu")
		(net "P2E_CPU_NGFF_C_TX_DN15")
	)
	(segment
		(start 95.553784 -57.550304)
		(end 96.9899 -58.98642)
		(width 0.1397)
		(layer "F.Cu")
		(net "P2E_CPU_NGFF_C_TX_DN15")
	)
	(segment
		(start 80.4799 -60.5917)
		(end 80.264 -60.3758)
		(width 0.1397)
		(layer "F.Cu")
		(net "P2E_CPU_NGFF_C_TX_DN15")
	)
	(segment
		(start 96.9899 -62.655958)
		(end 94.6531 -64.992758)
		(width 0.1397)
		(layer "F.Cu")
		(net "P2E_CPU_NGFF_C_TX_DN15")
	)
	(segment
		(start 96.9899 -58.98642)
		(end 96.9899 -62.655958)
		(width 0.1397)
		(layer "F.Cu")
		(net "P2E_CPU_NGFF_C_TX_DN15")
	)
	(segment
		(start 86.139782 -64.992758)
		(end 82.780124 -61.6331)
		(width 0.1397)
		(layer "F.Cu")
		(net "P2E_CPU_NGFF_C_TX_DN15")
	)
	(segment
		(start 95.181928 -57.277)
		(end 95.446088 -57.54116)
		(width 0.1016)
		(layer "F.Cu")
		(net "P2E_CPU_NGFF_C_TX_DN15")
	)
	(segment
		(start 94.6531 -64.992758)
		(end 86.139782 -64.992758)
		(width 0.1397)
		(layer "F.Cu")
		(net "P2E_CPU_NGFF_C_TX_DN15")
	)
	(segment
		(start 94.8182 -57.277)
		(end 95.181928 -57.277)
		(width 0.1016)
		(layer "F.Cu")
		(net "P2E_CPU_NGFF_C_TX_DN15")
	)
	(segment
		(start 9.652 -63.627)
		(end 8.9662 -63.627)
		(width 0.1397)
		(layer "F.Cu")
		(net "P2E_CPU_NGFF_C_TX_DN15")
	)
	(segment
		(start 93.4085 -55.8673)
		(end 94.8182 -57.277)
		(width 0.1016)
		(layer "F.Cu")
		(net "P2E_CPU_NGFF_C_TX_DN15")
	)
	(segment
		(start 93.4085 -51.7906)
		(end 93.4085 -55.8673)
		(width 0.1016)
		(layer "F.Cu")
		(net "P2E_CPU_NGFF_C_TX_DN15")
	)
	(segment
		(start 95.446088 -57.54116)
		(end 95.54464 -57.54116)
		(width 0.1016)
		(layer "F.Cu")
		(net "P2E_CPU_NGFF_C_TX_DN15")
	)
	(segment
		(start 82.780124 -61.6331)
		(end 80.95996 -61.6331)
		(width 0.1397)
		(layer "F.Cu")
		(net "P2E_CPU_NGFF_C_TX_DN15")
	)
	(segment
		(start 80.4799 -61.15304)
		(end 80.4799 -60.5917)
		(width 0.1397)
		(layer "F.Cu")
		(net "P2E_CPU_NGFF_C_TX_DN15")
	)
	(via
		(at 80.264 -60.3758)
		(size 0.4318)
		(drill 0.2032)
		(layers "F.Cu" "B.Cu")
		(net "P2E_CPU_NGFF_C_TX_DN15")
	)
	(via
		(at 9.652 -63.627)
		(size 0.508)
		(drill 0.254)
		(layers "F.Cu" "B.Cu")
		(net "P2E_CPU_NGFF_C_TX_DN15")
	)
	(segment
		(start 30.441646 -50.76825)
		(end 33.940496 -54.2671)
		(width 0.1143)
		(layer "In7.Cu")
		(net "P2E_CPU_NGFF_C_TX_DN15")
	)
	(segment
		(start 33.940496 -54.2671)
		(end 39.184834 -54.2671)
		(width 0.1143)
		(layer "In7.Cu")
		(net "P2E_CPU_NGFF_C_TX_DN15")
	)
	(segment
		(start 15.748 -58.277506)
		(end 15.748 -57.098184)
		(width 0.1143)
		(layer "In7.Cu")
		(net "P2E_CPU_NGFF_C_TX_DN15")
	)
	(segment
		(start 44.567094 -54.2671)
		(end 56.91632 -54.2671)
		(width 0.1143)
		(layer "In7.Cu")
		(net "P2E_CPU_NGFF_C_TX_DN15")
	)
	(segment
		(start 60.08497 -57.43575)
		(end 69.878956 -57.43575)
		(width 0.1143)
		(layer "In7.Cu")
		(net "P2E_CPU_NGFF_C_TX_DN15")
	)
	(segment
		(start 43.906694 -53.6067)
		(end 44.567094 -54.2671)
		(width 0.1143)
		(layer "In7.Cu")
		(net "P2E_CPU_NGFF_C_TX_DN15")
	)
	(segment
		(start 9.8933 -63.3857)
		(end 10.639806 -63.3857)
		(width 0.1143)
		(layer "In7.Cu")
		(net "P2E_CPU_NGFF_C_TX_DN15")
	)
	(segment
		(start 39.845234 -53.6067)
		(end 43.906694 -53.6067)
		(width 0.1143)
		(layer "In7.Cu")
		(net "P2E_CPU_NGFF_C_TX_DN15")
	)
	(segment
		(start 75.72248 -56.722264)
		(end 75.72248 -57.92597)
		(width 0.1143)
		(layer "In7.Cu")
		(net "P2E_CPU_NGFF_C_TX_DN15")
	)
	(segment
		(start 56.91632 -54.2671)
		(end 60.08497 -57.43575)
		(width 0.1143)
		(layer "In7.Cu")
		(net "P2E_CPU_NGFF_C_TX_DN15")
	)
	(segment
		(start 25.911556 -52.99075)
		(end 26.8732 -52.029106)
		(width 0.1143)
		(layer "In7.Cu")
		(net "P2E_CPU_NGFF_C_TX_DN15")
	)
	(segment
		(start 39.184834 -54.2671)
		(end 39.845234 -53.6067)
		(width 0.1143)
		(layer "In7.Cu")
		(net "P2E_CPU_NGFF_C_TX_DN15")
	)
	(segment
		(start 74.740516 -55.7403)
		(end 75.72248 -56.722264)
		(width 0.1143)
		(layer "In7.Cu")
		(net "P2E_CPU_NGFF_C_TX_DN15")
	)
	(segment
		(start 75.72248 -57.92597)
		(end 77.28331 -59.4868)
		(width 0.1143)
		(layer "In7.Cu")
		(net "P2E_CPU_NGFF_C_TX_DN15")
	)
	(segment
		(start 80.51292 -60.12688)
		(end 80.264 -60.3758)
		(width 0.1143)
		(layer "In7.Cu")
		(net "P2E_CPU_NGFF_C_TX_DN15")
	)
	(segment
		(start 26.8732 -51.309016)
		(end 27.413966 -50.76825)
		(width 0.1143)
		(layer "In7.Cu")
		(net "P2E_CPU_NGFF_C_TX_DN15")
	)
	(segment
		(start 19.855434 -52.99075)
		(end 25.911556 -52.99075)
		(width 0.1143)
		(layer "In7.Cu")
		(net "P2E_CPU_NGFF_C_TX_DN15")
	)
	(segment
		(start 80.51292 -59.847226)
		(end 80.51292 -60.12688)
		(width 0.1143)
		(layer "In7.Cu")
		(net "P2E_CPU_NGFF_C_TX_DN15")
	)
	(segment
		(start 15.748 -57.098184)
		(end 19.855434 -52.99075)
		(width 0.1143)
		(layer "In7.Cu")
		(net "P2E_CPU_NGFF_C_TX_DN15")
	)
	(segment
		(start 27.413966 -50.76825)
		(end 30.441646 -50.76825)
		(width 0.1143)
		(layer "In7.Cu")
		(net "P2E_CPU_NGFF_C_TX_DN15")
	)
	(segment
		(start 80.152494 -59.4868)
		(end 80.51292 -59.847226)
		(width 0.1143)
		(layer "In7.Cu")
		(net "P2E_CPU_NGFF_C_TX_DN15")
	)
	(segment
		(start 77.28331 -59.4868)
		(end 80.152494 -59.4868)
		(width 0.1143)
		(layer "In7.Cu")
		(net "P2E_CPU_NGFF_C_TX_DN15")
	)
	(segment
		(start 10.639806 -63.3857)
		(end 15.748 -58.277506)
		(width 0.1143)
		(layer "In7.Cu")
		(net "P2E_CPU_NGFF_C_TX_DN15")
	)
	(segment
		(start 26.8732 -52.029106)
		(end 26.8732 -51.309016)
		(width 0.1143)
		(layer "In7.Cu")
		(net "P2E_CPU_NGFF_C_TX_DN15")
	)
	(segment
		(start 69.878956 -57.43575)
		(end 71.574406 -55.7403)
		(width 0.1143)
		(layer "In7.Cu")
		(net "P2E_CPU_NGFF_C_TX_DN15")
	)
	(segment
		(start 71.574406 -55.7403)
		(end 74.740516 -55.7403)
		(width 0.1143)
		(layer "In7.Cu")
		(net "P2E_CPU_NGFF_C_TX_DN15")
	)
	(segment
		(start 9.652 -63.627)
		(end 9.8933 -63.3857)
		(width 0.1143)
		(layer "In7.Cu")
		(net "P2E_CPU_NGFF_C_TX_DN15")
	)
	(segment
		(start 92.5068 -51.89728)
		(end 92.5068 -51.498246)
		(width 0.1016)
		(layer "F.Cu")
		(net "P2E_CPU_NGFF_C_TX_DP14")
	)
	(segment
		(start 92.6211 -53.819044)
		(end 92.1512 -53.349144)
		(width 0.1016)
		(layer "F.Cu")
		(net "P2E_CPU_NGFF_C_TX_DP14")
	)
	(segment
		(start 95.7072 -59.190128)
		(end 92.6211 -56.104028)
		(width 0.1016)
		(layer "F.Cu")
		(net "P2E_CPU_NGFF_C_TX_DP14")
	)
	(segment
		(start 92.1512 -53.349144)
		(end 92.1512 -52.25288)
		(width 0.1016)
		(layer "F.Cu")
		(net "P2E_CPU_NGFF_C_TX_DP14")
	)
	(segment
		(start 84.3407 -61.307218)
		(end 86.69274 -63.659258)
		(width 0.1397)
		(layer "F.Cu")
		(net "P2E_CPU_NGFF_C_TX_DP14")
	)
	(segment
		(start 92.1512 -52.25288)
		(end 92.5068 -51.89728)
		(width 0.1016)
		(layer "F.Cu")
		(net "P2E_CPU_NGFF_C_TX_DP14")
	)
	(segment
		(start 94.100142 -63.659258)
		(end 95.63735 -62.12205)
		(width 0.1397)
		(layer "F.Cu")
		(net "P2E_CPU_NGFF_C_TX_DP14")
	)
	(segment
		(start 95.63735 -59.42965)
		(end 95.7072 -59.3598)
		(width 0.1016)
		(layer "F.Cu")
		(net "P2E_CPU_NGFF_C_TX_DP14")
	)
	(segment
		(start 84.110068 -59.349132)
		(end 84.110068 -59.700668)
		(width 0.1397)
		(layer "F.Cu")
		(net "P2E_CPU_NGFF_C_TX_DP14")
	)
	(segment
		(start 95.7072 -59.3598)
		(end 95.7072 -59.190128)
		(width 0.1016)
		(layer "F.Cu")
		(net "P2E_CPU_NGFF_C_TX_DP14")
	)
	(segment
		(start 92.5068 -51.498246)
		(end 92.451428 -51.442874)
		(width 0.1016)
		(layer "F.Cu")
		(net "P2E_CPU_NGFF_C_TX_DP14")
	)
	(segment
		(start 9.6266 -59.182)
		(end 8.9662 -59.182)
		(width 0.1397)
		(layer "F.Cu")
		(net "P2E_CPU_NGFF_C_TX_DP14")
	)
	(segment
		(start 84.110068 -59.700668)
		(end 84.3407 -59.9313)
		(width 0.1397)
		(layer "F.Cu")
		(net "P2E_CPU_NGFF_C_TX_DP14")
	)
	(segment
		(start 95.63735 -59.45505)
		(end 95.63735 -59.42965)
		(width 0.1016)
		(layer "F.Cu")
		(net "P2E_CPU_NGFF_C_TX_DP14")
	)
	(segment
		(start 92.6211 -56.104028)
		(end 92.6211 -53.819044)
		(width 0.1016)
		(layer "F.Cu")
		(net "P2E_CPU_NGFF_C_TX_DP14")
	)
	(segment
		(start 86.69274 -63.659258)
		(end 94.100142 -63.659258)
		(width 0.1397)
		(layer "F.Cu")
		(net "P2E_CPU_NGFF_C_TX_DP14")
	)
	(segment
		(start 84.3407 -59.9313)
		(end 84.3407 -61.307218)
		(width 0.1397)
		(layer "F.Cu")
		(net "P2E_CPU_NGFF_C_TX_DP14")
	)
	(segment
		(start 95.63735 -62.12205)
		(end 95.63735 -59.45505)
		(width 0.1397)
		(layer "F.Cu")
		(net "P2E_CPU_NGFF_C_TX_DP14")
	)
	(via
		(at 9.6266 -59.182)
		(size 0.508)
		(drill 0.254)
		(layers "F.Cu" "B.Cu")
		(net "P2E_CPU_NGFF_C_TX_DP14")
	)
	(via
		(at 84.110068 -59.349132)
		(size 0.4318)
		(drill 0.2032)
		(layers "F.Cu" "B.Cu")
		(net "P2E_CPU_NGFF_C_TX_DP14")
	)
	(segment
		(start 15.4559 -51.435)
		(end 12.7889 -54.102)
		(width 0.1143)
		(layer "In7.Cu")
		(net "P2E_CPU_NGFF_C_TX_DP14")
	)
	(segment
		(start 79.931006 -57.2262)
		(end 76.425806 -53.721)
		(width 0.1143)
		(layer "In7.Cu")
		(net "P2E_CPU_NGFF_C_TX_DP14")
	)
	(segment
		(start 53.578506 -51.2572)
		(end 52.08905 -51.2572)
		(width 0.1143)
		(layer "In7.Cu")
		(net "P2E_CPU_NGFF_C_TX_DP14")
	)
	(segment
		(start 67.83832 -53.36032)
		(end 66.404744 -54.79415)
		(width 0.1143)
		(layer "In7.Cu")
		(net "P2E_CPU_NGFF_C_TX_DP14")
	)
	(segment
		(start 22.294596 -49.2633)
		(end 20.372578 -49.2633)
		(width 0.1143)
		(layer "In7.Cu")
		(net "P2E_CPU_NGFF_C_TX_DP14")
	)
	(segment
		(start 27.549602 -47.471076)
		(end 27.291284 -47.729394)
		(width 0.1143)
		(layer "In7.Cu")
		(net "P2E_CPU_NGFF_C_TX_DP14")
	)
	(segment
		(start 50.76317 -51.04384)
		(end 50.42027 -51.04384)
		(width 0.1143)
		(layer "In7.Cu")
		(net "P2E_CPU_NGFF_C_TX_DP14")
	)
	(segment
		(start 76.425806 -53.721)
		(end 75.692 -53.721)
		(width 0.1143)
		(layer "In7.Cu")
		(net "P2E_CPU_NGFF_C_TX_DP14")
	)
	(segment
		(start 29.739844 -47.257716)
		(end 29.396944 -47.257716)
		(width 0.1143)
		(layer "In7.Cu")
		(net "P2E_CPU_NGFF_C_TX_DP14")
	)
	(segment
		(start 23.620476 -49.04994)
		(end 23.407116 -49.2633)
		(width 0.1143)
		(layer "In7.Cu")
		(net "P2E_CPU_NGFF_C_TX_DP14")
	)
	(segment
		(start 50.97653 -51.2572)
		(end 50.76317 -51.04384)
		(width 0.1143)
		(layer "In7.Cu")
		(net "P2E_CPU_NGFF_C_TX_DP14")
	)
	(segment
		(start 62.287912 -54.79415)
		(end 62.074552 -54.58079)
		(width 0.1143)
		(layer "In7.Cu")
		(net "P2E_CPU_NGFF_C_TX_DP14")
	)
	(segment
		(start 62.074552 -54.58079)
		(end 61.731652 -54.58079)
		(width 0.1143)
		(layer "In7.Cu")
		(net "P2E_CPU_NGFF_C_TX_DP14")
	)
	(segment
		(start 51.87569 -51.04384)
		(end 51.53279 -51.04384)
		(width 0.1143)
		(layer "In7.Cu")
		(net "P2E_CPU_NGFF_C_TX_DP14")
	)
	(segment
		(start 28.071064 -47.471076)
		(end 27.549602 -47.471076)
		(width 0.1143)
		(layer "In7.Cu")
		(net "P2E_CPU_NGFF_C_TX_DP14")
	)
	(segment
		(start 12.7889 -54.102)
		(end 12.7889 -57.2897)
		(width 0.1143)
		(layer "In7.Cu")
		(net "P2E_CPU_NGFF_C_TX_DP14")
	)
	(segment
		(start 28.840684 -47.471076)
		(end 28.627324 -47.257716)
		(width 0.1143)
		(layer "In7.Cu")
		(net "P2E_CPU_NGFF_C_TX_DP14")
	)
	(segment
		(start 26.747216 -48.273462)
		(end 25.757378 -49.2633)
		(width 0.1143)
		(layer "In7.Cu")
		(net "P2E_CPU_NGFF_C_TX_DP14")
	)
	(segment
		(start 23.407116 -49.2633)
		(end 23.064216 -49.2633)
		(width 0.1143)
		(layer "In7.Cu")
		(net "P2E_CPU_NGFF_C_TX_DP14")
	)
	(segment
		(start 60.604908 -54.79415)
		(end 57.842658 -52.0319)
		(width 0.1143)
		(layer "In7.Cu")
		(net "P2E_CPU_NGFF_C_TX_DP14")
	)
	(segment
		(start 83.793838 -59.349132)
		(end 81.670906 -57.2262)
		(width 0.1143)
		(layer "In7.Cu")
		(net "P2E_CPU_NGFF_C_TX_DP14")
	)
	(segment
		(start 28.284424 -47.257716)
		(end 28.071064 -47.471076)
		(width 0.1143)
		(layer "In7.Cu")
		(net "P2E_CPU_NGFF_C_TX_DP14")
	)
	(segment
		(start 30.296104 -47.471076)
		(end 29.953204 -47.471076)
		(width 0.1143)
		(layer "In7.Cu")
		(net "P2E_CPU_NGFF_C_TX_DP14")
	)
	(segment
		(start 20.372578 -49.2633)
		(end 18.200878 -51.435)
		(width 0.1143)
		(layer "In7.Cu")
		(net "P2E_CPU_NGFF_C_TX_DP14")
	)
	(segment
		(start 12.7889 -57.2897)
		(end 10.6172 -59.4614)
		(width 0.1143)
		(layer "In7.Cu")
		(net "P2E_CPU_NGFF_C_TX_DP14")
	)
	(segment
		(start 50.42027 -51.04384)
		(end 50.20691 -51.2572)
		(width 0.1143)
		(layer "In7.Cu")
		(net "P2E_CPU_NGFF_C_TX_DP14")
	)
	(segment
		(start 50.20691 -51.2572)
		(end 48.083216 -51.2572)
		(width 0.1143)
		(layer "In7.Cu")
		(net "P2E_CPU_NGFF_C_TX_DP14")
	)
	(segment
		(start 36.0426 -50.4444)
		(end 34.381948 -50.4444)
		(width 0.1143)
		(layer "In7.Cu")
		(net "P2E_CPU_NGFF_C_TX_DP14")
	)
	(segment
		(start 29.396944 -47.257716)
		(end 29.183584 -47.471076)
		(width 0.1143)
		(layer "In7.Cu")
		(net "P2E_CPU_NGFF_C_TX_DP14")
	)
	(segment
		(start 25.075896 -49.04994)
		(end 24.732996 -49.04994)
		(width 0.1143)
		(layer "In7.Cu")
		(net "P2E_CPU_NGFF_C_TX_DP14")
	)
	(segment
		(start 81.670906 -57.2262)
		(end 79.931006 -57.2262)
		(width 0.1143)
		(layer "In7.Cu")
		(net "P2E_CPU_NGFF_C_TX_DP14")
	)
	(segment
		(start 28.627324 -47.257716)
		(end 28.284424 -47.257716)
		(width 0.1143)
		(layer "In7.Cu")
		(net "P2E_CPU_NGFF_C_TX_DP14")
	)
	(segment
		(start 22.850856 -49.04994)
		(end 22.507956 -49.04994)
		(width 0.1143)
		(layer "In7.Cu")
		(net "P2E_CPU_NGFF_C_TX_DP14")
	)
	(segment
		(start 43.214036 -50.8635)
		(end 42.401236 -50.0507)
		(width 0.1143)
		(layer "In7.Cu")
		(net "P2E_CPU_NGFF_C_TX_DP14")
	)
	(segment
		(start 25.289256 -49.2633)
		(end 25.075896 -49.04994)
		(width 0.1143)
		(layer "In7.Cu")
		(net "P2E_CPU_NGFF_C_TX_DP14")
	)
	(segment
		(start 42.401236 -50.0507)
		(end 36.4363 -50.0507)
		(width 0.1143)
		(layer "In7.Cu")
		(net "P2E_CPU_NGFF_C_TX_DP14")
	)
	(segment
		(start 9.906 -59.4614)
		(end 9.6266 -59.182)
		(width 0.1143)
		(layer "In7.Cu")
		(net "P2E_CPU_NGFF_C_TX_DP14")
	)
	(segment
		(start 51.53279 -51.04384)
		(end 51.31943 -51.2572)
		(width 0.1143)
		(layer "In7.Cu")
		(net "P2E_CPU_NGFF_C_TX_DP14")
	)
	(segment
		(start 52.08905 -51.2572)
		(end 51.87569 -51.04384)
		(width 0.1143)
		(layer "In7.Cu")
		(net "P2E_CPU_NGFF_C_TX_DP14")
	)
	(segment
		(start 24.519636 -49.2633)
		(end 24.176736 -49.2633)
		(width 0.1143)
		(layer "In7.Cu")
		(net "P2E_CPU_NGFF_C_TX_DP14")
	)
	(segment
		(start 51.31943 -51.2572)
		(end 50.97653 -51.2572)
		(width 0.1143)
		(layer "In7.Cu")
		(net "P2E_CPU_NGFF_C_TX_DP14")
	)
	(segment
		(start 57.842658 -52.0319)
		(end 54.353206 -52.0319)
		(width 0.1143)
		(layer "In7.Cu")
		(net "P2E_CPU_NGFF_C_TX_DP14")
	)
	(segment
		(start 61.518292 -54.79415)
		(end 60.604908 -54.79415)
		(width 0.1143)
		(layer "In7.Cu")
		(net "P2E_CPU_NGFF_C_TX_DP14")
	)
	(segment
		(start 75.692 -53.721)
		(end 74.98334 -53.01234)
		(width 0.1143)
		(layer "In7.Cu")
		(net "P2E_CPU_NGFF_C_TX_DP14")
	)
	(segment
		(start 34.381948 -50.4444)
		(end 31.408624 -47.471076)
		(width 0.1143)
		(layer "In7.Cu")
		(net "P2E_CPU_NGFF_C_TX_DP14")
	)
	(segment
		(start 47.689516 -50.8635)
		(end 43.214036 -50.8635)
		(width 0.1143)
		(layer "In7.Cu")
		(net "P2E_CPU_NGFF_C_TX_DP14")
	)
	(segment
		(start 24.176736 -49.2633)
		(end 23.963376 -49.04994)
		(width 0.1143)
		(layer "In7.Cu")
		(net "P2E_CPU_NGFF_C_TX_DP14")
	)
	(segment
		(start 61.731652 -54.58079)
		(end 61.518292 -54.79415)
		(width 0.1143)
		(layer "In7.Cu")
		(net "P2E_CPU_NGFF_C_TX_DP14")
	)
	(segment
		(start 24.732996 -49.04994)
		(end 24.519636 -49.2633)
		(width 0.1143)
		(layer "In7.Cu")
		(net "P2E_CPU_NGFF_C_TX_DP14")
	)
	(segment
		(start 48.083216 -51.2572)
		(end 47.689516 -50.8635)
		(width 0.1143)
		(layer "In7.Cu")
		(net "P2E_CPU_NGFF_C_TX_DP14")
	)
	(segment
		(start 26.747216 -47.971964)
		(end 26.747216 -48.273462)
		(width 0.1143)
		(layer "In7.Cu")
		(net "P2E_CPU_NGFF_C_TX_DP14")
	)
	(segment
		(start 26.989532 -47.729394)
		(end 26.747216 -47.971964)
		(width 0.1143)
		(layer "In7.Cu")
		(net "P2E_CPU_NGFF_C_TX_DP14")
	)
	(segment
		(start 36.4363 -50.0507)
		(end 36.0426 -50.4444)
		(width 0.1143)
		(layer "In7.Cu")
		(net "P2E_CPU_NGFF_C_TX_DP14")
	)
	(segment
		(start 31.065724 -47.471076)
		(end 30.852364 -47.257716)
		(width 0.1143)
		(layer "In7.Cu")
		(net "P2E_CPU_NGFF_C_TX_DP14")
	)
	(segment
		(start 27.291284 -47.729394)
		(end 26.989532 -47.729394)
		(width 0.1143)
		(layer "In7.Cu")
		(net "P2E_CPU_NGFF_C_TX_DP14")
	)
	(segment
		(start 18.200878 -51.435)
		(end 15.4559 -51.435)
		(width 0.1143)
		(layer "In7.Cu")
		(net "P2E_CPU_NGFF_C_TX_DP14")
	)
	(segment
		(start 10.6172 -59.4614)
		(end 9.906 -59.4614)
		(width 0.1143)
		(layer "In7.Cu")
		(net "P2E_CPU_NGFF_C_TX_DP14")
	)
	(segment
		(start 25.757378 -49.2633)
		(end 25.289256 -49.2633)
		(width 0.1143)
		(layer "In7.Cu")
		(net "P2E_CPU_NGFF_C_TX_DP14")
	)
	(segment
		(start 30.852364 -47.257716)
		(end 30.509464 -47.257716)
		(width 0.1143)
		(layer "In7.Cu")
		(net "P2E_CPU_NGFF_C_TX_DP14")
	)
	(segment
		(start 74.98334 -53.01234)
		(end 68.186554 -53.01234)
		(width 0.1143)
		(layer "In7.Cu")
		(net "P2E_CPU_NGFF_C_TX_DP14")
	)
	(segment
		(start 22.507956 -49.04994)
		(end 22.294596 -49.2633)
		(width 0.1143)
		(layer "In7.Cu")
		(net "P2E_CPU_NGFF_C_TX_DP14")
	)
	(segment
		(start 84.110068 -59.349132)
		(end 83.793838 -59.349132)
		(width 0.1143)
		(layer "In7.Cu")
		(net "P2E_CPU_NGFF_C_TX_DP14")
	)
	(segment
		(start 29.953204 -47.471076)
		(end 29.739844 -47.257716)
		(width 0.1143)
		(layer "In7.Cu")
		(net "P2E_CPU_NGFF_C_TX_DP14")
	)
	(segment
		(start 31.408624 -47.471076)
		(end 31.065724 -47.471076)
		(width 0.1143)
		(layer "In7.Cu")
		(net "P2E_CPU_NGFF_C_TX_DP14")
	)
	(segment
		(start 68.186554 -53.01234)
		(end 67.83832 -53.36032)
		(width 0.1143)
		(layer "In7.Cu")
		(net "P2E_CPU_NGFF_C_TX_DP14")
	)
	(segment
		(start 66.404744 -54.79415)
		(end 62.287912 -54.79415)
		(width 0.1143)
		(layer "In7.Cu")
		(net "P2E_CPU_NGFF_C_TX_DP14")
	)
	(segment
		(start 23.963376 -49.04994)
		(end 23.620476 -49.04994)
		(width 0.1143)
		(layer "In7.Cu")
		(net "P2E_CPU_NGFF_C_TX_DP14")
	)
	(segment
		(start 54.353206 -52.0319)
		(end 53.578506 -51.2572)
		(width 0.1143)
		(layer "In7.Cu")
		(net "P2E_CPU_NGFF_C_TX_DP14")
	)
	(segment
		(start 30.509464 -47.257716)
		(end 30.296104 -47.471076)
		(width 0.1143)
		(layer "In7.Cu")
		(net "P2E_CPU_NGFF_C_TX_DP14")
	)
	(segment
		(start 29.183584 -47.471076)
		(end 28.840684 -47.471076)
		(width 0.1143)
		(layer "In7.Cu")
		(net "P2E_CPU_NGFF_C_TX_DP14")
	)
	(segment
		(start 23.064216 -49.2633)
		(end 22.850856 -49.04994)
		(width 0.1143)
		(layer "In7.Cu")
		(net "P2E_CPU_NGFF_C_TX_DP14")
	)
	(segment
		(start 95.98025 -59.44235)
		(end 95.9104 -59.3725)
		(width 0.1016)
		(layer "F.Cu")
		(net "P2E_CPU_NGFF_C_TX_DN14")
	)
	(segment
		(start 94.242382 -64.002158)
		(end 95.98025 -62.26429)
		(width 0.1397)
		(layer "F.Cu")
		(net "P2E_CPU_NGFF_C_TX_DN14")
	)
	(segment
		(start 92.8243 -53.734716)
		(end 92.3544 -53.264816)
		(width 0.1016)
		(layer "F.Cu")
		(net "P2E_CPU_NGFF_C_TX_DN14")
	)
	(segment
		(start 92.3544 -52.337208)
		(end 92.71 -51.981608)
		(width 0.1016)
		(layer "F.Cu")
		(net "P2E_CPU_NGFF_C_TX_DN14")
	)
	(segment
		(start 83.829144 -59.904884)
		(end 83.9978 -60.07354)
		(width 0.1397)
		(layer "F.Cu")
		(net "P2E_CPU_NGFF_C_TX_DN14")
	)
	(segment
		(start 86.5505 -64.002158)
		(end 94.242382 -64.002158)
		(width 0.1397)
		(layer "F.Cu")
		(net "P2E_CPU_NGFF_C_TX_DN14")
	)
	(segment
		(start 95.98025 -62.26429)
		(end 95.98025 -59.45505)
		(width 0.1397)
		(layer "F.Cu")
		(net "P2E_CPU_NGFF_C_TX_DN14")
	)
	(segment
		(start 95.98025 -59.45505)
		(end 95.98025 -59.44235)
		(width 0.1016)
		(layer "F.Cu")
		(net "P2E_CPU_NGFF_C_TX_DN14")
	)
	(segment
		(start 92.71 -51.981608)
		(end 92.71 -51.615594)
		(width 0.1016)
		(layer "F.Cu")
		(net "P2E_CPU_NGFF_C_TX_DN14")
	)
	(segment
		(start 83.9978 -60.07354)
		(end 83.9978 -61.449458)
		(width 0.1397)
		(layer "F.Cu")
		(net "P2E_CPU_NGFF_C_TX_DN14")
	)
	(segment
		(start 95.9104 -59.1058)
		(end 92.8243 -56.0197)
		(width 0.1016)
		(layer "F.Cu")
		(net "P2E_CPU_NGFF_C_TX_DN14")
	)
	(segment
		(start 83.55203 -59.904884)
		(end 83.829144 -59.904884)
		(width 0.1397)
		(layer "F.Cu")
		(net "P2E_CPU_NGFF_C_TX_DN14")
	)
	(segment
		(start 92.8243 -56.0197)
		(end 92.8243 -53.734716)
		(width 0.1016)
		(layer "F.Cu")
		(net "P2E_CPU_NGFF_C_TX_DN14")
	)
	(segment
		(start 9.652 -60.071)
		(end 8.9662 -60.071)
		(width 0.1397)
		(layer "F.Cu")
		(net "P2E_CPU_NGFF_C_TX_DN14")
	)
	(segment
		(start 92.71 -51.615594)
		(end 92.756228 -51.569366)
		(width 0.1016)
		(layer "F.Cu")
		(net "P2E_CPU_NGFF_C_TX_DN14")
	)
	(segment
		(start 92.756228 -51.569366)
		(end 92.756228 -51.29403)
		(width 0.1016)
		(layer "F.Cu")
		(net "P2E_CPU_NGFF_C_TX_DN14")
	)
	(segment
		(start 92.756228 -51.29403)
		(end 92.461588 -50.274474)
		(width 0.1016)
		(layer "F.Cu")
		(net "P2E_CPU_NGFF_C_TX_DN14")
	)
	(segment
		(start 95.9104 -59.3725)
		(end 95.9104 -59.1058)
		(width 0.1016)
		(layer "F.Cu")
		(net "P2E_CPU_NGFF_C_TX_DN14")
	)
	(segment
		(start 92.3544 -53.264816)
		(end 92.3544 -52.337208)
		(width 0.1016)
		(layer "F.Cu")
		(net "P2E_CPU_NGFF_C_TX_DN14")
	)
	(segment
		(start 83.9978 -61.449458)
		(end 86.5505 -64.002158)
		(width 0.1397)
		(layer "F.Cu")
		(net "P2E_CPU_NGFF_C_TX_DN14")
	)
	(via
		(at 83.55203 -59.904884)
		(size 0.4318)
		(drill 0.2032)
		(layers "F.Cu" "B.Cu")
		(net "P2E_CPU_NGFF_C_TX_DN14")
	)
	(via
		(at 9.652 -60.071)
		(size 0.508)
		(drill 0.254)
		(layers "F.Cu" "B.Cu")
		(net "P2E_CPU_NGFF_C_TX_DN14")
	)
	(segment
		(start 13.1191 -54.238906)
		(end 13.1191 -57.426606)
		(width 0.1143)
		(layer "In7.Cu")
		(net "P2E_CPU_NGFF_C_TX_DN14")
	)
	(segment
		(start 75.555094 -54.0512)
		(end 74.846434 -53.34254)
		(width 0.1143)
		(layer "In7.Cu")
		(net "P2E_CPU_NGFF_C_TX_DN14")
	)
	(segment
		(start 27.686508 -47.801276)
		(end 25.894284 -49.5935)
		(width 0.1143)
		(layer "In7.Cu")
		(net "P2E_CPU_NGFF_C_TX_DN14")
	)
	(segment
		(start 18.337784 -51.7652)
		(end 15.592806 -51.7652)
		(width 0.1143)
		(layer "In7.Cu")
		(net "P2E_CPU_NGFF_C_TX_DN14")
	)
	(segment
		(start 53.4416 -51.5874)
		(end 47.94631 -51.5874)
		(width 0.1143)
		(layer "In7.Cu")
		(net "P2E_CPU_NGFF_C_TX_DN14")
	)
	(segment
		(start 42.26433 -50.3809)
		(end 36.573206 -50.3809)
		(width 0.1143)
		(layer "In7.Cu")
		(net "P2E_CPU_NGFF_C_TX_DN14")
	)
	(segment
		(start 66.54165 -55.12435)
		(end 60.468002 -55.12435)
		(width 0.1143)
		(layer "In7.Cu")
		(net "P2E_CPU_NGFF_C_TX_DN14")
	)
	(segment
		(start 79.7941 -57.5564)
		(end 76.2889 -54.0512)
		(width 0.1143)
		(layer "In7.Cu")
		(net "P2E_CPU_NGFF_C_TX_DN14")
	)
	(segment
		(start 76.2889 -54.0512)
		(end 75.555094 -54.0512)
		(width 0.1143)
		(layer "In7.Cu")
		(net "P2E_CPU_NGFF_C_TX_DN14")
	)
	(segment
		(start 36.179506 -50.7746)
		(end 34.245042 -50.7746)
		(width 0.1143)
		(layer "In7.Cu")
		(net "P2E_CPU_NGFF_C_TX_DN14")
	)
	(segment
		(start 31.271718 -47.801276)
		(end 27.686508 -47.801276)
		(width 0.1143)
		(layer "In7.Cu")
		(net "P2E_CPU_NGFF_C_TX_DN14")
	)
	(segment
		(start 20.509484 -49.5935)
		(end 18.337784 -51.7652)
		(width 0.1143)
		(layer "In7.Cu")
		(net "P2E_CPU_NGFF_C_TX_DN14")
	)
	(segment
		(start 34.245042 -50.7746)
		(end 31.271718 -47.801276)
		(width 0.1143)
		(layer "In7.Cu")
		(net "P2E_CPU_NGFF_C_TX_DN14")
	)
	(segment
		(start 25.894284 -49.5935)
		(end 20.509484 -49.5935)
		(width 0.1143)
		(layer "In7.Cu")
		(net "P2E_CPU_NGFF_C_TX_DN14")
	)
	(segment
		(start 74.846434 -53.34254)
		(end 68.32346 -53.34254)
		(width 0.1143)
		(layer "In7.Cu")
		(net "P2E_CPU_NGFF_C_TX_DN14")
	)
	(segment
		(start 81.534 -57.5564)
		(end 79.7941 -57.5564)
		(width 0.1143)
		(layer "In7.Cu")
		(net "P2E_CPU_NGFF_C_TX_DN14")
	)
	(segment
		(start 10.754106 -59.7916)
		(end 9.9314 -59.7916)
		(width 0.1143)
		(layer "In7.Cu")
		(net "P2E_CPU_NGFF_C_TX_DN14")
	)
	(segment
		(start 68.32346 -53.34254)
		(end 66.54165 -55.12435)
		(width 0.1143)
		(layer "In7.Cu")
		(net "P2E_CPU_NGFF_C_TX_DN14")
	)
	(segment
		(start 54.2163 -52.3621)
		(end 53.4416 -51.5874)
		(width 0.1143)
		(layer "In7.Cu")
		(net "P2E_CPU_NGFF_C_TX_DN14")
	)
	(segment
		(start 47.55261 -51.1937)
		(end 43.07713 -51.1937)
		(width 0.1143)
		(layer "In7.Cu")
		(net "P2E_CPU_NGFF_C_TX_DN14")
	)
	(segment
		(start 47.94631 -51.5874)
		(end 47.55261 -51.1937)
		(width 0.1143)
		(layer "In7.Cu")
		(net "P2E_CPU_NGFF_C_TX_DN14")
	)
	(segment
		(start 15.592806 -51.7652)
		(end 13.1191 -54.238906)
		(width 0.1143)
		(layer "In7.Cu")
		(net "P2E_CPU_NGFF_C_TX_DN14")
	)
	(segment
		(start 13.1191 -57.426606)
		(end 10.754106 -59.7916)
		(width 0.1143)
		(layer "In7.Cu")
		(net "P2E_CPU_NGFF_C_TX_DN14")
	)
	(segment
		(start 9.9314 -59.7916)
		(end 9.652 -60.071)
		(width 0.1143)
		(layer "In7.Cu")
		(net "P2E_CPU_NGFF_C_TX_DN14")
	)
	(segment
		(start 60.468002 -55.12435)
		(end 57.705752 -52.3621)
		(width 0.1143)
		(layer "In7.Cu")
		(net "P2E_CPU_NGFF_C_TX_DN14")
	)
	(segment
		(start 83.55203 -59.904884)
		(end 83.55203 -59.57443)
		(width 0.1143)
		(layer "In7.Cu")
		(net "P2E_CPU_NGFF_C_TX_DN14")
	)
	(segment
		(start 83.55203 -59.57443)
		(end 81.534 -57.5564)
		(width 0.1143)
		(layer "In7.Cu")
		(net "P2E_CPU_NGFF_C_TX_DN14")
	)
	(segment
		(start 57.705752 -52.3621)
		(end 54.2163 -52.3621)
		(width 0.1143)
		(layer "In7.Cu")
		(net "P2E_CPU_NGFF_C_TX_DN14")
	)
	(segment
		(start 36.573206 -50.3809)
		(end 36.179506 -50.7746)
		(width 0.1143)
		(layer "In7.Cu")
		(net "P2E_CPU_NGFF_C_TX_DN14")
	)
	(segment
		(start 43.07713 -51.1937)
		(end 42.26433 -50.3809)
		(width 0.1143)
		(layer "In7.Cu")
		(net "P2E_CPU_NGFF_C_TX_DN14")
	)
	(segment
		(start 92.80525 -56.83885)
		(end 92.80525 -58.16981)
		(width 0.1016)
		(layer "F.Cu")
		(net "P2E_CPU_NGFF_C_TX_DN13")
	)
	(segment
		(start 83.879182 -56.751982)
		(end 83.879182 -56.551322)
		(width 0.1397)
		(layer "F.Cu")
		(net "P2E_CPU_NGFF_C_TX_DN13")
	)
	(segment
		(start 85.0392 -57.71134)
		(end 84.37626 -57.0484)
		(width 0.1397)
		(layer "F.Cu")
		(net "P2E_CPU_NGFF_C_TX_DN13")
	)
	(segment
		(start 91.266264 -63.011558)
		(end 86.961218 -63.011558)
		(width 0.1397)
		(layer "F.Cu")
		(net "P2E_CPU_NGFF_C_TX_DN13")
	)
	(segment
		(start 83.213956 -55.886096)
		(end 83.064096 -55.886096)
		(width 0.1397)
		(layer "F.Cu")
		(net "P2E_CPU_NGFF_C_TX_DN13")
	)
	(segment
		(start 92.239338 -56.272938)
		(end 92.80525 -56.83885)
		(width 0.1016)
		(layer "F.Cu")
		(net "P2E_CPU_NGFF_C_TX_DN13")
	)
	(segment
		(start 86.961218 -63.011558)
		(end 85.0392 -61.08954)
		(width 0.1397)
		(layer "F.Cu")
		(net "P2E_CPU_NGFF_C_TX_DN13")
	)
	(segment
		(start 84.1756 -57.0484)
		(end 83.879182 -56.751982)
		(width 0.1397)
		(layer "F.Cu")
		(net "P2E_CPU_NGFF_C_TX_DN13")
	)
	(segment
		(start 92.80525 -58.16981)
		(end 92.8751 -58.23966)
		(width 0.1016)
		(layer "F.Cu")
		(net "P2E_CPU_NGFF_C_TX_DN13")
	)
	(segment
		(start 91.948 -52.5272)
		(end 91.948 -53.751734)
		(width 0.1016)
		(layer "F.Cu")
		(net "P2E_CPU_NGFF_C_TX_DN13")
	)
	(segment
		(start 8.9662 -56.515)
		(end 9.6266 -56.515)
		(width 0.1397)
		(layer "F.Cu")
		(net "P2E_CPU_NGFF_C_TX_DN13")
	)
	(segment
		(start 92.239338 -54.043072)
		(end 92.239338 -56.272938)
		(width 0.1016)
		(layer "F.Cu")
		(net "P2E_CPU_NGFF_C_TX_DN13")
	)
	(segment
		(start 84.37626 -57.0484)
		(end 84.1756 -57.0484)
		(width 0.1397)
		(layer "F.Cu")
		(net "P2E_CPU_NGFF_C_TX_DN13")
	)
	(segment
		(start 91.948 -53.751734)
		(end 92.239338 -54.043072)
		(width 0.1016)
		(layer "F.Cu")
		(net "P2E_CPU_NGFF_C_TX_DN13")
	)
	(segment
		(start 91.862148 -52.055014)
		(end 91.862148 -52.441348)
		(width 0.1016)
		(layer "F.Cu")
		(net "P2E_CPU_NGFF_C_TX_DN13")
	)
	(segment
		(start 91.963748 -51.953414)
		(end 91.862148 -52.055014)
		(width 0.1016)
		(layer "F.Cu")
		(net "P2E_CPU_NGFF_C_TX_DN13")
	)
	(segment
		(start 83.879182 -56.551322)
		(end 83.213956 -55.886096)
		(width 0.1397)
		(layer "F.Cu")
		(net "P2E_CPU_NGFF_C_TX_DN13")
	)
	(segment
		(start 92.8751 -58.23966)
		(end 92.8751 -58.26506)
		(width 0.1016)
		(layer "F.Cu")
		(net "P2E_CPU_NGFF_C_TX_DN13")
	)
	(segment
		(start 91.862148 -52.441348)
		(end 91.948 -52.5272)
		(width 0.1016)
		(layer "F.Cu")
		(net "P2E_CPU_NGFF_C_TX_DN13")
	)
	(segment
		(start 92.8751 -58.26506)
		(end 92.8751 -61.402722)
		(width 0.1397)
		(layer "F.Cu")
		(net "P2E_CPU_NGFF_C_TX_DN13")
	)
	(segment
		(start 85.0392 -61.08954)
		(end 85.0392 -57.71134)
		(width 0.1397)
		(layer "F.Cu")
		(net "P2E_CPU_NGFF_C_TX_DN13")
	)
	(segment
		(start 92.8751 -61.402722)
		(end 91.266264 -63.011558)
		(width 0.1397)
		(layer "F.Cu")
		(net "P2E_CPU_NGFF_C_TX_DN13")
	)
	(via
		(at 9.6266 -56.515)
		(size 0.508)
		(drill 0.254)
		(layers "F.Cu" "B.Cu")
		(net "P2E_CPU_NGFF_C_TX_DN13")
	)
	(via
		(at 83.064096 -55.886096)
		(size 0.4318)
		(drill 0.2032)
		(layers "F.Cu" "B.Cu")
		(net "P2E_CPU_NGFF_C_TX_DN13")
	)
	(segment
		(start 10.54608 -56.2356)
		(end 11.2141 -55.56758)
		(width 0.1143)
		(layer "In7.Cu")
		(net "P2E_CPU_NGFF_C_TX_DN13")
	)
	(segment
		(start 46.083474 -47.45736)
		(end 46.426374 -47.45736)
		(width 0.1143)
		(layer "In7.Cu")
		(net "P2E_CPU_NGFF_C_TX_DN13")
	)
	(segment
		(start 32.322262 -41.1734)
		(end 37.531294 -41.1734)
		(width 0.1143)
		(layer "In7.Cu")
		(net "P2E_CPU_NGFF_C_TX_DN13")
	)
	(segment
		(start 76.139294 -52.2732)
		(end 76.952094 -52.2732)
		(width 0.1143)
		(layer "In7.Cu")
		(net "P2E_CPU_NGFF_C_TX_DN13")
	)
	(segment
		(start 59.633358 -50.3301)
		(end 61.633608 -52.33035)
		(width 0.1143)
		(layer "In7.Cu")
		(net "P2E_CPU_NGFF_C_TX_DN13")
	)
	(segment
		(start 16.495268 -48.7553)
		(end 18.273268 -46.9773)
		(width 0.1143)
		(layer "In7.Cu")
		(net "P2E_CPU_NGFF_C_TX_DN13")
	)
	(segment
		(start 38.0238 -41.665906)
		(end 38.0238 -44.6786)
		(width 0.1143)
		(layer "In7.Cu")
		(net "P2E_CPU_NGFF_C_TX_DN13")
	)
	(segment
		(start 46.426374 -47.45736)
		(end 46.639734 -47.244)
		(width 0.1143)
		(layer "In7.Cu")
		(net "P2E_CPU_NGFF_C_TX_DN13")
	)
	(segment
		(start 56.4007 -50.3301)
		(end 59.633358 -50.3301)
		(width 0.1143)
		(layer "In7.Cu")
		(net "P2E_CPU_NGFF_C_TX_DN13")
	)
	(segment
		(start 75.303634 -51.43754)
		(end 76.139294 -52.2732)
		(width 0.1143)
		(layer "In7.Cu")
		(net "P2E_CPU_NGFF_C_TX_DN13")
	)
	(segment
		(start 52.952142 -46.881542)
		(end 56.4007 -50.3301)
		(width 0.1143)
		(layer "In7.Cu")
		(net "P2E_CPU_NGFF_C_TX_DN13")
	)
	(segment
		(start 47.195994 -47.45736)
		(end 47.538894 -47.45736)
		(width 0.1143)
		(layer "In7.Cu")
		(net "P2E_CPU_NGFF_C_TX_DN13")
	)
	(segment
		(start 37.531294 -41.1734)
		(end 38.0238 -41.665906)
		(width 0.1143)
		(layer "In7.Cu")
		(net "P2E_CPU_NGFF_C_TX_DN13")
	)
	(segment
		(start 9.906 -56.2356)
		(end 10.54608 -56.2356)
		(width 0.1143)
		(layer "In7.Cu")
		(net "P2E_CPU_NGFF_C_TX_DN13")
	)
	(segment
		(start 25.277572 -45.37075)
		(end 28.124912 -45.37075)
		(width 0.1143)
		(layer "In7.Cu")
		(net "P2E_CPU_NGFF_C_TX_DN13")
	)
	(segment
		(start 23.671022 -46.9773)
		(end 25.277572 -45.37075)
		(width 0.1143)
		(layer "In7.Cu")
		(net "P2E_CPU_NGFF_C_TX_DN13")
	)
	(segment
		(start 76.952094 -52.2732)
		(end 80.499712 -55.820818)
		(width 0.1143)
		(layer "In7.Cu")
		(net "P2E_CPU_NGFF_C_TX_DN13")
	)
	(segment
		(start 80.499712 -55.820818)
		(end 82.998818 -55.820818)
		(width 0.1143)
		(layer "In7.Cu")
		(net "P2E_CPU_NGFF_C_TX_DN13")
	)
	(segment
		(start 61.633608 -52.33035)
		(end 65.01765 -52.33035)
		(width 0.1143)
		(layer "In7.Cu")
		(net "P2E_CPU_NGFF_C_TX_DN13")
	)
	(segment
		(start 38.0238 -44.6786)
		(end 40.5892 -47.244)
		(width 0.1143)
		(layer "In7.Cu")
		(net "P2E_CPU_NGFF_C_TX_DN13")
	)
	(segment
		(start 82.998818 -55.820818)
		(end 83.064096 -55.886096)
		(width 0.1143)
		(layer "In7.Cu")
		(net "P2E_CPU_NGFF_C_TX_DN13")
	)
	(segment
		(start 11.2141 -55.56758)
		(end 11.2141 -52.971446)
		(width 0.1143)
		(layer "In7.Cu")
		(net "P2E_CPU_NGFF_C_TX_DN13")
	)
	(segment
		(start 45.870114 -47.244)
		(end 46.083474 -47.45736)
		(width 0.1143)
		(layer "In7.Cu")
		(net "P2E_CPU_NGFF_C_TX_DN13")
	)
	(segment
		(start 49.2506 -47.244)
		(end 49.613058 -46.881542)
		(width 0.1143)
		(layer "In7.Cu")
		(net "P2E_CPU_NGFF_C_TX_DN13")
	)
	(segment
		(start 9.6266 -56.515)
		(end 9.906 -56.2356)
		(width 0.1143)
		(layer "In7.Cu")
		(net "P2E_CPU_NGFF_C_TX_DN13")
	)
	(segment
		(start 65.01765 -52.33035)
		(end 65.91046 -51.43754)
		(width 0.1143)
		(layer "In7.Cu")
		(net "P2E_CPU_NGFF_C_TX_DN13")
	)
	(segment
		(start 46.982634 -47.244)
		(end 47.195994 -47.45736)
		(width 0.1143)
		(layer "In7.Cu")
		(net "P2E_CPU_NGFF_C_TX_DN13")
	)
	(segment
		(start 46.639734 -47.244)
		(end 46.982634 -47.244)
		(width 0.1143)
		(layer "In7.Cu")
		(net "P2E_CPU_NGFF_C_TX_DN13")
	)
	(segment
		(start 47.752254 -47.244)
		(end 49.2506 -47.244)
		(width 0.1143)
		(layer "In7.Cu")
		(net "P2E_CPU_NGFF_C_TX_DN13")
	)
	(segment
		(start 40.5892 -47.244)
		(end 45.870114 -47.244)
		(width 0.1143)
		(layer "In7.Cu")
		(net "P2E_CPU_NGFF_C_TX_DN13")
	)
	(segment
		(start 18.273268 -46.9773)
		(end 23.671022 -46.9773)
		(width 0.1143)
		(layer "In7.Cu")
		(net "P2E_CPU_NGFF_C_TX_DN13")
	)
	(segment
		(start 47.538894 -47.45736)
		(end 47.752254 -47.244)
		(width 0.1143)
		(layer "In7.Cu")
		(net "P2E_CPU_NGFF_C_TX_DN13")
	)
	(segment
		(start 11.2141 -52.971446)
		(end 15.430246 -48.7553)
		(width 0.1143)
		(layer "In7.Cu")
		(net "P2E_CPU_NGFF_C_TX_DN13")
	)
	(segment
		(start 28.124912 -45.37075)
		(end 32.322262 -41.1734)
		(width 0.1143)
		(layer "In7.Cu")
		(net "P2E_CPU_NGFF_C_TX_DN13")
	)
	(segment
		(start 15.430246 -48.7553)
		(end 16.495268 -48.7553)
		(width 0.1143)
		(layer "In7.Cu")
		(net "P2E_CPU_NGFF_C_TX_DN13")
	)
	(segment
		(start 65.91046 -51.43754)
		(end 75.303634 -51.43754)
		(width 0.1143)
		(layer "In7.Cu")
		(net "P2E_CPU_NGFF_C_TX_DN13")
	)
	(segment
		(start 49.613058 -46.881542)
		(end 52.952142 -46.881542)
		(width 0.1143)
		(layer "In7.Cu")
		(net "P2E_CPU_NGFF_C_TX_DN13")
	)
	(segment
		(start 92.60205 -56.923178)
		(end 92.60205 -58.16981)
		(width 0.1016)
		(layer "F.Cu")
		(net "P2E_CPU_NGFF_C_TX_DP13")
	)
	(segment
		(start 85.3821 -60.9473)
		(end 85.3821 -57.5691)
		(width 0.1397)
		(layer "F.Cu")
		(net "P2E_CPU_NGFF_C_TX_DP13")
	)
	(segment
		(start 83.44154 -55.62854)
		(end 83.44154 -55.45328)
		(width 0.1397)
		(layer "F.Cu")
		(net "P2E_CPU_NGFF_C_TX_DP13")
	)
	(segment
		(start 85.3821 -57.5691)
		(end 83.44154 -55.62854)
		(width 0.1397)
		(layer "F.Cu")
		(net "P2E_CPU_NGFF_C_TX_DP13")
	)
	(segment
		(start 92.5322 -58.23966)
		(end 92.5322 -58.26506)
		(width 0.1016)
		(layer "F.Cu")
		(net "P2E_CPU_NGFF_C_TX_DP13")
	)
	(segment
		(start 92.036138 -56.357266)
		(end 92.60205 -56.923178)
		(width 0.1016)
		(layer "F.Cu")
		(net "P2E_CPU_NGFF_C_TX_DP13")
	)
	(segment
		(start 91.7448 -52.611528)
		(end 91.7448 -53.836062)
		(width 0.1016)
		(layer "F.Cu")
		(net "P2E_CPU_NGFF_C_TX_DP13")
	)
	(segment
		(start 91.7448 -53.836062)
		(end 92.036138 -54.1274)
		(width 0.1016)
		(layer "F.Cu")
		(net "P2E_CPU_NGFF_C_TX_DP13")
	)
	(segment
		(start 92.036138 -54.1274)
		(end 92.036138 -56.357266)
		(width 0.1016)
		(layer "F.Cu")
		(net "P2E_CPU_NGFF_C_TX_DP13")
	)
	(segment
		(start 91.658948 -52.525676)
		(end 91.7448 -52.611528)
		(width 0.1016)
		(layer "F.Cu")
		(net "P2E_CPU_NGFF_C_TX_DP13")
	)
	(segment
		(start 91.124024 -62.668658)
		(end 87.103458 -62.668658)
		(width 0.1397)
		(layer "F.Cu")
		(net "P2E_CPU_NGFF_C_TX_DP13")
	)
	(segment
		(start 92.5322 -61.260482)
		(end 91.124024 -62.668658)
		(width 0.1397)
		(layer "F.Cu")
		(net "P2E_CPU_NGFF_C_TX_DP13")
	)
	(segment
		(start 87.103458 -62.668658)
		(end 85.3821 -60.9473)
		(width 0.1397)
		(layer "F.Cu")
		(net "P2E_CPU_NGFF_C_TX_DP13")
	)
	(segment
		(start 92.60205 -58.16981)
		(end 92.5322 -58.23966)
		(width 0.1016)
		(layer "F.Cu")
		(net "P2E_CPU_NGFF_C_TX_DP13")
	)
	(segment
		(start 8.9662 -55.626)
		(end 9.6266 -55.626)
		(width 0.1397)
		(layer "F.Cu")
		(net "P2E_CPU_NGFF_C_TX_DP13")
	)
	(segment
		(start 91.912948 -50.995834)
		(end 91.658948 -51.826922)
		(width 0.1016)
		(layer "F.Cu")
		(net "P2E_CPU_NGFF_C_TX_DP13")
	)
	(segment
		(start 91.658948 -51.826922)
		(end 91.658948 -52.525676)
		(width 0.1016)
		(layer "F.Cu")
		(net "P2E_CPU_NGFF_C_TX_DP13")
	)
	(segment
		(start 92.5322 -58.26506)
		(end 92.5322 -61.260482)
		(width 0.1397)
		(layer "F.Cu")
		(net "P2E_CPU_NGFF_C_TX_DP13")
	)
	(via
		(at 9.6266 -55.626)
		(size 0.508)
		(drill 0.254)
		(layers "F.Cu" "B.Cu")
		(net "P2E_CPU_NGFF_C_TX_DP13")
	)
	(via
		(at 83.44154 -55.45328)
		(size 0.4318)
		(drill 0.2032)
		(layers "F.Cu" "B.Cu")
		(net "P2E_CPU_NGFF_C_TX_DP13")
	)
	(segment
		(start 77.089 -51.943)
		(end 76.2762 -51.943)
		(width 0.1143)
		(layer "In7.Cu")
		(net "P2E_CPU_NGFF_C_TX_DP13")
	)
	(segment
		(start 80.636618 -55.490618)
		(end 77.089 -51.943)
		(width 0.1143)
		(layer "In7.Cu")
		(net "P2E_CPU_NGFF_C_TX_DP13")
	)
	(segment
		(start 38.354 -41.529)
		(end 37.6682 -40.8432)
		(width 0.1143)
		(layer "In7.Cu")
		(net "P2E_CPU_NGFF_C_TX_DP13")
	)
	(segment
		(start 61.770514 -52.00015)
		(end 59.770264 -49.9999)
		(width 0.1143)
		(layer "In7.Cu")
		(net "P2E_CPU_NGFF_C_TX_DP13")
	)
	(segment
		(start 37.6682 -40.8432)
		(end 32.185356 -40.8432)
		(width 0.1143)
		(layer "In7.Cu")
		(net "P2E_CPU_NGFF_C_TX_DP13")
	)
	(segment
		(start 64.880744 -52.00015)
		(end 61.770514 -52.00015)
		(width 0.1143)
		(layer "In7.Cu")
		(net "P2E_CPU_NGFF_C_TX_DP13")
	)
	(segment
		(start 49.476152 -46.551342)
		(end 49.113694 -46.9138)
		(width 0.1143)
		(layer "In7.Cu")
		(net "P2E_CPU_NGFF_C_TX_DP13")
	)
	(segment
		(start 18.136362 -46.6471)
		(end 16.358362 -48.4251)
		(width 0.1143)
		(layer "In7.Cu")
		(net "P2E_CPU_NGFF_C_TX_DP13")
	)
	(segment
		(start 9.906 -55.9054)
		(end 9.6266 -55.626)
		(width 0.1143)
		(layer "In7.Cu")
		(net "P2E_CPU_NGFF_C_TX_DP13")
	)
	(segment
		(start 76.2762 -51.943)
		(end 75.44054 -51.10734)
		(width 0.1143)
		(layer "In7.Cu")
		(net "P2E_CPU_NGFF_C_TX_DP13")
	)
	(segment
		(start 27.988006 -45.04055)
		(end 25.140666 -45.04055)
		(width 0.1143)
		(layer "In7.Cu")
		(net "P2E_CPU_NGFF_C_TX_DP13")
	)
	(segment
		(start 49.113694 -46.9138)
		(end 40.726106 -46.9138)
		(width 0.1143)
		(layer "In7.Cu")
		(net "P2E_CPU_NGFF_C_TX_DP13")
	)
	(segment
		(start 65.773554 -51.10734)
		(end 64.880744 -52.00015)
		(width 0.1143)
		(layer "In7.Cu")
		(net "P2E_CPU_NGFF_C_TX_DP13")
	)
	(segment
		(start 83.44154 -55.45328)
		(end 83.404202 -55.490618)
		(width 0.1143)
		(layer "In7.Cu")
		(net "P2E_CPU_NGFF_C_TX_DP13")
	)
	(segment
		(start 25.140666 -45.04055)
		(end 23.534116 -46.6471)
		(width 0.1143)
		(layer "In7.Cu")
		(net "P2E_CPU_NGFF_C_TX_DP13")
	)
	(segment
		(start 10.8839 -55.430674)
		(end 10.409174 -55.9054)
		(width 0.1143)
		(layer "In7.Cu")
		(net "P2E_CPU_NGFF_C_TX_DP13")
	)
	(segment
		(start 59.770264 -49.9999)
		(end 56.537606 -49.9999)
		(width 0.1143)
		(layer "In7.Cu")
		(net "P2E_CPU_NGFF_C_TX_DP13")
	)
	(segment
		(start 83.404202 -55.490618)
		(end 80.636618 -55.490618)
		(width 0.1143)
		(layer "In7.Cu")
		(net "P2E_CPU_NGFF_C_TX_DP13")
	)
	(segment
		(start 53.089048 -46.551342)
		(end 49.476152 -46.551342)
		(width 0.1143)
		(layer "In7.Cu")
		(net "P2E_CPU_NGFF_C_TX_DP13")
	)
	(segment
		(start 38.354 -44.541694)
		(end 38.354 -41.529)
		(width 0.1143)
		(layer "In7.Cu")
		(net "P2E_CPU_NGFF_C_TX_DP13")
	)
	(segment
		(start 16.358362 -48.4251)
		(end 15.29334 -48.4251)
		(width 0.1143)
		(layer "In7.Cu")
		(net "P2E_CPU_NGFF_C_TX_DP13")
	)
	(segment
		(start 10.409174 -55.9054)
		(end 9.906 -55.9054)
		(width 0.1143)
		(layer "In7.Cu")
		(net "P2E_CPU_NGFF_C_TX_DP13")
	)
	(segment
		(start 40.726106 -46.9138)
		(end 38.354 -44.541694)
		(width 0.1143)
		(layer "In7.Cu")
		(net "P2E_CPU_NGFF_C_TX_DP13")
	)
	(segment
		(start 23.534116 -46.6471)
		(end 18.136362 -46.6471)
		(width 0.1143)
		(layer "In7.Cu")
		(net "P2E_CPU_NGFF_C_TX_DP13")
	)
	(segment
		(start 75.44054 -51.10734)
		(end 65.773554 -51.10734)
		(width 0.1143)
		(layer "In7.Cu")
		(net "P2E_CPU_NGFF_C_TX_DP13")
	)
	(segment
		(start 56.537606 -49.9999)
		(end 53.089048 -46.551342)
		(width 0.1143)
		(layer "In7.Cu")
		(net "P2E_CPU_NGFF_C_TX_DP13")
	)
	(segment
		(start 15.29334 -48.4251)
		(end 10.8839 -52.83454)
		(width 0.1143)
		(layer "In7.Cu")
		(net "P2E_CPU_NGFF_C_TX_DP13")
	)
	(segment
		(start 32.185356 -40.8432)
		(end 27.988006 -45.04055)
		(width 0.1143)
		(layer "In7.Cu")
		(net "P2E_CPU_NGFF_C_TX_DP13")
	)
	(segment
		(start 10.8839 -52.83454)
		(end 10.8839 -55.430674)
		(width 0.1143)
		(layer "In7.Cu")
		(net "P2E_CPU_NGFF_C_TX_DP13")
	)
	(segment
		(start 91.242388 -52.448714)
		(end 91.069414 -52.448714)
		(width 0.1016)
		(layer "F.Cu")
		(net "P2E_CPU_NGFF_C_TX_DP12")
	)
	(segment
		(start 12.53236 -47.9679)
		(end 12.8651 -47.9679)
		(width 0.1397)
		(layer "F.Cu")
		(net "P2E_CPU_NGFF_C_TX_DP12")
	)
	(segment
		(start 12.574524 -50.671476)
		(end 12.574524 -49.887124)
		(width 0.1397)
		(layer "F.Cu")
		(net "P2E_CPU_NGFF_C_TX_DP12")
	)
	(segment
		(start 91.069414 -52.448714)
		(end 90.8558 -52.662328)
		(width 0.1016)
		(layer "F.Cu")
		(net "P2E_CPU_NGFF_C_TX_DP12")
	)
	(segment
		(start 11.8872 -50.4952)
		(end 11.8872 -50.81905)
		(width 0.1397)
		(layer "F.Cu")
		(net "P2E_CPU_NGFF_C_TX_DP12")
	)
	(segment
		(start 12.1793 -49.4919)
		(end 12.1793 -48.32096)
		(width 0.1397)
		(layer "F.Cu")
		(net "P2E_CPU_NGFF_C_TX_DP12")
	)
	(segment
		(start 12.27455 -50.97145)
		(end 12.574524 -50.671476)
		(width 0.1397)
		(layer "F.Cu")
		(net "P2E_CPU_NGFF_C_TX_DP12")
	)
	(segment
		(start 12.0396 -50.97145)
		(end 12.27455 -50.97145)
		(width 0.1397)
		(layer "F.Cu")
		(net "P2E_CPU_NGFF_C_TX_DP12")
	)
	(segment
		(start 12.1793 -48.32096)
		(end 12.53236 -47.9679)
		(width 0.1397)
		(layer "F.Cu")
		(net "P2E_CPU_NGFF_C_TX_DP12")
	)
	(segment
		(start 90.8558 -52.662328)
		(end 90.8558 -53.193188)
		(width 0.1016)
		(layer "F.Cu")
		(net "P2E_CPU_NGFF_C_TX_DP12")
	)
	(segment
		(start 12.574524 -49.887124)
		(end 12.1793 -49.4919)
		(width 0.1397)
		(layer "F.Cu")
		(net "P2E_CPU_NGFF_C_TX_DP12")
	)
	(segment
		(start 90.8558 -53.193188)
		(end 91.058492 -53.39588)
		(width 0.1016)
		(layer "F.Cu")
		(net "P2E_CPU_NGFF_C_TX_DP12")
	)
	(segment
		(start 11.8872 -50.81905)
		(end 12.0396 -50.97145)
		(width 0.1397)
		(layer "F.Cu")
		(net "P2E_CPU_NGFF_C_TX_DP12")
	)
	(segment
		(start 12.8651 -47.9679)
		(end 13.17244 -47.66056)
		(width 0.1397)
		(layer "F.Cu")
		(net "P2E_CPU_NGFF_C_TX_DP12")
	)
	(via
		(at 13.17244 -47.66056)
		(size 0.508)
		(drill 0.254)
		(layers "F.Cu" "B.Cu")
		(net "P2E_CPU_NGFF_C_TX_DP12")
	)
	(via
		(at 91.058492 -53.39588)
		(size 0.4318)
		(drill 0.2032)
		(layers "F.Cu" "B.Cu")
		(net "P2E_CPU_NGFF_C_TX_DP12")
	)
	(segment
		(start 57.856628 -46.736)
		(end 57.404 -46.736)
		(width 0.1143)
		(layer "In7.Cu")
		(net "P2E_CPU_NGFF_C_TX_DP12")
	)
	(segment
		(start 53.400706 -45.466)
		(end 53.060346 -45.466)
		(width 0.1143)
		(layer "In7.Cu")
		(net "P2E_CPU_NGFF_C_TX_DP12")
	)
	(segment
		(start 18.478246 -44.958)
		(end 17.499076 -45.93717)
		(width 0.1143)
		(layer "In7.Cu")
		(net "P2E_CPU_NGFF_C_TX_DP12")
	)
	(segment
		(start 91.058492 -53.39588)
		(end 90.860372 -53.594)
		(width 0.1016)
		(layer "In7.Cu")
		(net "P2E_CPU_NGFF_C_TX_DP12")
	)
	(segment
		(start 47.4218 -45.72)
		(end 47.1805 -45.9613)
		(width 0.1143)
		(layer "In7.Cu")
		(net "P2E_CPU_NGFF_C_TX_DP12")
	)
	(segment
		(start 88.35136 -52.0954)
		(end 88.2523 -51.99634)
		(width 0.1016)
		(layer "In7.Cu")
		(net "P2E_CPU_NGFF_C_TX_DP12")
	)
	(segment
		(start 86.73592 -52.0954)
		(end 86.63686 -51.99634)
		(width 0.1016)
		(layer "In7.Cu")
		(net "P2E_CPU_NGFF_C_TX_DP12")
	)
	(segment
		(start 88.75522 -51.99634)
		(end 88.65616 -52.0954)
		(width 0.1016)
		(layer "In7.Cu")
		(net "P2E_CPU_NGFF_C_TX_DP12")
	)
	(segment
		(start 90.635328 -53.594)
		(end 90.4748 -53.433472)
		(width 0.1016)
		(layer "In7.Cu")
		(net "P2E_CPU_NGFF_C_TX_DP12")
	)
	(segment
		(start 14.605 -47.4726)
		(end 14.05255 -48.02505)
		(width 0.1143)
		(layer "In7.Cu")
		(net "P2E_CPU_NGFF_C_TX_DP12")
	)
	(segment
		(start 81.296256 -52.12715)
		(end 81.010506 -51.8414)
		(width 0.1143)
		(layer "In7.Cu")
		(net "P2E_CPU_NGFF_C_TX_DP12")
	)
	(segment
		(start 23.959312 -44.874688)
		(end 23.1394 -45.6946)
		(width 0.1143)
		(layer "In7.Cu")
		(net "P2E_CPU_NGFF_C_TX_DP12")
	)
	(segment
		(start 52.290726 -45.466)
		(end 51.947826 -45.466)
		(width 0.1143)
		(layer "In7.Cu")
		(net "P2E_CPU_NGFF_C_TX_DP12")
	)
	(segment
		(start 79.105506 -51.8414)
		(end 78.114906 -50.8508)
		(width 0.1143)
		(layer "In7.Cu")
		(net "P2E_CPU_NGFF_C_TX_DP12")
	)
	(segment
		(start 25.76195 -42.926)
		(end 25.273 -42.926)
		(width 0.1143)
		(layer "In7.Cu")
		(net "P2E_CPU_NGFF_C_TX_DP12")
	)
	(segment
		(start 23.1394 -45.6946)
		(end 20.1676 -45.6946)
		(width 0.1143)
		(layer "In7.Cu")
		(net "P2E_CPU_NGFF_C_TX_DP12")
	)
	(segment
		(start 45.339 -45.075094)
		(end 45.339 -45.609764)
		(width 0.1143)
		(layer "In7.Cu")
		(net "P2E_CPU_NGFF_C_TX_DP12")
	)
	(segment
		(start 28.824936 -42.69486)
		(end 27.254962 -41.124632)
		(width 0.1143)
		(layer "In7.Cu")
		(net "P2E_CPU_NGFF_C_TX_DP12")
	)
	(segment
		(start 39.51986 -41.08704)
		(end 39.3065 -40.87368)
		(width 0.1143)
		(layer "In7.Cu")
		(net "P2E_CPU_NGFF_C_TX_DP12")
	)
	(segment
		(start 87.54364 -52.0954)
		(end 87.44458 -51.99634)
		(width 0.1016)
		(layer "In7.Cu")
		(net "P2E_CPU_NGFF_C_TX_DP12")
	)
	(segment
		(start 39.3065 -44.146978)
		(end 39.3065 -41.6433)
		(width 0.1143)
		(layer "In7.Cu")
		(net "P2E_CPU_NGFF_C_TX_DP12")
	)
	(segment
		(start 26.820114 -41.124632)
		(end 26.464006 -41.48074)
		(width 0.1143)
		(layer "In7.Cu")
		(net "P2E_CPU_NGFF_C_TX_DP12")
	)
	(segment
		(start 39.914322 -44.7548)
		(end 39.3065 -44.146978)
		(width 0.1143)
		(layer "In7.Cu")
		(net "P2E_CPU_NGFF_C_TX_DP12")
	)
	(segment
		(start 23.959312 -44.572936)
		(end 23.959312 -44.874688)
		(width 0.1143)
		(layer "In7.Cu")
		(net "P2E_CPU_NGFF_C_TX_DP12")
	)
	(segment
		(start 56.7944 -48.2346)
		(end 56.169306 -48.2346)
		(width 0.1143)
		(layer "In7.Cu")
		(net "P2E_CPU_NGFF_C_TX_DP12")
	)
	(segment
		(start 43.183556 -44.62145)
		(end 41.95445 -44.62145)
		(width 0.1143)
		(layer "In7.Cu")
		(net "P2E_CPU_NGFF_C_TX_DP12")
	)
	(segment
		(start 57.023 -48.006)
		(end 56.7944 -48.2346)
		(width 0.1143)
		(layer "In7.Cu")
		(net "P2E_CPU_NGFF_C_TX_DP12")
	)
	(segment
		(start 83.914488 -52.25034)
		(end 83.815428 -52.3494)
		(width 0.1016)
		(layer "In7.Cu")
		(net "P2E_CPU_NGFF_C_TX_DP12")
	)
	(segment
		(start 55.783226 -46.130972)
		(end 55.509668 -46.130972)
		(width 0.1143)
		(layer "In7.Cu")
		(net "P2E_CPU_NGFF_C_TX_DP12")
	)
	(segment
		(start 25.273 -42.926)
		(end 24.8285 -43.3705)
		(width 0.1143)
		(layer "In7.Cu")
		(net "P2E_CPU_NGFF_C_TX_DP12")
	)
	(segment
		(start 54.322726 -46.38802)
		(end 53.400706 -45.466)
		(width 0.1143)
		(layer "In7.Cu")
		(net "P2E_CPU_NGFF_C_TX_DP12")
	)
	(segment
		(start 85.9282 -52.0954)
		(end 85.6742 -52.3494)
		(width 0.1016)
		(layer "In7.Cu")
		(net "P2E_CPU_NGFF_C_TX_DP12")
	)
	(segment
		(start 46.736 -45.847)
		(end 46.736 -45.202094)
		(width 0.1143)
		(layer "In7.Cu")
		(net "P2E_CPU_NGFF_C_TX_DP12")
	)
	(segment
		(start 46.237906 -44.704)
		(end 45.710094 -44.704)
		(width 0.1143)
		(layer "In7.Cu")
		(net "P2E_CPU_NGFF_C_TX_DP12")
	)
	(segment
		(start 86.33206 -51.99634)
		(end 86.233 -52.0954)
		(width 0.1016)
		(layer "In7.Cu")
		(net "P2E_CPU_NGFF_C_TX_DP12")
	)
	(segment
		(start 44.459906 -45.8978)
		(end 43.183556 -44.62145)
		(width 0.1143)
		(layer "In7.Cu")
		(net "P2E_CPU_NGFF_C_TX_DP12")
	)
	(segment
		(start 17.499076 -45.93717)
		(end 17.197324 -45.93717)
		(width 0.1143)
		(layer "In7.Cu")
		(net "P2E_CPU_NGFF_C_TX_DP12")
	)
	(segment
		(start 24.50338 -44.33062)
		(end 24.201628 -44.33062)
		(width 0.1143)
		(layer "In7.Cu")
		(net "P2E_CPU_NGFF_C_TX_DP12")
	)
	(segment
		(start 41.378632 -42.902632)
		(end 40.663368 -42.902632)
		(width 0.1143)
		(layer "In7.Cu")
		(net "P2E_CPU_NGFF_C_TX_DP12")
	)
	(segment
		(start 85.6742 -52.3494)
		(end 85.126068 -52.3494)
		(width 0.1016)
		(layer "In7.Cu")
		(net "P2E_CPU_NGFF_C_TX_DP12")
	)
	(segment
		(start 45.339 -45.609764)
		(end 45.050964 -45.8978)
		(width 0.1143)
		(layer "In7.Cu")
		(net "P2E_CPU_NGFF_C_TX_DP12")
	)
	(segment
		(start 81.010506 -51.8414)
		(end 79.105506 -51.8414)
		(width 0.1143)
		(layer "In7.Cu")
		(net "P2E_CPU_NGFF_C_TX_DP12")
	)
	(segment
		(start 55.509668 -46.130972)
		(end 55.50916 -46.13148)
		(width 0.1143)
		(layer "In7.Cu")
		(net "P2E_CPU_NGFF_C_TX_DP12")
	)
	(segment
		(start 87.04072 -52.0954)
		(end 86.73592 -52.0954)
		(width 0.1016)
		(layer "In7.Cu")
		(net "P2E_CPU_NGFF_C_TX_DP12")
	)
	(segment
		(start 40.122094 -44.7548)
		(end 39.914322 -44.7548)
		(width 0.1143)
		(layer "In7.Cu")
		(net "P2E_CPU_NGFF_C_TX_DP12")
	)
	(segment
		(start 88.65616 -52.0954)
		(end 88.35136 -52.0954)
		(width 0.1016)
		(layer "In7.Cu")
		(net "P2E_CPU_NGFF_C_TX_DP12")
	)
	(segment
		(start 24.201628 -44.33062)
		(end 23.959312 -44.572936)
		(width 0.1143)
		(layer "In7.Cu")
		(net "P2E_CPU_NGFF_C_TX_DP12")
	)
	(segment
		(start 41.656 -44.323)
		(end 41.656 -43.18)
		(width 0.1143)
		(layer "In7.Cu")
		(net "P2E_CPU_NGFF_C_TX_DP12")
	)
	(segment
		(start 90.4748 -52.696872)
		(end 89.873328 -52.0954)
		(width 0.1016)
		(layer "In7.Cu")
		(net "P2E_CPU_NGFF_C_TX_DP12")
	)
	(segment
		(start 16.955008 -46.179486)
		(end 16.955008 -46.481238)
		(width 0.1143)
		(layer "In7.Cu")
		(net "P2E_CPU_NGFF_C_TX_DP12")
	)
	(segment
		(start 46.8503 -45.9613)
		(end 46.736 -45.847)
		(width 0.1143)
		(layer "In7.Cu")
		(net "P2E_CPU_NGFF_C_TX_DP12")
	)
	(segment
		(start 87.13978 -51.99634)
		(end 87.04072 -52.0954)
		(width 0.1016)
		(layer "In7.Cu")
		(net "P2E_CPU_NGFF_C_TX_DP12")
	)
	(segment
		(start 83.3882 -52.3494)
		(end 83.22945 -52.19065)
		(width 0.1016)
		(layer "In7.Cu")
		(net "P2E_CPU_NGFF_C_TX_DP12")
	)
	(segment
		(start 30.40634 -41.275)
		(end 29.845 -41.275)
		(width 0.1143)
		(layer "In7.Cu")
		(net "P2E_CPU_NGFF_C_TX_DP12")
	)
	(segment
		(start 29.363416 -42.31767)
		(end 28.98648 -42.69486)
		(width 0.1143)
		(layer "In7.Cu")
		(net "P2E_CPU_NGFF_C_TX_DP12")
	)
	(segment
		(start 63.21552 -49.0982)
		(end 60.218828 -49.0982)
		(width 0.1143)
		(layer "In7.Cu")
		(net "P2E_CPU_NGFF_C_TX_DP12")
	)
	(segment
		(start 26.924 -44.08805)
		(end 25.76195 -42.926)
		(width 0.1143)
		(layer "In7.Cu")
		(net "P2E_CPU_NGFF_C_TX_DP12")
	)
	(segment
		(start 28.98648 -42.69486)
		(end 28.824936 -42.69486)
		(width 0.1143)
		(layer "In7.Cu")
		(net "P2E_CPU_NGFF_C_TX_DP12")
	)
	(segment
		(start 84.318348 -52.3494)
		(end 84.219288 -52.25034)
		(width 0.1016)
		(layer "In7.Cu")
		(net "P2E_CPU_NGFF_C_TX_DP12")
	)
	(segment
		(start 76.5048 -50.8508)
		(end 75.80884 -50.15484)
		(width 0.1143)
		(layer "In7.Cu")
		(net "P2E_CPU_NGFF_C_TX_DP12")
	)
	(segment
		(start 47.1805 -45.9613)
		(end 46.8503 -45.9613)
		(width 0.1143)
		(layer "In7.Cu")
		(net "P2E_CPU_NGFF_C_TX_DP12")
	)
	(segment
		(start 27.559 -43.942)
		(end 27.41295 -44.08805)
		(width 0.1143)
		(layer "In7.Cu")
		(net "P2E_CPU_NGFF_C_TX_DP12")
	)
	(segment
		(start 40.663368 -42.902632)
		(end 40.259 -43.307)
		(width 0.1143)
		(layer "In7.Cu")
		(net "P2E_CPU_NGFF_C_TX_DP12")
	)
	(segment
		(start 89.15908 -52.0954)
		(end 89.06002 -51.99634)
		(width 0.1016)
		(layer "In7.Cu")
		(net "P2E_CPU_NGFF_C_TX_DP12")
	)
	(segment
		(start 31.0388 -39.9542)
		(end 31.0388 -40.64254)
		(width 0.1143)
		(layer "In7.Cu")
		(net "P2E_CPU_NGFF_C_TX_DP12")
	)
	(segment
		(start 15.963646 -47.4726)
		(end 14.605 -47.4726)
		(width 0.1143)
		(layer "In7.Cu")
		(net "P2E_CPU_NGFF_C_TX_DP12")
	)
	(segment
		(start 64.27216 -50.15484)
		(end 63.21552 -49.0982)
		(width 0.1143)
		(layer "In7.Cu")
		(net "P2E_CPU_NGFF_C_TX_DP12")
	)
	(segment
		(start 60.218828 -49.0982)
		(end 57.856628 -46.736)
		(width 0.1143)
		(layer "In7.Cu")
		(net "P2E_CPU_NGFF_C_TX_DP12")
	)
	(segment
		(start 86.63686 -51.99634)
		(end 86.33206 -51.99634)
		(width 0.1016)
		(layer "In7.Cu")
		(net "P2E_CPU_NGFF_C_TX_DP12")
	)
	(segment
		(start 75.80884 -50.15484)
		(end 64.27216 -50.15484)
		(width 0.1143)
		(layer "In7.Cu")
		(net "P2E_CPU_NGFF_C_TX_DP12")
	)
	(segment
		(start 29.36367 -42.31767)
		(end 29.363416 -42.31767)
		(width 0.1143)
		(layer "In7.Cu")
		(net "P2E_CPU_NGFF_C_TX_DP12")
	)
	(segment
		(start 41.95445 -44.62145)
		(end 41.656 -44.323)
		(width 0.1143)
		(layer "In7.Cu")
		(net "P2E_CPU_NGFF_C_TX_DP12")
	)
	(segment
		(start 26.464006 -42.339006)
		(end 27.559 -43.434)
		(width 0.1143)
		(layer "In7.Cu")
		(net "P2E_CPU_NGFF_C_TX_DP12")
	)
	(segment
		(start 39.3065 -41.6433)
		(end 39.51986 -41.42994)
		(width 0.1143)
		(layer "In7.Cu")
		(net "P2E_CPU_NGFF_C_TX_DP12")
	)
	(segment
		(start 90.860372 -53.594)
		(end 90.635328 -53.594)
		(width 0.1016)
		(layer "In7.Cu")
		(net "P2E_CPU_NGFF_C_TX_DP12")
	)
	(segment
		(start 20.1676 -45.6946)
		(end 19.431 -44.958)
		(width 0.1143)
		(layer "In7.Cu")
		(net "P2E_CPU_NGFF_C_TX_DP12")
	)
	(segment
		(start 86.233 -52.0954)
		(end 85.9282 -52.0954)
		(width 0.1016)
		(layer "In7.Cu")
		(net "P2E_CPU_NGFF_C_TX_DP12")
	)
	(segment
		(start 47.4218 -45.456094)
		(end 47.4218 -45.72)
		(width 0.1143)
		(layer "In7.Cu")
		(net "P2E_CPU_NGFF_C_TX_DP12")
	)
	(segment
		(start 51.947826 -45.466)
		(end 51.734466 -45.25264)
		(width 0.1143)
		(layer "In7.Cu")
		(net "P2E_CPU_NGFF_C_TX_DP12")
	)
	(segment
		(start 56.261 -47.244)
		(end 56.261 -46.608746)
		(width 0.1143)
		(layer "In7.Cu")
		(net "P2E_CPU_NGFF_C_TX_DP12")
	)
	(segment
		(start 89.06002 -51.99634)
		(end 88.75522 -51.99634)
		(width 0.1016)
		(layer "In7.Cu")
		(net "P2E_CPU_NGFF_C_TX_DP12")
	)
	(segment
		(start 78.114906 -50.8508)
		(end 76.5048 -50.8508)
		(width 0.1143)
		(layer "In7.Cu")
		(net "P2E_CPU_NGFF_C_TX_DP12")
	)
	(segment
		(start 19.431 -44.958)
		(end 18.478246 -44.958)
		(width 0.1143)
		(layer "In7.Cu")
		(net "P2E_CPU_NGFF_C_TX_DP12")
	)
	(segment
		(start 52.846986 -45.25264)
		(end 52.504086 -45.25264)
		(width 0.1143)
		(layer "In7.Cu")
		(net "P2E_CPU_NGFF_C_TX_DP12")
	)
	(segment
		(start 51.391566 -45.25264)
		(end 51.178206 -45.466)
		(width 0.1143)
		(layer "In7.Cu")
		(net "P2E_CPU_NGFF_C_TX_DP12")
	)
	(segment
		(start 47.957994 -44.9199)
		(end 47.4218 -45.456094)
		(width 0.1143)
		(layer "In7.Cu")
		(net "P2E_CPU_NGFF_C_TX_DP12")
	)
	(segment
		(start 57.023 -47.117)
		(end 57.023 -48.006)
		(width 0.1143)
		(layer "In7.Cu")
		(net "P2E_CPU_NGFF_C_TX_DP12")
	)
	(segment
		(start 27.41295 -44.08805)
		(end 26.924 -44.08805)
		(width 0.1143)
		(layer "In7.Cu")
		(net "P2E_CPU_NGFF_C_TX_DP12")
	)
	(segment
		(start 53.060346 -45.466)
		(end 52.846986 -45.25264)
		(width 0.1143)
		(layer "In7.Cu")
		(net "P2E_CPU_NGFF_C_TX_DP12")
	)
	(segment
		(start 46.736 -45.202094)
		(end 46.237906 -44.704)
		(width 0.1143)
		(layer "In7.Cu")
		(net "P2E_CPU_NGFF_C_TX_DP12")
	)
	(segment
		(start 55.50916 -46.13148)
		(end 55.08752 -46.13148)
		(width 0.1143)
		(layer "In7.Cu")
		(net "P2E_CPU_NGFF_C_TX_DP12")
	)
	(segment
		(start 82.86115 -52.12715)
		(end 82.83575 -52.12715)
		(width 0.1016)
		(layer "In7.Cu")
		(net "P2E_CPU_NGFF_C_TX_DP12")
	)
	(segment
		(start 13.53693 -48.02505)
		(end 13.17244 -47.66056)
		(width 0.1143)
		(layer "In7.Cu")
		(net "P2E_CPU_NGFF_C_TX_DP12")
	)
	(segment
		(start 41.656 -43.18)
		(end 41.378632 -42.902632)
		(width 0.1143)
		(layer "In7.Cu")
		(net "P2E_CPU_NGFF_C_TX_DP12")
	)
	(segment
		(start 38.617906 -39.4208)
		(end 31.5722 -39.4208)
		(width 0.1143)
		(layer "In7.Cu")
		(net "P2E_CPU_NGFF_C_TX_DP12")
	)
	(segment
		(start 90.4748 -53.433472)
		(end 90.4748 -52.696872)
		(width 0.1016)
		(layer "In7.Cu")
		(net "P2E_CPU_NGFF_C_TX_DP12")
	)
	(segment
		(start 31.5722 -39.4208)
		(end 31.0388 -39.9542)
		(width 0.1143)
		(layer "In7.Cu")
		(net "P2E_CPU_NGFF_C_TX_DP12")
	)
	(segment
		(start 83.22945 -52.19065)
		(end 82.92465 -52.19065)
		(width 0.1016)
		(layer "In7.Cu")
		(net "P2E_CPU_NGFF_C_TX_DP12")
	)
	(segment
		(start 29.36367 -41.75633)
		(end 29.36367 -42.31767)
		(width 0.1143)
		(layer "In7.Cu")
		(net "P2E_CPU_NGFF_C_TX_DP12")
	)
	(segment
		(start 89.873328 -52.0954)
		(end 89.15908 -52.0954)
		(width 0.1016)
		(layer "In7.Cu")
		(net "P2E_CPU_NGFF_C_TX_DP12")
	)
	(segment
		(start 26.464006 -41.48074)
		(end 26.464006 -42.339006)
		(width 0.1143)
		(layer "In7.Cu")
		(net "P2E_CPU_NGFF_C_TX_DP12")
	)
	(segment
		(start 40.259 -44.617894)
		(end 40.122094 -44.7548)
		(width 0.1143)
		(layer "In7.Cu")
		(net "P2E_CPU_NGFF_C_TX_DP12")
	)
	(segment
		(start 39.51986 -41.42994)
		(end 39.51986 -41.08704)
		(width 0.1143)
		(layer "In7.Cu")
		(net "P2E_CPU_NGFF_C_TX_DP12")
	)
	(segment
		(start 54.83098 -46.38802)
		(end 54.322726 -46.38802)
		(width 0.1143)
		(layer "In7.Cu")
		(net "P2E_CPU_NGFF_C_TX_DP12")
	)
	(segment
		(start 48.803306 -44.9199)
		(end 47.957994 -44.9199)
		(width 0.1143)
		(layer "In7.Cu")
		(net "P2E_CPU_NGFF_C_TX_DP12")
	)
	(segment
		(start 39.3065 -40.109394)
		(end 38.617906 -39.4208)
		(width 0.1143)
		(layer "In7.Cu")
		(net "P2E_CPU_NGFF_C_TX_DP12")
	)
	(segment
		(start 87.84844 -52.0954)
		(end 87.54364 -52.0954)
		(width 0.1016)
		(layer "In7.Cu")
		(net "P2E_CPU_NGFF_C_TX_DP12")
	)
	(segment
		(start 17.197324 -45.93717)
		(end 16.955008 -46.179486)
		(width 0.1143)
		(layer "In7.Cu")
		(net "P2E_CPU_NGFF_C_TX_DP12")
	)
	(segment
		(start 57.404 -46.736)
		(end 57.023 -47.117)
		(width 0.1143)
		(layer "In7.Cu")
		(net "P2E_CPU_NGFF_C_TX_DP12")
	)
	(segment
		(start 29.845 -41.275)
		(end 29.36367 -41.75633)
		(width 0.1143)
		(layer "In7.Cu")
		(net "P2E_CPU_NGFF_C_TX_DP12")
	)
	(segment
		(start 51.178206 -45.466)
		(end 49.349406 -45.466)
		(width 0.1143)
		(layer "In7.Cu")
		(net "P2E_CPU_NGFF_C_TX_DP12")
	)
	(segment
		(start 49.349406 -45.466)
		(end 48.803306 -44.9199)
		(width 0.1143)
		(layer "In7.Cu")
		(net "P2E_CPU_NGFF_C_TX_DP12")
	)
	(segment
		(start 56.007 -47.498)
		(end 56.261 -47.244)
		(width 0.1143)
		(layer "In7.Cu")
		(net "P2E_CPU_NGFF_C_TX_DP12")
	)
	(segment
		(start 14.05255 -48.02505)
		(end 13.53693 -48.02505)
		(width 0.1143)
		(layer "In7.Cu")
		(net "P2E_CPU_NGFF_C_TX_DP12")
	)
	(segment
		(start 45.710094 -44.704)
		(end 45.339 -45.075094)
		(width 0.1143)
		(layer "In7.Cu")
		(net "P2E_CPU_NGFF_C_TX_DP12")
	)
	(segment
		(start 56.261 -46.608746)
		(end 55.783226 -46.130972)
		(width 0.1143)
		(layer "In7.Cu")
		(net "P2E_CPU_NGFF_C_TX_DP12")
	)
	(segment
		(start 39.3065 -40.87368)
		(end 39.3065 -40.109394)
		(width 0.1143)
		(layer "In7.Cu")
		(net "P2E_CPU_NGFF_C_TX_DP12")
	)
	(segment
		(start 84.623148 -52.3494)
		(end 84.318348 -52.3494)
		(width 0.1016)
		(layer "In7.Cu")
		(net "P2E_CPU_NGFF_C_TX_DP12")
	)
	(segment
		(start 82.92465 -52.19065)
		(end 82.86115 -52.12715)
		(width 0.1016)
		(layer "In7.Cu")
		(net "P2E_CPU_NGFF_C_TX_DP12")
	)
	(segment
		(start 45.050964 -45.8978)
		(end 44.459906 -45.8978)
		(width 0.1143)
		(layer "In7.Cu")
		(net "P2E_CPU_NGFF_C_TX_DP12")
	)
	(segment
		(start 24.8285 -43.3705)
		(end 24.8285 -44.0055)
		(width 0.1143)
		(layer "In7.Cu")
		(net "P2E_CPU_NGFF_C_TX_DP12")
	)
	(segment
		(start 82.83575 -52.12715)
		(end 81.296256 -52.12715)
		(width 0.1143)
		(layer "In7.Cu")
		(net "P2E_CPU_NGFF_C_TX_DP12")
	)
	(segment
		(start 85.126068 -52.3494)
		(end 85.027008 -52.25034)
		(width 0.1016)
		(layer "In7.Cu")
		(net "P2E_CPU_NGFF_C_TX_DP12")
	)
	(segment
		(start 51.734466 -45.25264)
		(end 51.391566 -45.25264)
		(width 0.1143)
		(layer "In7.Cu")
		(net "P2E_CPU_NGFF_C_TX_DP12")
	)
	(segment
		(start 31.0388 -40.64254)
		(end 30.40634 -41.275)
		(width 0.1143)
		(layer "In7.Cu")
		(net "P2E_CPU_NGFF_C_TX_DP12")
	)
	(segment
		(start 16.955008 -46.481238)
		(end 15.963646 -47.4726)
		(width 0.1143)
		(layer "In7.Cu")
		(net "P2E_CPU_NGFF_C_TX_DP12")
	)
	(segment
		(start 56.169306 -48.2346)
		(end 56.007 -48.072294)
		(width 0.1143)
		(layer "In7.Cu")
		(net "P2E_CPU_NGFF_C_TX_DP12")
	)
	(segment
		(start 24.8285 -44.0055)
		(end 24.50338 -44.33062)
		(width 0.1143)
		(layer "In7.Cu")
		(net "P2E_CPU_NGFF_C_TX_DP12")
	)
	(segment
		(start 87.9475 -51.99634)
		(end 87.84844 -52.0954)
		(width 0.1016)
		(layer "In7.Cu")
		(net "P2E_CPU_NGFF_C_TX_DP12")
	)
	(segment
		(start 27.559 -43.434)
		(end 27.559 -43.942)
		(width 0.1143)
		(layer "In7.Cu")
		(net "P2E_CPU_NGFF_C_TX_DP12")
	)
	(segment
		(start 84.219288 -52.25034)
		(end 83.914488 -52.25034)
		(width 0.1016)
		(layer "In7.Cu")
		(net "P2E_CPU_NGFF_C_TX_DP12")
	)
	(segment
		(start 27.254962 -41.124632)
		(end 26.820114 -41.124632)
		(width 0.1143)
		(layer "In7.Cu")
		(net "P2E_CPU_NGFF_C_TX_DP12")
	)
	(segment
		(start 83.815428 -52.3494)
		(end 83.3882 -52.3494)
		(width 0.1016)
		(layer "In7.Cu")
		(net "P2E_CPU_NGFF_C_TX_DP12")
	)
	(segment
		(start 52.504086 -45.25264)
		(end 52.290726 -45.466)
		(width 0.1143)
		(layer "In7.Cu")
		(net "P2E_CPU_NGFF_C_TX_DP12")
	)
	(segment
		(start 56.007 -48.072294)
		(end 56.007 -47.498)
		(width 0.1143)
		(layer "In7.Cu")
		(net "P2E_CPU_NGFF_C_TX_DP12")
	)
	(segment
		(start 40.259 -43.307)
		(end 40.259 -44.617894)
		(width 0.1143)
		(layer "In7.Cu")
		(net "P2E_CPU_NGFF_C_TX_DP12")
	)
	(segment
		(start 84.722208 -52.25034)
		(end 84.623148 -52.3494)
		(width 0.1016)
		(layer "In7.Cu")
		(net "P2E_CPU_NGFF_C_TX_DP12")
	)
	(segment
		(start 87.44458 -51.99634)
		(end 87.13978 -51.99634)
		(width 0.1016)
		(layer "In7.Cu")
		(net "P2E_CPU_NGFF_C_TX_DP12")
	)
	(segment
		(start 88.2523 -51.99634)
		(end 87.9475 -51.99634)
		(width 0.1016)
		(layer "In7.Cu")
		(net "P2E_CPU_NGFF_C_TX_DP12")
	)
	(segment
		(start 55.08752 -46.13148)
		(end 54.83098 -46.38802)
		(width 0.1143)
		(layer "In7.Cu")
		(net "P2E_CPU_NGFF_C_TX_DP12")
	)
	(segment
		(start 85.027008 -52.25034)
		(end 84.722208 -52.25034)
		(width 0.1016)
		(layer "In7.Cu")
		(net "P2E_CPU_NGFF_C_TX_DP12")
	)
	(segment
		(start 11.8872 -51.4604)
		(end 12.03325 -51.31435)
		(width 0.1397)
		(layer "F.Cu")
		(net "P2E_CPU_NGFF_C_TX_DN12")
	)
	(segment
		(start 12.5222 -48.4632)
		(end 12.6746 -48.3108)
		(width 0.1397)
		(layer "F.Cu")
		(net "P2E_CPU_NGFF_C_TX_DN12")
	)
	(segment
		(start 11.8872 -51.7398)
		(end 11.8872 -51.4604)
		(width 0.1397)
		(layer "F.Cu")
		(net "P2E_CPU_NGFF_C_TX_DN12")
	)
	(segment
		(start 91.029028 -53.956458)
		(end 90.6526 -53.58003)
		(width 0.1016)
		(layer "F.Cu")
		(net "P2E_CPU_NGFF_C_TX_DN12")
	)
	(segment
		(start 12.5222 -49.34966)
		(end 12.5222 -48.4632)
		(width 0.1397)
		(layer "F.Cu")
		(net "P2E_CPU_NGFF_C_TX_DN12")
	)
	(segment
		(start 12.6746 -48.3108)
		(end 12.8651 -48.3108)
		(width 0.1397)
		(layer "F.Cu")
		(net "P2E_CPU_NGFF_C_TX_DN12")
	)
	(segment
		(start 12.8651 -48.3108)
		(end 13.17244 -48.61814)
		(width 0.1397)
		(layer "F.Cu")
		(net "P2E_CPU_NGFF_C_TX_DN12")
	)
	(segment
		(start 12.917424 -50.813716)
		(end 12.917424 -49.744884)
		(width 0.1397)
		(layer "F.Cu")
		(net "P2E_CPU_NGFF_C_TX_DN12")
	)
	(segment
		(start 90.6526 -52.578)
		(end 90.9574 -52.2732)
		(width 0.1016)
		(layer "F.Cu")
		(net "P2E_CPU_NGFF_C_TX_DN12")
	)
	(segment
		(start 12.03325 -51.31435)
		(end 12.41679 -51.31435)
		(width 0.1397)
		(layer "F.Cu")
		(net "P2E_CPU_NGFF_C_TX_DN12")
	)
	(segment
		(start 90.6526 -53.58003)
		(end 90.6526 -52.578)
		(width 0.1016)
		(layer "F.Cu")
		(net "P2E_CPU_NGFF_C_TX_DN12")
	)
	(segment
		(start 12.917424 -49.744884)
		(end 12.5222 -49.34966)
		(width 0.1397)
		(layer "F.Cu")
		(net "P2E_CPU_NGFF_C_TX_DN12")
	)
	(segment
		(start 90.9574 -52.2732)
		(end 91.293188 -51.503834)
		(width 0.1016)
		(layer "F.Cu")
		(net "P2E_CPU_NGFF_C_TX_DN12")
	)
	(segment
		(start 12.41679 -51.31435)
		(end 12.917424 -50.813716)
		(width 0.1397)
		(layer "F.Cu")
		(net "P2E_CPU_NGFF_C_TX_DN12")
	)
	(via
		(at 13.17244 -48.61814)
		(size 0.508)
		(drill 0.254)
		(layers "F.Cu" "B.Cu")
		(net "P2E_CPU_NGFF_C_TX_DN12")
	)
	(via
		(at 91.029028 -53.956458)
		(size 0.4318)
		(drill 0.2032)
		(layers "F.Cu" "B.Cu")
		(net "P2E_CPU_NGFF_C_TX_DN12")
	)
	(segment
		(start 14.189456 -48.35525)
		(end 13.43533 -48.35525)
		(width 0.1143)
		(layer "In7.Cu")
		(net "P2E_CPU_NGFF_C_TX_DN12")
	)
	(segment
		(start 90.2716 -53.5178)
		(end 90.2716 -52.7812)
		(width 0.1016)
		(layer "In7.Cu")
		(net "P2E_CPU_NGFF_C_TX_DN12")
	)
	(segment
		(start 55.224426 -46.46168)
		(end 54.967886 -46.71822)
		(width 0.1143)
		(layer "In7.Cu")
		(net "P2E_CPU_NGFF_C_TX_DN12")
	)
	(segment
		(start 54.967886 -46.71822)
		(end 54.18582 -46.71822)
		(width 0.1143)
		(layer "In7.Cu")
		(net "P2E_CPU_NGFF_C_TX_DN12")
	)
	(segment
		(start 81.15935 -52.45735)
		(end 80.8736 -52.1716)
		(width 0.1143)
		(layer "In7.Cu")
		(net "P2E_CPU_NGFF_C_TX_DN12")
	)
	(segment
		(start 83.145122 -52.39385)
		(end 82.92465 -52.39385)
		(width 0.1016)
		(layer "In7.Cu")
		(net "P2E_CPU_NGFF_C_TX_DN12")
	)
	(segment
		(start 19.294094 -45.2882)
		(end 18.615152 -45.2882)
		(width 0.1143)
		(layer "In7.Cu")
		(net "P2E_CPU_NGFF_C_TX_DN12")
	)
	(segment
		(start 47.752 -45.593)
		(end 47.752 -45.856906)
		(width 0.1143)
		(layer "In7.Cu")
		(net "P2E_CPU_NGFF_C_TX_DN12")
	)
	(segment
		(start 48.0949 -45.2501)
		(end 47.752 -45.593)
		(width 0.1143)
		(layer "In7.Cu")
		(net "P2E_CPU_NGFF_C_TX_DN12")
	)
	(segment
		(start 83.303872 -52.5526)
		(end 83.145122 -52.39385)
		(width 0.1016)
		(layer "In7.Cu")
		(net "P2E_CPU_NGFF_C_TX_DN12")
	)
	(segment
		(start 44.323 -46.228)
		(end 43.04665 -44.95165)
		(width 0.1143)
		(layer "In7.Cu")
		(net "P2E_CPU_NGFF_C_TX_DN12")
	)
	(segment
		(start 48.6664 -45.2501)
		(end 48.0949 -45.2501)
		(width 0.1143)
		(layer "In7.Cu")
		(net "P2E_CPU_NGFF_C_TX_DN12")
	)
	(segment
		(start 40.259 -45.085)
		(end 39.777416 -45.085)
		(width 0.1143)
		(layer "In7.Cu")
		(net "P2E_CPU_NGFF_C_TX_DN12")
	)
	(segment
		(start 82.92465 -52.39385)
		(end 82.86115 -52.45735)
		(width 0.1016)
		(layer "In7.Cu")
		(net "P2E_CPU_NGFF_C_TX_DN12")
	)
	(segment
		(start 27.549856 -44.41825)
		(end 26.787094 -44.41825)
		(width 0.1143)
		(layer "In7.Cu")
		(net "P2E_CPU_NGFF_C_TX_DN12")
	)
	(segment
		(start 91.029028 -53.956458)
		(end 90.86977 -53.7972)
		(width 0.1016)
		(layer "In7.Cu")
		(net "P2E_CPU_NGFF_C_TX_DN12")
	)
	(segment
		(start 43.04665 -44.95165)
		(end 41.817544 -44.95165)
		(width 0.1143)
		(layer "In7.Cu")
		(net "P2E_CPU_NGFF_C_TX_DN12")
	)
	(segment
		(start 90.551 -53.7972)
		(end 90.2716 -53.5178)
		(width 0.1016)
		(layer "In7.Cu")
		(net "P2E_CPU_NGFF_C_TX_DN12")
	)
	(segment
		(start 20.030694 -46.0248)
		(end 19.294094 -45.2882)
		(width 0.1143)
		(layer "In7.Cu")
		(net "P2E_CPU_NGFF_C_TX_DN12")
	)
	(segment
		(start 46.713394 -46.2915)
		(end 46.4058 -45.983906)
		(width 0.1143)
		(layer "In7.Cu")
		(net "P2E_CPU_NGFF_C_TX_DN12")
	)
	(segment
		(start 64.135254 -50.48504)
		(end 63.078614 -49.4284)
		(width 0.1143)
		(layer "In7.Cu")
		(net "P2E_CPU_NGFF_C_TX_DN12")
	)
	(segment
		(start 63.078614 -49.4284)
		(end 60.081922 -49.4284)
		(width 0.1143)
		(layer "In7.Cu")
		(net "P2E_CPU_NGFF_C_TX_DN12")
	)
	(segment
		(start 13.43533 -48.35525)
		(end 13.17244 -48.61814)
		(width 0.1143)
		(layer "In7.Cu")
		(net "P2E_CPU_NGFF_C_TX_DN12")
	)
	(segment
		(start 18.615152 -45.2882)
		(end 16.100552 -47.8028)
		(width 0.1143)
		(layer "In7.Cu")
		(net "P2E_CPU_NGFF_C_TX_DN12")
	)
	(segment
		(start 41.3258 -43.316906)
		(end 41.241726 -43.232832)
		(width 0.1143)
		(layer "In7.Cu")
		(net "P2E_CPU_NGFF_C_TX_DN12")
	)
	(segment
		(start 46.4058 -45.339)
		(end 46.101 -45.0342)
		(width 0.1143)
		(layer "In7.Cu")
		(net "P2E_CPU_NGFF_C_TX_DN12")
	)
	(segment
		(start 78.9686 -52.1716)
		(end 77.978 -51.181)
		(width 0.1143)
		(layer "In7.Cu")
		(net "P2E_CPU_NGFF_C_TX_DN12")
	)
	(segment
		(start 28.68803 -43.02506)
		(end 27.118056 -41.454832)
		(width 0.1143)
		(layer "In7.Cu")
		(net "P2E_CPU_NGFF_C_TX_DN12")
	)
	(segment
		(start 16.100552 -47.8028)
		(end 14.741906 -47.8028)
		(width 0.1143)
		(layer "In7.Cu")
		(net "P2E_CPU_NGFF_C_TX_DN12")
	)
	(segment
		(start 57.719722 -47.0662)
		(end 57.540906 -47.0662)
		(width 0.1143)
		(layer "In7.Cu")
		(net "P2E_CPU_NGFF_C_TX_DN12")
	)
	(segment
		(start 56.0324 -48.5648)
		(end 55.6768 -48.2092)
		(width 0.1143)
		(layer "In7.Cu")
		(net "P2E_CPU_NGFF_C_TX_DN12")
	)
	(segment
		(start 45.6692 -45.74667)
		(end 45.18787 -46.228)
		(width 0.1143)
		(layer "In7.Cu")
		(net "P2E_CPU_NGFF_C_TX_DN12")
	)
	(segment
		(start 27.8892 -44.078906)
		(end 27.549856 -44.41825)
		(width 0.1143)
		(layer "In7.Cu")
		(net "P2E_CPU_NGFF_C_TX_DN12")
	)
	(segment
		(start 85.758528 -52.5526)
		(end 83.303872 -52.5526)
		(width 0.1016)
		(layer "In7.Cu")
		(net "P2E_CPU_NGFF_C_TX_DN12")
	)
	(segment
		(start 38.9763 -40.2463)
		(end 38.481 -39.751)
		(width 0.1143)
		(layer "In7.Cu")
		(net "P2E_CPU_NGFF_C_TX_DN12")
	)
	(segment
		(start 29.981906 -41.6052)
		(end 29.69387 -41.893236)
		(width 0.1143)
		(layer "In7.Cu")
		(net "P2E_CPU_NGFF_C_TX_DN12")
	)
	(segment
		(start 40.800274 -43.232832)
		(end 40.5892 -43.443906)
		(width 0.1143)
		(layer "In7.Cu")
		(net "P2E_CPU_NGFF_C_TX_DN12")
	)
	(segment
		(start 55.9308 -46.745906)
		(end 55.64632 -46.461426)
		(width 0.1143)
		(layer "In7.Cu")
		(net "P2E_CPU_NGFF_C_TX_DN12")
	)
	(segment
		(start 26.794206 -41.617646)
		(end 26.794206 -42.2021)
		(width 0.1143)
		(layer "In7.Cu")
		(net "P2E_CPU_NGFF_C_TX_DN12")
	)
	(segment
		(start 39.777416 -45.085)
		(end 38.9763 -44.283884)
		(width 0.1143)
		(layer "In7.Cu")
		(net "P2E_CPU_NGFF_C_TX_DN12")
	)
	(segment
		(start 31.709106 -39.751)
		(end 31.369 -40.091106)
		(width 0.1143)
		(layer "In7.Cu")
		(net "P2E_CPU_NGFF_C_TX_DN12")
	)
	(segment
		(start 29.69387 -42.454576)
		(end 29.123386 -43.02506)
		(width 0.1143)
		(layer "In7.Cu")
		(net "P2E_CPU_NGFF_C_TX_DN12")
	)
	(segment
		(start 41.241726 -43.232832)
		(end 40.800274 -43.232832)
		(width 0.1143)
		(layer "In7.Cu")
		(net "P2E_CPU_NGFF_C_TX_DN12")
	)
	(segment
		(start 29.123386 -43.02506)
		(end 28.68803 -43.02506)
		(width 0.1143)
		(layer "In7.Cu")
		(net "P2E_CPU_NGFF_C_TX_DN12")
	)
	(segment
		(start 26.95702 -41.454832)
		(end 26.794206 -41.617646)
		(width 0.1143)
		(layer "In7.Cu")
		(net "P2E_CPU_NGFF_C_TX_DN12")
	)
	(segment
		(start 45.847 -45.0342)
		(end 45.6692 -45.212)
		(width 0.1143)
		(layer "In7.Cu")
		(net "P2E_CPU_NGFF_C_TX_DN12")
	)
	(segment
		(start 14.741906 -47.8028)
		(end 14.189456 -48.35525)
		(width 0.1143)
		(layer "In7.Cu")
		(net "P2E_CPU_NGFF_C_TX_DN12")
	)
	(segment
		(start 26.794206 -42.2021)
		(end 27.8892 -43.297094)
		(width 0.1143)
		(layer "In7.Cu")
		(net "P2E_CPU_NGFF_C_TX_DN12")
	)
	(segment
		(start 38.9763 -44.283884)
		(end 38.9763 -40.2463)
		(width 0.1143)
		(layer "In7.Cu")
		(net "P2E_CPU_NGFF_C_TX_DN12")
	)
	(segment
		(start 25.625044 -43.2562)
		(end 25.409906 -43.2562)
		(width 0.1143)
		(layer "In7.Cu")
		(net "P2E_CPU_NGFF_C_TX_DN12")
	)
	(segment
		(start 90.2716 -52.7812)
		(end 89.789 -52.2986)
		(width 0.1016)
		(layer "In7.Cu")
		(net "P2E_CPU_NGFF_C_TX_DN12")
	)
	(segment
		(start 55.64632 -46.461426)
		(end 55.646066 -46.46168)
		(width 0.1143)
		(layer "In7.Cu")
		(net "P2E_CPU_NGFF_C_TX_DN12")
	)
	(segment
		(start 57.3532 -48.142906)
		(end 56.931306 -48.5648)
		(width 0.1143)
		(layer "In7.Cu")
		(net "P2E_CPU_NGFF_C_TX_DN12")
	)
	(segment
		(start 57.3532 -47.253906)
		(end 57.3532 -48.142906)
		(width 0.1143)
		(layer "In7.Cu")
		(net "P2E_CPU_NGFF_C_TX_DN12")
	)
	(segment
		(start 25.1587 -44.142406)
		(end 23.276306 -46.0248)
		(width 0.1143)
		(layer "In7.Cu")
		(net "P2E_CPU_NGFF_C_TX_DN12")
	)
	(segment
		(start 41.817544 -44.95165)
		(end 41.3258 -44.459906)
		(width 0.1143)
		(layer "In7.Cu")
		(net "P2E_CPU_NGFF_C_TX_DN12")
	)
	(segment
		(start 90.86977 -53.7972)
		(end 90.551 -53.7972)
		(width 0.1016)
		(layer "In7.Cu")
		(net "P2E_CPU_NGFF_C_TX_DN12")
	)
	(segment
		(start 40.5892 -44.7548)
		(end 40.259 -45.085)
		(width 0.1143)
		(layer "In7.Cu")
		(net "P2E_CPU_NGFF_C_TX_DN12")
	)
	(segment
		(start 89.789 -52.2986)
		(end 86.012528 -52.2986)
		(width 0.1016)
		(layer "In7.Cu")
		(net "P2E_CPU_NGFF_C_TX_DN12")
	)
	(segment
		(start 86.012528 -52.2986)
		(end 85.758528 -52.5526)
		(width 0.1016)
		(layer "In7.Cu")
		(net "P2E_CPU_NGFF_C_TX_DN12")
	)
	(segment
		(start 53.2638 -45.7962)
		(end 49.2125 -45.7962)
		(width 0.1143)
		(layer "In7.Cu")
		(net "P2E_CPU_NGFF_C_TX_DN12")
	)
	(segment
		(start 31.369 -40.091106)
		(end 31.369 -40.779446)
		(width 0.1143)
		(layer "In7.Cu")
		(net "P2E_CPU_NGFF_C_TX_DN12")
	)
	(segment
		(start 40.5892 -43.443906)
		(end 40.5892 -44.7548)
		(width 0.1143)
		(layer "In7.Cu")
		(net "P2E_CPU_NGFF_C_TX_DN12")
	)
	(segment
		(start 82.83575 -52.45735)
		(end 81.15935 -52.45735)
		(width 0.1143)
		(layer "In7.Cu")
		(net "P2E_CPU_NGFF_C_TX_DN12")
	)
	(segment
		(start 55.646066 -46.46168)
		(end 55.224426 -46.46168)
		(width 0.1143)
		(layer "In7.Cu")
		(net "P2E_CPU_NGFF_C_TX_DN12")
	)
	(segment
		(start 46.101 -45.0342)
		(end 45.847 -45.0342)
		(width 0.1143)
		(layer "In7.Cu")
		(net "P2E_CPU_NGFF_C_TX_DN12")
	)
	(segment
		(start 25.1587 -43.507406)
		(end 25.1587 -44.142406)
		(width 0.1143)
		(layer "In7.Cu")
		(net "P2E_CPU_NGFF_C_TX_DN12")
	)
	(segment
		(start 55.6768 -48.2092)
		(end 55.6768 -47.361094)
		(width 0.1143)
		(layer "In7.Cu")
		(net "P2E_CPU_NGFF_C_TX_DN12")
	)
	(segment
		(start 77.978 -51.181)
		(end 76.367894 -51.181)
		(width 0.1143)
		(layer "In7.Cu")
		(net "P2E_CPU_NGFF_C_TX_DN12")
	)
	(segment
		(start 45.18787 -46.228)
		(end 44.323 -46.228)
		(width 0.1143)
		(layer "In7.Cu")
		(net "P2E_CPU_NGFF_C_TX_DN12")
	)
	(segment
		(start 26.787094 -44.41825)
		(end 25.625044 -43.2562)
		(width 0.1143)
		(layer "In7.Cu")
		(net "P2E_CPU_NGFF_C_TX_DN12")
	)
	(segment
		(start 80.8736 -52.1716)
		(end 78.9686 -52.1716)
		(width 0.1143)
		(layer "In7.Cu")
		(net "P2E_CPU_NGFF_C_TX_DN12")
	)
	(segment
		(start 45.6692 -45.212)
		(end 45.6692 -45.74667)
		(width 0.1143)
		(layer "In7.Cu")
		(net "P2E_CPU_NGFF_C_TX_DN12")
	)
	(segment
		(start 38.481 -39.751)
		(end 31.709106 -39.751)
		(width 0.1143)
		(layer "In7.Cu")
		(net "P2E_CPU_NGFF_C_TX_DN12")
	)
	(segment
		(start 27.8892 -43.297094)
		(end 27.8892 -44.078906)
		(width 0.1143)
		(layer "In7.Cu")
		(net "P2E_CPU_NGFF_C_TX_DN12")
	)
	(segment
		(start 55.9308 -47.107094)
		(end 55.9308 -46.745906)
		(width 0.1143)
		(layer "In7.Cu")
		(net "P2E_CPU_NGFF_C_TX_DN12")
	)
	(segment
		(start 25.409906 -43.2562)
		(end 25.1587 -43.507406)
		(width 0.1143)
		(layer "In7.Cu")
		(net "P2E_CPU_NGFF_C_TX_DN12")
	)
	(segment
		(start 49.2125 -45.7962)
		(end 48.6664 -45.2501)
		(width 0.1143)
		(layer "In7.Cu")
		(net "P2E_CPU_NGFF_C_TX_DN12")
	)
	(segment
		(start 60.081922 -49.4284)
		(end 57.719722 -47.0662)
		(width 0.1143)
		(layer "In7.Cu")
		(net "P2E_CPU_NGFF_C_TX_DN12")
	)
	(segment
		(start 56.931306 -48.5648)
		(end 56.0324 -48.5648)
		(width 0.1143)
		(layer "In7.Cu")
		(net "P2E_CPU_NGFF_C_TX_DN12")
	)
	(segment
		(start 30.543246 -41.6052)
		(end 29.981906 -41.6052)
		(width 0.1143)
		(layer "In7.Cu")
		(net "P2E_CPU_NGFF_C_TX_DN12")
	)
	(segment
		(start 76.367894 -51.181)
		(end 75.671934 -50.48504)
		(width 0.1143)
		(layer "In7.Cu")
		(net "P2E_CPU_NGFF_C_TX_DN12")
	)
	(segment
		(start 54.18582 -46.71822)
		(end 53.2638 -45.7962)
		(width 0.1143)
		(layer "In7.Cu")
		(net "P2E_CPU_NGFF_C_TX_DN12")
	)
	(segment
		(start 75.671934 -50.48504)
		(end 64.135254 -50.48504)
		(width 0.1143)
		(layer "In7.Cu")
		(net "P2E_CPU_NGFF_C_TX_DN12")
	)
	(segment
		(start 29.69387 -41.893236)
		(end 29.69387 -42.454576)
		(width 0.1143)
		(layer "In7.Cu")
		(net "P2E_CPU_NGFF_C_TX_DN12")
	)
	(segment
		(start 46.4058 -45.983906)
		(end 46.4058 -45.339)
		(width 0.1143)
		(layer "In7.Cu")
		(net "P2E_CPU_NGFF_C_TX_DN12")
	)
	(segment
		(start 41.3258 -44.459906)
		(end 41.3258 -43.316906)
		(width 0.1143)
		(layer "In7.Cu")
		(net "P2E_CPU_NGFF_C_TX_DN12")
	)
	(segment
		(start 31.369 -40.779446)
		(end 30.543246 -41.6052)
		(width 0.1143)
		(layer "In7.Cu")
		(net "P2E_CPU_NGFF_C_TX_DN12")
	)
	(segment
		(start 57.540906 -47.0662)
		(end 57.3532 -47.253906)
		(width 0.1143)
		(layer "In7.Cu")
		(net "P2E_CPU_NGFF_C_TX_DN12")
	)
	(segment
		(start 47.752 -45.856906)
		(end 47.317406 -46.2915)
		(width 0.1143)
		(layer "In7.Cu")
		(net "P2E_CPU_NGFF_C_TX_DN12")
	)
	(segment
		(start 23.276306 -46.0248)
		(end 20.030694 -46.0248)
		(width 0.1143)
		(layer "In7.Cu")
		(net "P2E_CPU_NGFF_C_TX_DN12")
	)
	(segment
		(start 82.86115 -52.45735)
		(end 82.83575 -52.45735)
		(width 0.1016)
		(layer "In7.Cu")
		(net "P2E_CPU_NGFF_C_TX_DN12")
	)
	(segment
		(start 55.6768 -47.361094)
		(end 55.9308 -47.107094)
		(width 0.1143)
		(layer "In7.Cu")
		(net "P2E_CPU_NGFF_C_TX_DN12")
	)
	(segment
		(start 27.118056 -41.454832)
		(end 26.95702 -41.454832)
		(width 0.1143)
		(layer "In7.Cu")
		(net "P2E_CPU_NGFF_C_TX_DN12")
	)
	(segment
		(start 47.317406 -46.2915)
		(end 46.713394 -46.2915)
		(width 0.1143)
		(layer "In7.Cu")
		(net "P2E_CPU_NGFF_C_TX_DN12")
	)
	(segment
		(start 4.755896 -63.871348)
		(end 2.23774 -63.871348)
		(width 0.1397)
		(layer "F.Cu")
		(net "P2E_CPU_NGFF_C_RX_DN14")
	)
	(segment
		(start 2.23774 -63.871348)
		(end 1.9304 -64.178688)
		(width 0.1397)
		(layer "F.Cu")
		(net "P2E_CPU_NGFF_C_RX_DN14")
	)
	(segment
		(start 7.77875 -61.57595)
		(end 7.051294 -61.57595)
		(width 0.1397)
		(layer "F.Cu")
		(net "P2E_CPU_NGFF_C_RX_DN14")
	)
	(segment
		(start 8.0518 -61.849)
		(end 7.77875 -61.57595)
		(width 0.1397)
		(layer "F.Cu")
		(net "P2E_CPU_NGFF_C_RX_DN14")
	)
	(segment
		(start 7.051294 -61.57595)
		(end 4.755896 -63.871348)
		(width 0.1397)
		(layer "F.Cu")
		(net "P2E_CPU_NGFF_C_RX_DN14")
	)
	(via
		(at 1.9304 -64.178688)
		(size 0.508)
		(drill 0.254)
		(layers "F.Cu" "B.Cu")
		(net "P2E_CPU_NGFF_C_RX_DN14")
	)
	(segment
		(start 5.575046 -63.949834)
		(end 4.583176 -63.949834)
		(width 0.1397)
		(layer "B.Cu")
		(net "P2E_CPU_NGFF_C_RX_DN14")
	)
	(segment
		(start 4.583176 -63.949834)
		(end 4.50469 -63.871348)
		(width 0.1397)
		(layer "B.Cu")
		(net "P2E_CPU_NGFF_C_RX_DN14")
	)
	(segment
		(start 2.23774 -63.871348)
		(end 1.9304 -64.178688)
		(width 0.1397)
		(layer "B.Cu")
		(net "P2E_CPU_NGFF_C_RX_DN14")
	)
	(segment
		(start 4.50469 -63.871348)
		(end 2.23774 -63.871348)
		(width 0.1397)
		(layer "B.Cu")
		(net "P2E_CPU_NGFF_C_RX_DN14")
	)
	(segment
		(start 6.909054 -61.23305)
		(end 4.613656 -63.528448)
		(width 0.1397)
		(layer "F.Cu")
		(net "P2E_CPU_NGFF_C_RX_DP14")
	)
	(segment
		(start 8.0518 -60.96)
		(end 7.77875 -61.23305)
		(width 0.1397)
		(layer "F.Cu")
		(net "P2E_CPU_NGFF_C_RX_DP14")
	)
	(segment
		(start 2.23774 -63.528448)
		(end 1.9304 -63.221108)
		(width 0.1397)
		(layer "F.Cu")
		(net "P2E_CPU_NGFF_C_RX_DP14")
	)
	(segment
		(start 7.77875 -61.23305)
		(end 6.909054 -61.23305)
		(width 0.1397)
		(layer "F.Cu")
		(net "P2E_CPU_NGFF_C_RX_DP14")
	)
	(segment
		(start 4.613656 -63.528448)
		(end 2.23774 -63.528448)
		(width 0.1397)
		(layer "F.Cu")
		(net "P2E_CPU_NGFF_C_RX_DP14")
	)
	(via
		(at 1.9304 -63.221108)
		(size 0.508)
		(drill 0.254)
		(layers "F.Cu" "B.Cu")
		(net "P2E_CPU_NGFF_C_RX_DP14")
	)
	(segment
		(start 2.23774 -63.528448)
		(end 1.9304 -63.221108)
		(width 0.1397)
		(layer "B.Cu")
		(net "P2E_CPU_NGFF_C_RX_DP14")
	)
	(segment
		(start 4.50469 -63.528448)
		(end 2.23774 -63.528448)
		(width 0.1397)
		(layer "B.Cu")
		(net "P2E_CPU_NGFF_C_RX_DP14")
	)
	(segment
		(start 5.575046 -63.449962)
		(end 4.583176 -63.449962)
		(width 0.1397)
		(layer "B.Cu")
		(net "P2E_CPU_NGFF_C_RX_DP14")
	)
	(segment
		(start 4.583176 -63.449962)
		(end 4.50469 -63.528448)
		(width 0.1397)
		(layer "B.Cu")
		(net "P2E_CPU_NGFF_C_RX_DP14")
	)
	(segment
		(start 8.0518 -64.516)
		(end 7.77875 -64.78905)
		(width 0.1397)
		(layer "F.Cu")
		(net "P2E_CPU_NGFF_C_RX_DP15")
	)
	(segment
		(start 7.77875 -64.78905)
		(end 6.32841 -64.78905)
		(width 0.1397)
		(layer "F.Cu")
		(net "P2E_CPU_NGFF_C_RX_DP15")
	)
	(segment
		(start 6.32841 -64.78905)
		(end 4.589018 -66.528442)
		(width 0.1397)
		(layer "F.Cu")
		(net "P2E_CPU_NGFF_C_RX_DP15")
	)
	(segment
		(start 4.589018 -66.528442)
		(end 2.23774 -66.528442)
		(width 0.1397)
		(layer "F.Cu")
		(net "P2E_CPU_NGFF_C_RX_DP15")
	)
	(segment
		(start 2.23774 -66.528442)
		(end 1.9304 -66.221102)
		(width 0.1397)
		(layer "F.Cu")
		(net "P2E_CPU_NGFF_C_RX_DP15")
	)
	(via
		(at 1.9304 -66.221102)
		(size 0.508)
		(drill 0.254)
		(layers "F.Cu" "B.Cu")
		(net "P2E_CPU_NGFF_C_RX_DP15")
	)
	(segment
		(start 5.575046 -66.449956)
		(end 4.583176 -66.449956)
		(width 0.1397)
		(layer "B.Cu")
		(net "P2E_CPU_NGFF_C_RX_DP15")
	)
	(segment
		(start 2.23774 -66.528442)
		(end 1.9304 -66.221102)
		(width 0.1397)
		(layer "B.Cu")
		(net "P2E_CPU_NGFF_C_RX_DP15")
	)
	(segment
		(start 4.583176 -66.449956)
		(end 4.50469 -66.528442)
		(width 0.1397)
		(layer "B.Cu")
		(net "P2E_CPU_NGFF_C_RX_DP15")
	)
	(segment
		(start 4.50469 -66.528442)
		(end 2.23774 -66.528442)
		(width 0.1397)
		(layer "B.Cu")
		(net "P2E_CPU_NGFF_C_RX_DP15")
	)
	(segment
		(start 2.23774 -60.528454)
		(end 1.9304 -60.221114)
		(width 0.1397)
		(layer "F.Cu")
		(net "P2E_CPU_NGFF_C_RX_DP13")
	)
	(segment
		(start 7.77875 -57.67705)
		(end 7.09295 -57.67705)
		(width 0.1397)
		(layer "F.Cu")
		(net "P2E_CPU_NGFF_C_RX_DP13")
	)
	(segment
		(start 7.09295 -57.67705)
		(end 4.241546 -60.528454)
		(width 0.1397)
		(layer "F.Cu")
		(net "P2E_CPU_NGFF_C_RX_DP13")
	)
	(segment
		(start 4.241546 -60.528454)
		(end 2.23774 -60.528454)
		(width 0.1397)
		(layer "F.Cu")
		(net "P2E_CPU_NGFF_C_RX_DP13")
	)
	(segment
		(start 8.0518 -57.404)
		(end 7.77875 -57.67705)
		(width 0.1397)
		(layer "F.Cu")
		(net "P2E_CPU_NGFF_C_RX_DP13")
	)
	(via
		(at 1.9304 -60.221114)
		(size 0.508)
		(drill 0.254)
		(layers "F.Cu" "B.Cu")
		(net "P2E_CPU_NGFF_C_RX_DP13")
	)
	(segment
		(start 4.583176 -60.449968)
		(end 4.50469 -60.528454)
		(width 0.1397)
		(layer "B.Cu")
		(net "P2E_CPU_NGFF_C_RX_DP13")
	)
	(segment
		(start 5.575046 -60.449968)
		(end 4.583176 -60.449968)
		(width 0.1397)
		(layer "B.Cu")
		(net "P2E_CPU_NGFF_C_RX_DP13")
	)
	(segment
		(start 2.23774 -60.528454)
		(end 1.9304 -60.221114)
		(width 0.1397)
		(layer "B.Cu")
		(net "P2E_CPU_NGFF_C_RX_DP13")
	)
	(segment
		(start 4.50469 -60.528454)
		(end 2.23774 -60.528454)
		(width 0.1397)
		(layer "B.Cu")
		(net "P2E_CPU_NGFF_C_RX_DP13")
	)
	(segment
		(start 4.383786 -60.871354)
		(end 2.23774 -60.871354)
		(width 0.1397)
		(layer "F.Cu")
		(net "P2E_CPU_NGFF_C_RX_DN13")
	)
	(segment
		(start 7.77875 -58.01995)
		(end 7.23519 -58.01995)
		(width 0.1397)
		(layer "F.Cu")
		(net "P2E_CPU_NGFF_C_RX_DN13")
	)
	(segment
		(start 2.23774 -60.871354)
		(end 1.9304 -61.178694)
		(width 0.1397)
		(layer "F.Cu")
		(net "P2E_CPU_NGFF_C_RX_DN13")
	)
	(segment
		(start 8.0518 -58.293)
		(end 7.77875 -58.01995)
		(width 0.1397)
		(layer "F.Cu")
		(net "P2E_CPU_NGFF_C_RX_DN13")
	)
	(segment
		(start 7.23519 -58.01995)
		(end 4.383786 -60.871354)
		(width 0.1397)
		(layer "F.Cu")
		(net "P2E_CPU_NGFF_C_RX_DN13")
	)
	(via
		(at 1.9304 -61.178694)
		(size 0.508)
		(drill 0.254)
		(layers "F.Cu" "B.Cu")
		(net "P2E_CPU_NGFF_C_RX_DN13")
	)
	(segment
		(start 4.583176 -60.94984)
		(end 4.50469 -60.871354)
		(width 0.1397)
		(layer "B.Cu")
		(net "P2E_CPU_NGFF_C_RX_DN13")
	)
	(segment
		(start 5.575046 -60.94984)
		(end 4.583176 -60.94984)
		(width 0.1397)
		(layer "B.Cu")
		(net "P2E_CPU_NGFF_C_RX_DN13")
	)
	(segment
		(start 2.23774 -60.871354)
		(end 1.9304 -61.178694)
		(width 0.1397)
		(layer "B.Cu")
		(net "P2E_CPU_NGFF_C_RX_DN13")
	)
	(segment
		(start 4.50469 -60.871354)
		(end 2.23774 -60.871354)
		(width 0.1397)
		(layer "B.Cu")
		(net "P2E_CPU_NGFF_C_RX_DN13")
	)
	(segment
		(start 7.77875 -65.13195)
		(end 6.47065 -65.13195)
		(width 0.1397)
		(layer "F.Cu")
		(net "P2E_CPU_NGFF_C_RX_DN15")
	)
	(segment
		(start 6.47065 -65.13195)
		(end 4.731258 -66.871342)
		(width 0.1397)
		(layer "F.Cu")
		(net "P2E_CPU_NGFF_C_RX_DN15")
	)
	(segment
		(start 8.0518 -65.405)
		(end 7.77875 -65.13195)
		(width 0.1397)
		(layer "F.Cu")
		(net "P2E_CPU_NGFF_C_RX_DN15")
	)
	(segment
		(start 4.731258 -66.871342)
		(end 2.23774 -66.871342)
		(width 0.1397)
		(layer "F.Cu")
		(net "P2E_CPU_NGFF_C_RX_DN15")
	)
	(segment
		(start 2.23774 -66.871342)
		(end 1.9304 -67.178682)
		(width 0.1397)
		(layer "F.Cu")
		(net "P2E_CPU_NGFF_C_RX_DN15")
	)
	(via
		(at 1.9304 -67.178682)
		(size 0.508)
		(drill 0.254)
		(layers "F.Cu" "B.Cu")
		(net "P2E_CPU_NGFF_C_RX_DN15")
	)
	(segment
		(start 4.583176 -66.949828)
		(end 4.50469 -66.871342)
		(width 0.1397)
		(layer "B.Cu")
		(net "P2E_CPU_NGFF_C_RX_DN15")
	)
	(segment
		(start 5.575046 -66.949828)
		(end 4.583176 -66.949828)
		(width 0.1397)
		(layer "B.Cu")
		(net "P2E_CPU_NGFF_C_RX_DN15")
	)
	(segment
		(start 4.50469 -66.871342)
		(end 2.23774 -66.871342)
		(width 0.1397)
		(layer "B.Cu")
		(net "P2E_CPU_NGFF_C_RX_DN15")
	)
	(segment
		(start 2.23774 -66.871342)
		(end 1.9304 -67.178682)
		(width 0.1397)
		(layer "B.Cu")
		(net "P2E_CPU_NGFF_C_RX_DN15")
	)
	(segment
		(start 11.684 -53.8226)
		(end 11.43635 -53.57495)
		(width 0.1397)
		(layer "F.Cu")
		(net "P2E_CPU_NGFF_C_RX_DN12")
	)
	(segment
		(start 11.684 -54.0258)
		(end 11.684 -53.8226)
		(width 0.1397)
		(layer "F.Cu")
		(net "P2E_CPU_NGFF_C_RX_DN12")
	)
	(segment
		(start 11.43635 -53.57495)
		(end 9.16305 -53.57495)
		(width 0.1397)
		(layer "F.Cu")
		(net "P2E_CPU_NGFF_C_RX_DN12")
	)
	(segment
		(start 9.16305 -53.57495)
		(end 8.8392 -53.8988)
		(width 0.1397)
		(layer "F.Cu")
		(net "P2E_CPU_NGFF_C_RX_DN12")
	)
	(via
		(at 8.8392 -53.8988)
		(size 0.508)
		(drill 0.254)
		(layers "F.Cu" "B.Cu")
		(net "P2E_CPU_NGFF_C_RX_DN12")
	)
	(segment
		(start 8.2169 -56.50484)
		(end 6.85038 -57.87136)
		(width 0.1397)
		(layer "B.Cu")
		(net "P2E_CPU_NGFF_C_RX_DN12")
	)
	(segment
		(start 8.3693 -53.594)
		(end 8.2169 -53.7464)
		(width 0.1397)
		(layer "B.Cu")
		(net "P2E_CPU_NGFF_C_RX_DN12")
	)
	(segment
		(start 8.5344 -53.594)
		(end 8.3693 -53.594)
		(width 0.1397)
		(layer "B.Cu")
		(net "P2E_CPU_NGFF_C_RX_DN12")
	)
	(segment
		(start 6.85038 -57.87136)
		(end 6.31444 -57.87136)
		(width 0.1397)
		(layer "B.Cu")
		(net "P2E_CPU_NGFF_C_RX_DN12")
	)
	(segment
		(start 6.31444 -57.87136)
		(end 6.235954 -57.949846)
		(width 0.1397)
		(layer "B.Cu")
		(net "P2E_CPU_NGFF_C_RX_DN12")
	)
	(segment
		(start 6.235954 -57.949846)
		(end 5.575046 -57.949846)
		(width 0.1397)
		(layer "B.Cu")
		(net "P2E_CPU_NGFF_C_RX_DN12")
	)
	(segment
		(start 8.2169 -53.7464)
		(end 8.2169 -56.50484)
		(width 0.1397)
		(layer "B.Cu")
		(net "P2E_CPU_NGFF_C_RX_DN12")
	)
	(segment
		(start 8.8392 -53.8988)
		(end 8.5344 -53.594)
		(width 0.1397)
		(layer "B.Cu")
		(net "P2E_CPU_NGFF_C_RX_DN12")
	)
	(segment
		(start 11.38555 -53.23205)
		(end 9.16305 -53.23205)
		(width 0.1397)
		(layer "F.Cu")
		(net "P2E_CPU_NGFF_C_RX_DP12")
	)
	(segment
		(start 9.16305 -53.23205)
		(end 8.8392 -52.9082)
		(width 0.1397)
		(layer "F.Cu")
		(net "P2E_CPU_NGFF_C_RX_DP12")
	)
	(segment
		(start 11.684 -52.7812)
		(end 11.684 -52.9336)
		(width 0.1397)
		(layer "F.Cu")
		(net "P2E_CPU_NGFF_C_RX_DP12")
	)
	(segment
		(start 11.684 -52.9336)
		(end 11.38555 -53.23205)
		(width 0.1397)
		(layer "F.Cu")
		(net "P2E_CPU_NGFF_C_RX_DP12")
	)
	(via
		(at 8.8392 -52.9082)
		(size 0.508)
		(drill 0.254)
		(layers "F.Cu" "B.Cu")
		(net "P2E_CPU_NGFF_C_RX_DP12")
	)
	(segment
		(start 8.8392 -52.9082)
		(end 8.4963 -53.2511)
		(width 0.1397)
		(layer "B.Cu")
		(net "P2E_CPU_NGFF_C_RX_DP12")
	)
	(segment
		(start 6.294374 -57.449974)
		(end 5.575046 -57.449974)
		(width 0.1397)
		(layer "B.Cu")
		(net "P2E_CPU_NGFF_C_RX_DP12")
	)
	(segment
		(start 6.37286 -57.52846)
		(end 6.294374 -57.449974)
		(width 0.1397)
		(layer "B.Cu")
		(net "P2E_CPU_NGFF_C_RX_DP12")
	)
	(segment
		(start 8.4963 -53.2511)
		(end 8.22706 -53.2511)
		(width 0.1397)
		(layer "B.Cu")
		(net "P2E_CPU_NGFF_C_RX_DP12")
	)
	(segment
		(start 7.874 -56.3626)
		(end 6.70814 -57.52846)
		(width 0.1397)
		(layer "B.Cu")
		(net "P2E_CPU_NGFF_C_RX_DP12")
	)
	(segment
		(start 6.70814 -57.52846)
		(end 6.37286 -57.52846)
		(width 0.1397)
		(layer "B.Cu")
		(net "P2E_CPU_NGFF_C_RX_DP12")
	)
	(segment
		(start 8.22706 -53.2511)
		(end 7.874 -53.60416)
		(width 0.1397)
		(layer "B.Cu")
		(net "P2E_CPU_NGFF_C_RX_DP12")
	)
	(segment
		(start 7.874 -53.60416)
		(end 7.874 -56.3626)
		(width 0.1397)
		(layer "B.Cu")
		(net "P2E_CPU_NGFF_C_RX_DP12")
	)
	(segment
		(start 87.3252 -32.258)
		(end 87.968074 -32.258)
		(width 0.127)
		(layer "F.Cu")
		(net "NGFF_PRESENT#")
	)
	(segment
		(start 87.968074 -32.258)
		(end 88.374728 -32.664654)
		(width 0.127)
		(layer "F.Cu")
		(net "NGFF_PRESENT#")
	)
	(segment
		(start 87.122 -32.0548)
		(end 87.3252 -32.258)
		(width 0.127)
		(layer "F.Cu")
		(net "NGFF_PRESENT#")
	)
	(via
		(at 87.122 -32.0548)
		(size 0.4318)
		(drill 0.2032)
		(layers "F.Cu" "B.Cu")
		(net "NGFF_PRESENT#")
	)
	(via
		(at 81.915 -29.083)
		(size 0.7112)
		(drill 0.3556)
		(layers "F.Cu" "B.Cu")
		(net "NGFF_PRESENT#")
	)
	(segment
		(start 81.915 -28.26766)
		(end 81.61528 -27.96794)
		(width 0.127)
		(layer "B.Cu")
		(net "NGFF_PRESENT#")
	)
	(segment
		(start 87.017098 -32.0548)
		(end 86.077298 -31.115)
		(width 0.127)
		(layer "B.Cu")
		(net "NGFF_PRESENT#")
	)
	(segment
		(start 87.122 -32.0548)
		(end 87.017098 -32.0548)
		(width 0.127)
		(layer "B.Cu")
		(net "NGFF_PRESENT#")
	)
	(segment
		(start 84.336636 -30.281372)
		(end 83.918806 -29.863542)
		(width 0.127)
		(layer "B.Cu")
		(net "NGFF_PRESENT#")
	)
	(segment
		(start 79.0448 -27.178)
		(end 78.4098 -26.543)
		(width 0.127)
		(layer "B.Cu")
		(net "NGFF_PRESENT#")
	)
	(segment
		(start 81.915 -29.083)
		(end 81.915 -28.26766)
		(width 0.127)
		(layer "B.Cu")
		(net "NGFF_PRESENT#")
	)
	(segment
		(start 80.92694 -27.96794)
		(end 80.137 -27.178)
		(width 0.127)
		(layer "B.Cu")
		(net "NGFF_PRESENT#")
	)
	(segment
		(start 80.137 -27.178)
		(end 79.0448 -27.178)
		(width 0.127)
		(layer "B.Cu")
		(net "NGFF_PRESENT#")
	)
	(segment
		(start 86.077298 -31.115)
		(end 84.703666 -31.115)
		(width 0.127)
		(layer "B.Cu")
		(net "NGFF_PRESENT#")
	)
	(segment
		(start 82.695542 -29.863542)
		(end 81.915 -29.083)
		(width 0.127)
		(layer "B.Cu")
		(net "NGFF_PRESENT#")
	)
	(segment
		(start 81.61528 -27.96794)
		(end 80.92694 -27.96794)
		(width 0.127)
		(layer "B.Cu")
		(net "NGFF_PRESENT#")
	)
	(segment
		(start 83.918806 -29.863542)
		(end 82.695542 -29.863542)
		(width 0.127)
		(layer "B.Cu")
		(net "NGFF_PRESENT#")
	)
	(segment
		(start 84.703666 -31.115)
		(end 84.336636 -30.74797)
		(width 0.127)
		(layer "B.Cu")
		(net "NGFF_PRESENT#")
	)
	(segment
		(start 84.336636 -30.74797)
		(end 84.336636 -30.281372)
		(width 0.127)
		(layer "B.Cu")
		(net "NGFF_PRESENT#")
	)
	(segment
		(start 75.946 -24.2316)
		(end 75.9968 -24.1808)
		(width 0.127)
		(layer "F.Cu")
		(net "NGFF_PRESENT_R#")
	)
	(segment
		(start 75.8952 -24.2316)
		(end 75.946 -24.2316)
		(width 0.127)
		(layer "F.Cu")
		(net "NGFF_PRESENT_R#")
	)
	(segment
		(start 75.9968 -24.1808)
		(end 77.057504 -24.1808)
		(width 0.127)
		(layer "F.Cu")
		(net "NGFF_PRESENT_R#")
	)
	(via
		(at 4.2926 -68.326)
		(size 0.508)
		(drill 0.254)
		(layers "F.Cu" "B.Cu")
		(net "NGFF_PRESENT_R#")
	)
	(via
		(at 75.8952 -24.2316)
		(size 0.7112)
		(drill 0.3556)
		(layers "F.Cu" "B.Cu")
		(net "NGFF_PRESENT_R#")
	)
	(via
		(at 77.057504 -24.1808)
		(size 0.508)
		(drill 0.254)
		(layers "F.Cu" "B.Cu")
		(net "NGFF_PRESENT_R#")
	)
	(segment
		(start 5.575046 -67.949826)
		(end 4.668774 -67.949826)
		(width 0.127)
		(layer "B.Cu")
		(net "NGFF_PRESENT_R#")
	)
	(segment
		(start 78.4098 -25.2222)
		(end 77.47 -24.2824)
		(width 0.127)
		(layer "B.Cu")
		(net "NGFF_PRESENT_R#")
	)
	(segment
		(start 77.159104 -24.2824)
		(end 77.057504 -24.1808)
		(width 0.127)
		(layer "B.Cu")
		(net "NGFF_PRESENT_R#")
	)
	(segment
		(start 77.47 -24.2824)
		(end 77.159104 -24.2824)
		(width 0.127)
		(layer "B.Cu")
		(net "NGFF_PRESENT_R#")
	)
	(segment
		(start 4.668774 -67.949826)
		(end 4.2926 -68.326)
		(width 0.127)
		(layer "B.Cu")
		(net "NGFF_PRESENT_R#")
	)
	(segment
		(start 79.0194 -26.289)
		(end 78.4098 -25.6794)
		(width 0.127)
		(layer "B.Cu")
		(net "NGFF_PRESENT_R#")
	)
	(segment
		(start 79.5782 -26.289)
		(end 79.0194 -26.289)
		(width 0.127)
		(layer "B.Cu")
		(net "NGFF_PRESENT_R#")
	)
	(segment
		(start 78.4098 -25.6794)
		(end 78.4098 -25.2222)
		(width 0.127)
		(layer "B.Cu")
		(net "NGFF_PRESENT_R#")
	)
	(segment
		(start 55.27421 -22.947884)
		(end 59.890152 -22.947884)
		(width 0.127)
		(layer "In4.Cu")
		(net "NGFF_PRESENT_R#")
	)
	(segment
		(start 63.015368 -22.8727)
		(end 63.993268 -21.8948)
		(width 0.127)
		(layer "In4.Cu")
		(net "NGFF_PRESENT_R#")
	)
	(segment
		(start 40.075104 -30.988)
		(end 42.164 -28.899104)
		(width 0.127)
		(layer "In4.Cu")
		(net "NGFF_PRESENT_R#")
	)
	(segment
		(start 60.653168 -22.9743)
		(end 60.754768 -22.8727)
		(width 0.127)
		(layer "In4.Cu")
		(net "NGFF_PRESENT_R#")
	)
	(segment
		(start 31.623 -30.6324)
		(end 32.0167 -30.2387)
		(width 0.127)
		(layer "In4.Cu")
		(net "NGFF_PRESENT_R#")
	)
	(segment
		(start 38.464998 -31.5341)
		(end 39.011098 -30.988)
		(width 0.127)
		(layer "In4.Cu")
		(net "NGFF_PRESENT_R#")
	)
	(segment
		(start 37.3253 -31.5341)
		(end 38.464998 -31.5341)
		(width 0.127)
		(layer "In4.Cu")
		(net "NGFF_PRESENT_R#")
	)
	(segment
		(start 59.916568 -22.9743)
		(end 60.653168 -22.9743)
		(width 0.127)
		(layer "In4.Cu")
		(net "NGFF_PRESENT_R#")
	)
	(segment
		(start 45.067982 -22.8473)
		(end 49.7713 -22.8473)
		(width 0.127)
		(layer "In4.Cu")
		(net "NGFF_PRESENT_R#")
	)
	(segment
		(start 4.7879 -42.4561)
		(end 4.7879 -36.711382)
		(width 0.127)
		(layer "In4.Cu")
		(net "NGFF_PRESENT_R#")
	)
	(segment
		(start 42.164 -28.899104)
		(end 42.164 -25.751282)
		(width 0.127)
		(layer "In4.Cu")
		(net "NGFF_PRESENT_R#")
	)
	(segment
		(start 7.425182 -34.0741)
		(end 19.9517 -34.0741)
		(width 0.127)
		(layer "In4.Cu")
		(net "NGFF_PRESENT_R#")
	)
	(segment
		(start 4.2926 -68.326)
		(end 4.762246 -67.856354)
		(width 0.127)
		(layer "In4.Cu")
		(net "NGFF_PRESENT_R#")
	)
	(segment
		(start 4.762246 -56.870346)
		(end 2.794 -54.9021)
		(width 0.127)
		(layer "In4.Cu")
		(net "NGFF_PRESENT_R#")
	)
	(segment
		(start 19.9517 -34.0741)
		(end 23.3934 -30.6324)
		(width 0.127)
		(layer "In4.Cu")
		(net "NGFF_PRESENT_R#")
	)
	(segment
		(start 23.3934 -30.6324)
		(end 31.623 -30.6324)
		(width 0.127)
		(layer "In4.Cu")
		(net "NGFF_PRESENT_R#")
	)
	(segment
		(start 63.993268 -21.8948)
		(end 75.3618 -21.8948)
		(width 0.127)
		(layer "In4.Cu")
		(net "NGFF_PRESENT_R#")
	)
	(segment
		(start 2.794 -54.9021)
		(end 2.794 -44.45)
		(width 0.127)
		(layer "In4.Cu")
		(net "NGFF_PRESENT_R#")
	)
	(segment
		(start 4.762246 -67.856354)
		(end 4.762246 -56.870346)
		(width 0.127)
		(layer "In4.Cu")
		(net "NGFF_PRESENT_R#")
	)
	(segment
		(start 60.754768 -22.8727)
		(end 63.015368 -22.8727)
		(width 0.127)
		(layer "In4.Cu")
		(net "NGFF_PRESENT_R#")
	)
	(segment
		(start 59.890152 -22.947884)
		(end 59.916568 -22.9743)
		(width 0.127)
		(layer "In4.Cu")
		(net "NGFF_PRESENT_R#")
	)
	(segment
		(start 50.2285 -23.3045)
		(end 54.917594 -23.3045)
		(width 0.127)
		(layer "In4.Cu")
		(net "NGFF_PRESENT_R#")
	)
	(segment
		(start 49.7713 -22.8473)
		(end 50.2285 -23.3045)
		(width 0.127)
		(layer "In4.Cu")
		(net "NGFF_PRESENT_R#")
	)
	(segment
		(start 76.1492 -22.6822)
		(end 76.1492 -23.833836)
		(width 0.127)
		(layer "In4.Cu")
		(net "NGFF_PRESENT_R#")
	)
	(segment
		(start 39.011098 -30.988)
		(end 40.075104 -30.988)
		(width 0.127)
		(layer "In4.Cu")
		(net "NGFF_PRESENT_R#")
	)
	(segment
		(start 32.0167 -30.2387)
		(end 36.0299 -30.2387)
		(width 0.127)
		(layer "In4.Cu")
		(net "NGFF_PRESENT_R#")
	)
	(segment
		(start 76.1492 -23.833836)
		(end 76.496164 -24.1808)
		(width 0.127)
		(layer "In4.Cu")
		(net "NGFF_PRESENT_R#")
	)
	(segment
		(start 42.164 -25.751282)
		(end 45.067982 -22.8473)
		(width 0.127)
		(layer "In4.Cu")
		(net "NGFF_PRESENT_R#")
	)
	(segment
		(start 76.496164 -24.1808)
		(end 77.057504 -24.1808)
		(width 0.127)
		(layer "In4.Cu")
		(net "NGFF_PRESENT_R#")
	)
	(segment
		(start 75.3618 -21.8948)
		(end 76.1492 -22.6822)
		(width 0.127)
		(layer "In4.Cu")
		(net "NGFF_PRESENT_R#")
	)
	(segment
		(start 2.794 -44.45)
		(end 4.7879 -42.4561)
		(width 0.127)
		(layer "In4.Cu")
		(net "NGFF_PRESENT_R#")
	)
	(segment
		(start 4.7879 -36.711382)
		(end 7.425182 -34.0741)
		(width 0.127)
		(layer "In4.Cu")
		(net "NGFF_PRESENT_R#")
	)
	(segment
		(start 36.0299 -30.2387)
		(end 37.3253 -31.5341)
		(width 0.127)
		(layer "In4.Cu")
		(net "NGFF_PRESENT_R#")
	)
	(segment
		(start 54.917594 -23.3045)
		(end 55.27421 -22.947884)
		(width 0.127)
		(layer "In4.Cu")
		(net "NGFF_PRESENT_R#")
	)
	(segment
		(start 67.2846 -21.5138)
		(end 67.818 -21.5138)
		(width 0.127)
		(layer "F.Cu")
		(net "MSATA_PRESENT_R#")
	)
	(segment
		(start 65.9765 -20.2057)
		(end 67.2846 -21.5138)
		(width 0.127)
		(layer "F.Cu")
		(net "MSATA_PRESENT_R#")
	)
	(segment
		(start 65.532 -20.2057)
		(end 65.9765 -20.2057)
		(width 0.127)
		(layer "F.Cu")
		(net "MSATA_PRESENT_R#")
	)
	(segment
		(start 62.6364 -19.0627)
		(end 63.7794 -20.2057)
		(width 0.127)
		(layer "F.Cu")
		(net "MSATA_PRESENT_R#")
	)
	(segment
		(start 63.7794 -20.2057)
		(end 65.532 -20.2057)
		(width 0.127)
		(layer "F.Cu")
		(net "MSATA_PRESENT_R#")
	)
	(segment
		(start 67.818 -21.5138)
		(end 68.58 -21.5138)
		(width 0.127)
		(layer "F.Cu")
		(net "MSATA_PRESENT_R#")
	)
	(segment
		(start 62.6364 -18.7198)
		(end 62.6364 -19.0627)
		(width 0.127)
		(layer "F.Cu")
		(net "MSATA_PRESENT_R#")
	)
	(via
		(at 62.6364 -18.7198)
		(size 0.508)
		(drill 0.254)
		(layers "F.Cu" "B.Cu")
		(net "MSATA_PRESENT_R#")
	)
	(via
		(at 65.532 -20.2057)
		(size 0.7112)
		(drill 0.3556)
		(layers "F.Cu" "B.Cu")
		(net "MSATA_PRESENT_R#")
	)
	(segment
		(start 63.225934 -20.299934)
		(end 63.946532 -20.299934)
		(width 0.127)
		(layer "B.Cu")
		(net "MSATA_PRESENT_R#")
	)
	(segment
		(start 62.6364 -19.7104)
		(end 63.225934 -20.299934)
		(width 0.127)
		(layer "B.Cu")
		(net "MSATA_PRESENT_R#")
	)
	(segment
		(start 62.6364 -18.7198)
		(end 62.6364 -19.7104)
		(width 0.127)
		(layer "B.Cu")
		(net "MSATA_PRESENT_R#")
	)
	(segment
		(start 56.316118 -11.755882)
		(end 56.316118 -9.346184)
		(width 0.127)
		(layer "F.Cu")
		(net "PCIE_RSVD_A41")
	)
	(segment
		(start 56.316118 -9.346184)
		(end 56.3499 -9.312402)
		(width 0.127)
		(layer "F.Cu")
		(net "PCIE_RSVD_A41")
	)
	(segment
		(start 56.3499 -9.312402)
		(end 56.3499 -6.195568)
		(width 0.127)
		(layer "F.Cu")
		(net "PCIE_RSVD_A41")
	)
	(segment
		(start 55.499 -12.573)
		(end 56.316118 -11.755882)
		(width 0.127)
		(layer "F.Cu")
		(net "PCIE_RSVD_A41")
	)
	(segment
		(start 115.847114 -2.4892)
		(end 114.3508 -2.4892)
		(width 0.1143)
		(layer "F.Cu")
		(net "POWER_GOOD")
	)
	(segment
		(start 128.03124 -12.142978)
		(end 120.009158 -4.120896)
		(width 0.1143)
		(layer "F.Cu")
		(net "POWER_GOOD")
	)
	(segment
		(start 130.096514 -12.142978)
		(end 128.03124 -12.142978)
		(width 0.1143)
		(layer "F.Cu")
		(net "POWER_GOOD")
	)
	(segment
		(start 132.26415 -17.76095)
		(end 132.26415 -14.310614)
		(width 0.1143)
		(layer "F.Cu")
		(net "POWER_GOOD")
	)
	(segment
		(start 132.461 -17.9578)
		(end 132.26415 -17.76095)
		(width 0.1143)
		(layer "F.Cu")
		(net "POWER_GOOD")
	)
	(segment
		(start 132.8166 -18.3134)
		(end 132.461 -17.9578)
		(width 0.1143)
		(layer "F.Cu")
		(net "POWER_GOOD")
	)
	(segment
		(start 120.009158 -4.120896)
		(end 117.47881 -4.120896)
		(width 0.1143)
		(layer "F.Cu")
		(net "POWER_GOOD")
	)
	(segment
		(start 132.26415 -14.310614)
		(end 130.096514 -12.142978)
		(width 0.1143)
		(layer "F.Cu")
		(net "POWER_GOOD")
	)
	(segment
		(start 133.731 -18.9992)
		(end 133.0452 -18.3134)
		(width 0.1143)
		(layer "F.Cu")
		(net "POWER_GOOD")
	)
	(segment
		(start 133.0452 -18.3134)
		(end 132.8166 -18.3134)
		(width 0.1143)
		(layer "F.Cu")
		(net "POWER_GOOD")
	)
	(segment
		(start 117.47881 -4.120896)
		(end 115.847114 -2.4892)
		(width 0.1143)
		(layer "F.Cu")
		(net "POWER_GOOD")
	)
	(via
		(at 132.461 -17.9578)
		(size 0.7112)
		(drill 0.3556)
		(layers "F.Cu" "B.Cu")
		(net "POWER_GOOD")
	)
	(via
		(at 114.3508 -2.4892)
		(size 0.508)
		(drill 0.254)
		(layers "F.Cu" "B.Cu")
		(net "POWER_GOOD")
	)
	(segment
		(start 116.967 -3.79476)
		(end 117.22608 -3.79476)
		(width 0.1143)
		(layer "B.Cu")
		(net "POWER_GOOD")
	)
	(segment
		(start 115.66144 -2.4892)
		(end 116.967 -3.79476)
		(width 0.1143)
		(layer "B.Cu")
		(net "POWER_GOOD")
	)
	(segment
		(start 114.3508 -2.4892)
		(end 115.66144 -2.4892)
		(width 0.1143)
		(layer "B.Cu")
		(net "POWER_GOOD")
	)
	(segment
		(start 65.349882 -5.814568)
		(end 65.349882 -8.447024)
		(width 0.1397)
		(layer "B.Cu")
		(net "SATA2_TX_C_DN0")
	)
	(segment
		(start 65.678558 -8.7757)
		(end 65.678558 -12.129008)
		(width 0.1397)
		(layer "B.Cu")
		(net "SATA2_TX_C_DN0")
	)
	(segment
		(start 65.99555 -12.92225)
		(end 65.786 -13.1318)
		(width 0.1397)
		(layer "B.Cu")
		(net "SATA2_TX_C_DN0")
	)
	(segment
		(start 65.678558 -12.129008)
		(end 65.99555 -12.446)
		(width 0.1397)
		(layer "B.Cu")
		(net "SATA2_TX_C_DN0")
	)
	(segment
		(start 65.349882 -8.447024)
		(end 65.678558 -8.7757)
		(width 0.1397)
		(layer "B.Cu")
		(net "SATA2_TX_C_DN0")
	)
	(segment
		(start 65.99555 -12.446)
		(end 65.99555 -12.92225)
		(width 0.1397)
		(layer "B.Cu")
		(net "SATA2_TX_C_DN0")
	)
	(segment
		(start 66.021458 -11.986768)
		(end 66.33845 -12.30376)
		(width 0.1397)
		(layer "B.Cu")
		(net "SATA2_TX_C_DP0")
	)
	(segment
		(start 66.021458 -8.7757)
		(end 66.021458 -11.986768)
		(width 0.1397)
		(layer "B.Cu")
		(net "SATA2_TX_C_DP0")
	)
	(segment
		(start 66.33845 -12.92225)
		(end 66.548 -13.1318)
		(width 0.1397)
		(layer "B.Cu")
		(net "SATA2_TX_C_DP0")
	)
	(segment
		(start 66.33845 -12.30376)
		(end 66.33845 -12.92225)
		(width 0.1397)
		(layer "B.Cu")
		(net "SATA2_TX_C_DP0")
	)
	(segment
		(start 66.34988 -8.447278)
		(end 66.021458 -8.7757)
		(width 0.1397)
		(layer "B.Cu")
		(net "SATA2_TX_C_DP0")
	)
	(segment
		(start 66.34988 -5.814568)
		(end 66.34988 -8.447278)
		(width 0.1397)
		(layer "B.Cu")
		(net "SATA2_TX_C_DP0")
	)
	(segment
		(start 52.77485 -12.16025)
		(end 52.9844 -12.3698)
		(width 0.1397)
		(layer "F.Cu")
		(net "CPU_GBE_RX_C_DP0")
	)
	(segment
		(start 52.021232 -8.7757)
		(end 52.021232 -10.238232)
		(width 0.1397)
		(layer "F.Cu")
		(net "CPU_GBE_RX_C_DP0")
	)
	(segment
		(start 52.021232 -10.238232)
		(end 52.77485 -10.99185)
		(width 0.1397)
		(layer "F.Cu")
		(net "CPU_GBE_RX_C_DP0")
	)
	(segment
		(start 52.349908 -8.447024)
		(end 52.021232 -8.7757)
		(width 0.1397)
		(layer "F.Cu")
		(net "CPU_GBE_RX_C_DP0")
	)
	(segment
		(start 52.77485 -10.99185)
		(end 52.77485 -12.16025)
		(width 0.1397)
		(layer "F.Cu")
		(net "CPU_GBE_RX_C_DP0")
	)
	(segment
		(start 52.349908 -6.195568)
		(end 52.349908 -8.447024)
		(width 0.1397)
		(layer "F.Cu")
		(net "CPU_GBE_RX_C_DP0")
	)
	(segment
		(start 51.678332 -10.380472)
		(end 52.43195 -11.13409)
		(width 0.1397)
		(layer "F.Cu")
		(net "CPU_GBE_RX_C_DN0")
	)
	(segment
		(start 51.34991 -6.195568)
		(end 51.34991 -8.447278)
		(width 0.1397)
		(layer "F.Cu")
		(net "CPU_GBE_RX_C_DN0")
	)
	(segment
		(start 52.43195 -11.13409)
		(end 52.43195 -12.16025)
		(width 0.1397)
		(layer "F.Cu")
		(net "CPU_GBE_RX_C_DN0")
	)
	(segment
		(start 51.678332 -8.7757)
		(end 51.678332 -10.380472)
		(width 0.1397)
		(layer "F.Cu")
		(net "CPU_GBE_RX_C_DN0")
	)
	(segment
		(start 51.34991 -8.447278)
		(end 51.678332 -8.7757)
		(width 0.1397)
		(layer "F.Cu")
		(net "CPU_GBE_RX_C_DN0")
	)
	(segment
		(start 52.43195 -12.16025)
		(end 52.2224 -12.3698)
		(width 0.1397)
		(layer "F.Cu")
		(net "CPU_GBE_RX_C_DN0")
	)
	(segment
		(start 50.2158 -12.2428)
		(end 50.00625 -12.03325)
		(width 0.1397)
		(layer "F.Cu")
		(net "CPU_GBE_TX_C_DP0")
	)
	(segment
		(start 50.00625 -10.564622)
		(end 50.310542 -10.26033)
		(width 0.1397)
		(layer "F.Cu")
		(net "CPU_GBE_TX_C_DP0")
	)
	(segment
		(start 50.00625 -12.03325)
		(end 50.00625 -10.564622)
		(width 0.1397)
		(layer "F.Cu")
		(net "CPU_GBE_TX_C_DP0")
	)
	(via
		(at 50.310542 -10.26033)
		(size 0.508)
		(drill 0.254)
		(layers "F.Cu" "B.Cu")
		(net "CPU_GBE_TX_C_DP0")
	)
	(segment
		(start 50.349912 -5.814568)
		(end 50.349912 -8.447024)
		(width 0.1397)
		(layer "B.Cu")
		(net "CPU_GBE_TX_C_DP0")
	)
	(segment
		(start 50.021236 -8.7757)
		(end 50.021236 -9.971024)
		(width 0.1397)
		(layer "B.Cu")
		(net "CPU_GBE_TX_C_DP0")
	)
	(segment
		(start 50.021236 -9.971024)
		(end 50.310542 -10.26033)
		(width 0.1397)
		(layer "B.Cu")
		(net "CPU_GBE_TX_C_DP0")
	)
	(segment
		(start 50.349912 -8.447024)
		(end 50.021236 -8.7757)
		(width 0.1397)
		(layer "B.Cu")
		(net "CPU_GBE_TX_C_DP0")
	)
	(segment
		(start 49.66335 -12.03325)
		(end 49.66335 -10.53465)
		(width 0.1397)
		(layer "F.Cu")
		(net "CPU_GBE_TX_C_DN0")
	)
	(segment
		(start 49.66335 -10.53465)
		(end 49.38903 -10.26033)
		(width 0.1397)
		(layer "F.Cu")
		(net "CPU_GBE_TX_C_DN0")
	)
	(segment
		(start 49.4538 -12.2428)
		(end 49.66335 -12.03325)
		(width 0.1397)
		(layer "F.Cu")
		(net "CPU_GBE_TX_C_DN0")
	)
	(via
		(at 49.38903 -10.26033)
		(size 0.508)
		(drill 0.254)
		(layers "F.Cu" "B.Cu")
		(net "CPU_GBE_TX_C_DN0")
	)
	(segment
		(start 49.349914 -8.447278)
		(end 49.678336 -8.7757)
		(width 0.1397)
		(layer "B.Cu")
		(net "CPU_GBE_TX_C_DN0")
	)
	(segment
		(start 49.349914 -5.814568)
		(end 49.349914 -8.447278)
		(width 0.1397)
		(layer "B.Cu")
		(net "CPU_GBE_TX_C_DN0")
	)
	(segment
		(start 49.678336 -8.7757)
		(end 49.678336 -9.971024)
		(width 0.1397)
		(layer "B.Cu")
		(net "CPU_GBE_TX_C_DN0")
	)
	(segment
		(start 49.678336 -9.971024)
		(end 49.38903 -10.26033)
		(width 0.1397)
		(layer "B.Cu")
		(net "CPU_GBE_TX_C_DN0")
	)
	(via
		(at 198.901812 -67.626484)
		(size 0.7112)
		(drill 0.3556)
		(layers "F.Cu" "B.Cu")
		(net "PWR_STATUS_LED_EN")
	)
	(segment
		(start 197.624954 -67.564)
		(end 196.034914 -69.15404)
		(width 0.127)
		(layer "B.Cu")
		(net "PWR_STATUS_LED_EN")
	)
	(segment
		(start 197.6628 -67.564)
		(end 198.839328 -67.564)
		(width 0.127)
		(layer "B.Cu")
		(net "PWR_STATUS_LED_EN")
	)
	(segment
		(start 197.6628 -67.564)
		(end 197.624954 -67.564)
		(width 0.127)
		(layer "B.Cu")
		(net "PWR_STATUS_LED_EN")
	)
	(segment
		(start 198.839328 -67.564)
		(end 198.901812 -67.626484)
		(width 0.127)
		(layer "B.Cu")
		(net "PWR_STATUS_LED_EN")
	)
	(via
		(at 201.168 -71.3232)
		(size 0.7112)
		(drill 0.3556)
		(layers "F.Cu" "B.Cu")
		(net "PWR_STATUS_LED")
	)
	(segment
		(start 201.168 -71.3232)
		(end 202.0316 -71.3232)
		(width 0.127)
		(layer "B.Cu")
		(net "PWR_STATUS_LED")
	)
	(segment
		(start 200.3552 -72.136)
		(end 201.168 -71.3232)
		(width 0.127)
		(layer "B.Cu")
		(net "PWR_STATUS_LED")
	)
	(segment
		(start 198.538084 -71.300086)
		(end 199.373998 -72.136)
		(width 0.127)
		(layer "B.Cu")
		(net "PWR_STATUS_LED")
	)
	(segment
		(start 199.373998 -72.136)
		(end 200.3552 -72.136)
		(width 0.127)
		(layer "B.Cu")
		(net "PWR_STATUS_LED")
	)
	(segment
		(start 202.0316 -71.3232)
		(end 202.3618 -70.993)
		(width 0.127)
		(layer "B.Cu")
		(net "PWR_STATUS_LED")
	)
	(segment
		(start 135.509 -19.2278)
		(end 135.128 -19.6088)
		(width 0.1143)
		(layer "F.Cu")
		(net "POWER_CONTROL")
	)
	(segment
		(start 135.128 -21.082)
		(end 135.378444 -21.332444)
		(width 0.1143)
		(layer "F.Cu")
		(net "POWER_CONTROL")
	)
	(segment
		(start 135.887968 -22.988778)
		(end 135.887968 -22.502622)
		(width 0.1143)
		(layer "F.Cu")
		(net "POWER_CONTROL")
	)
	(segment
		(start 135.49757 -23.379176)
		(end 135.887968 -22.988778)
		(width 0.1143)
		(layer "F.Cu")
		(net "POWER_CONTROL")
	)
	(segment
		(start 135.378444 -21.993098)
		(end 135.378444 -21.76145)
		(width 0.1143)
		(layer "F.Cu")
		(net "POWER_CONTROL")
	)
	(segment
		(start 135.49757 -23.9268)
		(end 135.49757 -23.379176)
		(width 0.1143)
		(layer "F.Cu")
		(net "POWER_CONTROL")
	)
	(segment
		(start 135.128 -19.6088)
		(end 135.128 -21.082)
		(width 0.1143)
		(layer "F.Cu")
		(net "POWER_CONTROL")
	)
	(segment
		(start 135.378444 -21.332444)
		(end 135.378444 -21.76145)
		(width 0.1143)
		(layer "F.Cu")
		(net "POWER_CONTROL")
	)
	(segment
		(start 135.887968 -22.502622)
		(end 135.378444 -21.993098)
		(width 0.1143)
		(layer "F.Cu")
		(net "POWER_CONTROL")
	)
	(via
		(at 135.378444 -21.76145)
		(size 0.7112)
		(drill 0.3556)
		(layers "F.Cu" "B.Cu")
		(net "POWER_CONTROL")
	)
	(segment
		(start 67.302126 -23.7744)
		(end 67.437 -23.639526)
		(width 0.127)
		(layer "B.Cu")
		(net "LED_MSATA_DAS_R")
	)
	(segment
		(start 66.3702 -23.7744)
		(end 67.302126 -23.7744)
		(width 0.127)
		(layer "B.Cu")
		(net "LED_MSATA_DAS_R")
	)
	(segment
		(start 88.489536 -72.720454)
		(end 85.746082 -69.977)
		(width 0.127)
		(layer "F.Cu")
		(net "CPU_DIAG_LED_D")
	)
	(segment
		(start 85.746082 -69.977)
		(end 81.7118 -69.977)
		(width 0.127)
		(layer "F.Cu")
		(net "CPU_DIAG_LED_D")
	)
	(segment
		(start 192.201546 -72.720454)
		(end 88.489536 -72.720454)
		(width 0.127)
		(layer "F.Cu")
		(net "CPU_DIAG_LED_D")
	)
	(segment
		(start 81.7118 -69.977)
		(end 81.1276 -70.5612)
		(width 0.127)
		(layer "F.Cu")
		(net "CPU_DIAG_LED_D")
	)
	(segment
		(start 193.548 -71.374)
		(end 192.201546 -72.720454)
		(width 0.127)
		(layer "F.Cu")
		(net "CPU_DIAG_LED_D")
	)
	(segment
		(start 81.1276 -70.5612)
		(end 81.1276 -70.8152)
		(width 0.127)
		(layer "F.Cu")
		(net "CPU_DIAG_LED_D")
	)
	(via
		(at 66.6242 -59.055)
		(size 0.7112)
		(drill 0.3556)
		(layers "F.Cu" "B.Cu")
		(net "CPU_DIAG_LED_D")
	)
	(via
		(at 193.548 -71.374)
		(size 0.508)
		(drill 0.254)
		(layers "F.Cu" "B.Cu")
		(net "CPU_DIAG_LED_D")
	)
	(via
		(at 81.1276 -70.8152)
		(size 0.508)
		(drill 0.254)
		(layers "F.Cu" "B.Cu")
		(net "CPU_DIAG_LED_D")
	)
	(segment
		(start 193.548 -71.374)
		(end 192.91173 -71.374)
		(width 0.127)
		(layer "B.Cu")
		(net "CPU_DIAG_LED_D")
	)
	(segment
		(start 199.95261 -66.08191)
		(end 199.95261 -66.300096)
		(width 0.127)
		(layer "B.Cu")
		(net "CPU_DIAG_LED_D")
	)
	(segment
		(start 191.428116 -65.5193)
		(end 199.39 -65.5193)
		(width 0.127)
		(layer "B.Cu")
		(net "CPU_DIAG_LED_D")
	)
	(segment
		(start 190.731648 -66.215768)
		(end 191.428116 -65.5193)
		(width 0.127)
		(layer "B.Cu")
		(net "CPU_DIAG_LED_D")
	)
	(segment
		(start 80.2767 -69.5325)
		(end 77.624432 -69.5325)
		(width 0.127)
		(layer "B.Cu")
		(net "CPU_DIAG_LED_D")
	)
	(segment
		(start 67.7799 -48.0441)
		(end 68.06946 -48.33366)
		(width 0.127)
		(layer "B.Cu")
		(net "CPU_DIAG_LED_D")
	)
	(segment
		(start 69.77507 -69.28485)
		(end 66.4845 -65.99428)
		(width 0.127)
		(layer "B.Cu")
		(net "CPU_DIAG_LED_D")
	)
	(segment
		(start 66.6242 -58.166)
		(end 66.6242 -59.055)
		(width 0.127)
		(layer "B.Cu")
		(net "CPU_DIAG_LED_D")
	)
	(segment
		(start 74.343768 -69.28485)
		(end 69.77507 -69.28485)
		(width 0.127)
		(layer "B.Cu")
		(net "CPU_DIAG_LED_D")
	)
	(segment
		(start 77.624432 -69.5325)
		(end 77.25283 -69.160898)
		(width 0.127)
		(layer "B.Cu")
		(net "CPU_DIAG_LED_D")
	)
	(segment
		(start 77.25283 -69.160898)
		(end 74.46772 -69.160898)
		(width 0.127)
		(layer "B.Cu")
		(net "CPU_DIAG_LED_D")
	)
	(segment
		(start 67.7799 -45.8851)
		(end 67.7799 -48.0441)
		(width 0.127)
		(layer "B.Cu")
		(net "CPU_DIAG_LED_D")
	)
	(segment
		(start 81.153 -70.4088)
		(end 80.2767 -69.5325)
		(width 0.127)
		(layer "B.Cu")
		(net "CPU_DIAG_LED_D")
	)
	(segment
		(start 66.4845 -58.0263)
		(end 66.6242 -58.166)
		(width 0.127)
		(layer "B.Cu")
		(net "CPU_DIAG_LED_D")
	)
	(segment
		(start 81.1276 -70.8152)
		(end 81.153 -70.7898)
		(width 0.127)
		(layer "B.Cu")
		(net "CPU_DIAG_LED_D")
	)
	(segment
		(start 199.39 -65.5193)
		(end 199.95261 -66.08191)
		(width 0.127)
		(layer "B.Cu")
		(net "CPU_DIAG_LED_D")
	)
	(segment
		(start 67.399154 -53.748178)
		(end 66.4845 -54.662832)
		(width 0.127)
		(layer "B.Cu")
		(net "CPU_DIAG_LED_D")
	)
	(segment
		(start 66.4845 -65.99428)
		(end 66.4845 -59.7154)
		(width 0.127)
		(layer "B.Cu")
		(net "CPU_DIAG_LED_D")
	)
	(segment
		(start 67.399154 -49.595024)
		(end 67.399154 -53.748178)
		(width 0.127)
		(layer "B.Cu")
		(net "CPU_DIAG_LED_D")
	)
	(segment
		(start 192.91173 -71.374)
		(end 190.731648 -69.193918)
		(width 0.127)
		(layer "B.Cu")
		(net "CPU_DIAG_LED_D")
	)
	(segment
		(start 81.153 -70.7898)
		(end 81.153 -70.4088)
		(width 0.127)
		(layer "B.Cu")
		(net "CPU_DIAG_LED_D")
	)
	(segment
		(start 190.731648 -69.193918)
		(end 190.731648 -66.215768)
		(width 0.127)
		(layer "B.Cu")
		(net "CPU_DIAG_LED_D")
	)
	(segment
		(start 74.46772 -69.160898)
		(end 74.343768 -69.28485)
		(width 0.127)
		(layer "B.Cu")
		(net "CPU_DIAG_LED_D")
	)
	(segment
		(start 68.06946 -48.33366)
		(end 68.06946 -48.924718)
		(width 0.127)
		(layer "B.Cu")
		(net "CPU_DIAG_LED_D")
	)
	(segment
		(start 68.06946 -48.924718)
		(end 67.399154 -49.595024)
		(width 0.127)
		(layer "B.Cu")
		(net "CPU_DIAG_LED_D")
	)
	(segment
		(start 68.780914 -44.884086)
		(end 67.7799 -45.8851)
		(width 0.127)
		(layer "B.Cu")
		(net "CPU_DIAG_LED_D")
	)
	(segment
		(start 66.4845 -54.662832)
		(end 66.4845 -58.0263)
		(width 0.127)
		(layer "B.Cu")
		(net "CPU_DIAG_LED_D")
	)
	(segment
		(start 69.088 -44.884086)
		(end 68.780914 -44.884086)
		(width 0.127)
		(layer "B.Cu")
		(net "CPU_DIAG_LED_D")
	)
	(segment
		(start 66.4845 -59.7154)
		(end 66.6242 -59.5757)
		(width 0.127)
		(layer "B.Cu")
		(net "CPU_DIAG_LED_D")
	)
	(segment
		(start 66.6242 -59.5757)
		(end 66.6242 -59.055)
		(width 0.127)
		(layer "B.Cu")
		(net "CPU_DIAG_LED_D")
	)
	(via
		(at 200.39457 -67.506342)
		(size 0.7112)
		(drill 0.3556)
		(layers "F.Cu" "B.Cu")
		(net "DIAG_LED")
	)
	(segment
		(start 200.39457 -67.506342)
		(end 199.949308 -67.506342)
		(width 0.127)
		(layer "B.Cu")
		(net "DIAG_LED")
	)
	(segment
		(start 199.949308 -67.506342)
		(end 198.743062 -66.300096)
		(width 0.127)
		(layer "B.Cu")
		(net "DIAG_LED")
	)
	(segment
		(start 198.743062 -66.300096)
		(end 198.647558 -66.300096)
		(width 0.127)
		(layer "B.Cu")
		(net "DIAG_LED")
	)
	(segment
		(start 197.6628 -66.04)
		(end 198.387462 -66.04)
		(width 0.127)
		(layer "B.Cu")
		(net "DIAG_LED")
	)
	(segment
		(start 198.387462 -66.04)
		(end 198.647558 -66.300096)
		(width 0.127)
		(layer "B.Cu")
		(net "DIAG_LED")
	)
	(via
		(at 91.350084 -12.7)
		(size 0.7112)
		(drill 0.3556)
		(layers "F.Cu" "B.Cu")
		(net "PWR_BTN#")
	)
	(segment
		(start 92.329 -13.0302)
		(end 91.6432 -13.0302)
		(width 0.1143)
		(layer "B.Cu")
		(net "PWR_BTN#")
	)
	(segment
		(start 91.350084 -12.737084)
		(end 91.350084 -12.7)
		(width 0.1143)
		(layer "B.Cu")
		(net "PWR_BTN#")
	)
	(segment
		(start 91.6432 -13.0302)
		(end 91.350084 -12.737084)
		(width 0.1143)
		(layer "B.Cu")
		(net "PWR_BTN#")
	)
	(segment
		(start 91.350084 -5.814568)
		(end 91.350084 -12.7)
		(width 0.1143)
		(layer "B.Cu")
		(net "PWR_BTN#")
	)
	(segment
		(start 85.552788 -39.431214)
		(end 85.334856 -39.649146)
		(width 0.127)
		(layer "F.Cu")
		(net "CPU_DIAG_LED")
	)
	(segment
		(start 85.334856 -39.649146)
		(end 85.334856 -40.262048)
		(width 0.127)
		(layer "F.Cu")
		(net "CPU_DIAG_LED")
	)
	(via
		(at 75.819 -42.4434)
		(size 0.7112)
		(drill 0.3556)
		(layers "F.Cu" "B.Cu")
		(net "CPU_DIAG_LED")
	)
	(via
		(at 85.334856 -40.262048)
		(size 0.4318)
		(drill 0.2032)
		(layers "F.Cu" "B.Cu")
		(net "CPU_DIAG_LED")
	)
	(segment
		(start 74.0791 -42.1513)
		(end 74.5998 -42.672)
		(width 0.127)
		(layer "B.Cu")
		(net "CPU_DIAG_LED")
	)
	(segment
		(start 73.4441 -42.1513)
		(end 74.0791 -42.1513)
		(width 0.127)
		(layer "B.Cu")
		(net "CPU_DIAG_LED")
	)
	(segment
		(start 82.535776 -40.4622)
		(end 81.555844 -40.4622)
		(width 0.127)
		(layer "B.Cu")
		(net "CPU_DIAG_LED")
	)
	(segment
		(start 80.96631 -41.051734)
		(end 80.080866 -41.051734)
		(width 0.127)
		(layer "B.Cu")
		(net "CPU_DIAG_LED")
	)
	(segment
		(start 85.334856 -40.262048)
		(end 85.207348 -40.262048)
		(width 0.127)
		(layer "B.Cu")
		(net "CPU_DIAG_LED")
	)
	(segment
		(start 80.080866 -41.051734)
		(end 78.9178 -42.2148)
		(width 0.127)
		(layer "B.Cu")
		(net "CPU_DIAG_LED")
	)
	(segment
		(start 75.5904 -42.672)
		(end 75.819 -42.4434)
		(width 0.127)
		(layer "B.Cu")
		(net "CPU_DIAG_LED")
	)
	(segment
		(start 74.5998 -42.672)
		(end 75.5904 -42.672)
		(width 0.127)
		(layer "B.Cu")
		(net "CPU_DIAG_LED")
	)
	(segment
		(start 85.207348 -40.262048)
		(end 84.619084 -39.673784)
		(width 0.127)
		(layer "B.Cu")
		(net "CPU_DIAG_LED")
	)
	(segment
		(start 83.324192 -39.673784)
		(end 82.535776 -40.4622)
		(width 0.127)
		(layer "B.Cu")
		(net "CPU_DIAG_LED")
	)
	(segment
		(start 84.619084 -39.673784)
		(end 83.324192 -39.673784)
		(width 0.127)
		(layer "B.Cu")
		(net "CPU_DIAG_LED")
	)
	(segment
		(start 76.0476 -42.2148)
		(end 75.819 -42.4434)
		(width 0.127)
		(layer "B.Cu")
		(net "CPU_DIAG_LED")
	)
	(segment
		(start 72.9234 -42.672)
		(end 73.4441 -42.1513)
		(width 0.127)
		(layer "B.Cu")
		(net "CPU_DIAG_LED")
	)
	(segment
		(start 78.9178 -42.2148)
		(end 76.0476 -42.2148)
		(width 0.127)
		(layer "B.Cu")
		(net "CPU_DIAG_LED")
	)
	(segment
		(start 81.555844 -40.4622)
		(end 80.96631 -41.051734)
		(width 0.127)
		(layer "B.Cu")
		(net "CPU_DIAG_LED")
	)
	(segment
		(start 71.4248 -47.117)
		(end 71.2978 -47.244)
		(width 0.127)
		(layer "F.Cu")
		(net "CPU_BEEP_LED")
	)
	(segment
		(start 70.8914 -47.6504)
		(end 71.2978 -47.244)
		(width 0.127)
		(layer "F.Cu")
		(net "CPU_BEEP_LED")
	)
	(segment
		(start 70.8914 -48.643286)
		(end 70.8914 -47.6504)
		(width 0.127)
		(layer "F.Cu")
		(net "CPU_BEEP_LED")
	)
	(segment
		(start 73.6092 -47.117)
		(end 71.4248 -47.117)
		(width 0.127)
		(layer "F.Cu")
		(net "CPU_BEEP_LED")
	)
	(segment
		(start 69.542914 -50.98796)
		(end 69.542914 -49.991772)
		(width 0.127)
		(layer "F.Cu")
		(net "CPU_BEEP_LED")
	)
	(segment
		(start 69.542914 -49.991772)
		(end 70.8914 -48.643286)
		(width 0.127)
		(layer "F.Cu")
		(net "CPU_BEEP_LED")
	)
	(via
		(at 71.2978 -47.244)
		(size 0.7112)
		(drill 0.3556)
		(layers "F.Cu" "B.Cu")
		(net "CPU_BEEP_LED")
	)
	(via
		(at 71.0946 -42.672)
		(size 0.7112)
		(drill 0.3556)
		(layers "F.Cu" "B.Cu")
		(net "CPU_DIAG_LED_R")
	)
	(segment
		(start 71.020686 -42.745914)
		(end 71.0946 -42.672)
		(width 0.127)
		(layer "B.Cu")
		(net "CPU_DIAG_LED_R")
	)
	(segment
		(start 71.0946 -42.672)
		(end 72.0598 -42.672)
		(width 0.127)
		(layer "B.Cu")
		(net "CPU_DIAG_LED_R")
	)
	(segment
		(start 70.03796 -42.745914)
		(end 71.020686 -42.745914)
		(width 0.127)
		(layer "B.Cu")
		(net "CPU_DIAG_LED_R")
	)
	(segment
		(start 77.268832 -33.705038)
		(end 76.9366 -33.372806)
		(width 0.1143)
		(layer "F.Cu")
		(net "BD_ID_2")
	)
	(segment
		(start 71.374 -33.5534)
		(end 70.4342 -33.5534)
		(width 0.1143)
		(layer "F.Cu")
		(net "BD_ID_2")
	)
	(segment
		(start 85.933788 -34.447988)
		(end 85.935566 -34.449766)
		(width 0.1143)
		(layer "F.Cu")
		(net "BD_ID_2")
	)
	(segment
		(start 85.933788 -33.472374)
		(end 85.933788 -34.447988)
		(width 0.1143)
		(layer "F.Cu")
		(net "BD_ID_2")
	)
	(segment
		(start 70.0278 -31.496)
		(end 70.0278 -33.147)
		(width 0.1143)
		(layer "F.Cu")
		(net "BD_ID_2")
	)
	(segment
		(start 78.053692 -33.705038)
		(end 77.268832 -33.705038)
		(width 0.1143)
		(layer "F.Cu")
		(net "BD_ID_2")
	)
	(segment
		(start 76.9366 -33.372806)
		(end 75.25639 -31.69285)
		(width 0.1143)
		(layer "F.Cu")
		(net "BD_ID_2")
	)
	(segment
		(start 70.0278 -33.147)
		(end 70.270116 -33.389316)
		(width 0.1143)
		(layer "F.Cu")
		(net "BD_ID_2")
	)
	(segment
		(start 85.935566 -34.449766)
		(end 85.935566 -34.45891)
		(width 0.1143)
		(layer "F.Cu")
		(net "BD_ID_2")
	)
	(segment
		(start 71.8566 -33.0708)
		(end 71.374 -33.5534)
		(width 0.1143)
		(layer "F.Cu")
		(net "BD_ID_2")
	)
	(segment
		(start 72.24395 -31.69285)
		(end 71.8566 -32.0802)
		(width 0.1143)
		(layer "F.Cu")
		(net "BD_ID_2")
	)
	(segment
		(start 75.25639 -31.69285)
		(end 72.24395 -31.69285)
		(width 0.1143)
		(layer "F.Cu")
		(net "BD_ID_2")
	)
	(segment
		(start 70.0278 -30.734)
		(end 70.0278 -31.496)
		(width 0.1143)
		(layer "F.Cu")
		(net "BD_ID_2")
	)
	(segment
		(start 70.4342 -33.5534)
		(end 70.270116 -33.389316)
		(width 0.1143)
		(layer "F.Cu")
		(net "BD_ID_2")
	)
	(segment
		(start 71.8566 -32.0802)
		(end 71.8566 -33.0708)
		(width 0.1143)
		(layer "F.Cu")
		(net "BD_ID_2")
	)
	(via
		(at 70.270116 -33.389316)
		(size 0.7112)
		(drill 0.3556)
		(layers "F.Cu" "B.Cu")
		(net "BD_ID_2")
	)
	(via
		(at 78.053692 -33.705038)
		(size 0.4318)
		(drill 0.2032)
		(layers "F.Cu" "B.Cu")
		(net "BD_ID_2")
	)
	(via
		(at 85.935566 -34.45891)
		(size 0.4318)
		(drill 0.2032)
		(layers "F.Cu" "B.Cu")
		(net "BD_ID_2")
	)
	(segment
		(start 79.199994 -34.1249)
		(end 78.462886 -34.1249)
		(width 0.0889)
		(layer "In7.Cu")
		(net "BD_ID_2")
	)
	(segment
		(start 79.349346 -34.274252)
		(end 79.199994 -34.1249)
		(width 0.0889)
		(layer "In7.Cu")
		(net "BD_ID_2")
	)
	(segment
		(start 85.935566 -34.45891)
		(end 85.449918 -33.973262)
		(width 0.0889)
		(layer "In7.Cu")
		(net "BD_ID_2")
	)
	(segment
		(start 85.449918 -33.973262)
		(end 84.425536 -33.973262)
		(width 0.0889)
		(layer "In7.Cu")
		(net "BD_ID_2")
	)
	(segment
		(start 81.17586 -34.274252)
		(end 79.349346 -34.274252)
		(width 0.0889)
		(layer "In7.Cu")
		(net "BD_ID_2")
	)
	(segment
		(start 82.113628 -34.911792)
		(end 81.8134 -34.911792)
		(width 0.0889)
		(layer "In7.Cu")
		(net "BD_ID_2")
	)
	(segment
		(start 78.462886 -34.1249)
		(end 78.053692 -33.715706)
		(width 0.0889)
		(layer "In7.Cu")
		(net "BD_ID_2")
	)
	(segment
		(start 78.053692 -33.715706)
		(end 78.053692 -33.705038)
		(width 0.0889)
		(layer "In7.Cu")
		(net "BD_ID_2")
	)
	(segment
		(start 83.88604 -34.512758)
		(end 82.512662 -34.512758)
		(width 0.0889)
		(layer "In7.Cu")
		(net "BD_ID_2")
	)
	(segment
		(start 84.425536 -33.973262)
		(end 83.88604 -34.512758)
		(width 0.0889)
		(layer "In7.Cu")
		(net "BD_ID_2")
	)
	(segment
		(start 81.8134 -34.911792)
		(end 81.17586 -34.274252)
		(width 0.0889)
		(layer "In7.Cu")
		(net "BD_ID_2")
	)
	(segment
		(start 82.512662 -34.512758)
		(end 82.113628 -34.911792)
		(width 0.0889)
		(layer "In7.Cu")
		(net "BD_ID_2")
	)
	(segment
		(start 63.83655 -12.92225)
		(end 63.627 -13.1318)
		(width 0.1397)
		(layer "F.Cu")
		(net "SATA2_RX_C_DN0")
	)
	(segment
		(start 63.349886 -8.447278)
		(end 63.678308 -8.7757)
		(width 0.1397)
		(layer "F.Cu")
		(net "SATA2_RX_C_DN0")
	)
	(segment
		(start 63.678308 -8.7757)
		(end 63.678308 -11.356848)
		(width 0.1397)
		(layer "F.Cu")
		(net "SATA2_RX_C_DN0")
	)
	(segment
		(start 63.678308 -11.356848)
		(end 63.83655 -11.51509)
		(width 0.1397)
		(layer "F.Cu")
		(net "SATA2_RX_C_DN0")
	)
	(segment
		(start 63.83655 -11.51509)
		(end 63.83655 -12.92225)
		(width 0.1397)
		(layer "F.Cu")
		(net "SATA2_RX_C_DN0")
	)
	(segment
		(start 63.349886 -6.195568)
		(end 63.349886 -8.447278)
		(width 0.1397)
		(layer "F.Cu")
		(net "SATA2_RX_C_DN0")
	)
	(segment
		(start 64.021208 -11.214608)
		(end 64.17945 -11.37285)
		(width 0.1397)
		(layer "F.Cu")
		(net "SATA2_RX_C_DP0")
	)
	(segment
		(start 64.349884 -6.195568)
		(end 64.349884 -8.447024)
		(width 0.1397)
		(layer "F.Cu")
		(net "SATA2_RX_C_DP0")
	)
	(segment
		(start 64.021208 -8.7757)
		(end 64.021208 -11.214608)
		(width 0.1397)
		(layer "F.Cu")
		(net "SATA2_RX_C_DP0")
	)
	(segment
		(start 64.349884 -8.447024)
		(end 64.021208 -8.7757)
		(width 0.1397)
		(layer "F.Cu")
		(net "SATA2_RX_C_DP0")
	)
	(segment
		(start 64.17945 -11.37285)
		(end 64.17945 -12.92225)
		(width 0.1397)
		(layer "F.Cu")
		(net "SATA2_RX_C_DP0")
	)
	(segment
		(start 64.17945 -12.92225)
		(end 64.389 -13.1318)
		(width 0.1397)
		(layer "F.Cu")
		(net "SATA2_RX_C_DP0")
	)
	(segment
		(start 63.946532 -27.500072)
		(end 64.668654 -27.500072)
		(width 0.1397)
		(layer "B.Cu")
		(net "SATA3_TX_C_DP0")
	)
	(segment
		(start 64.9224 -27.753818)
		(end 66.530982 -27.753818)
		(width 0.1397)
		(layer "B.Cu")
		(net "SATA3_TX_C_DP0")
	)
	(segment
		(start 66.530982 -27.753818)
		(end 66.7258 -27.559)
		(width 0.1397)
		(layer "B.Cu")
		(net "SATA3_TX_C_DP0")
	)
	(segment
		(start 64.668654 -27.500072)
		(end 64.9224 -27.753818)
		(width 0.1397)
		(layer "B.Cu")
		(net "SATA3_TX_C_DP0")
	)
	(segment
		(start 64.9732 -30.928564)
		(end 64.7446 -30.699964)
		(width 0.1397)
		(layer "B.Cu")
		(net "SATA3_RX_C_DN0")
	)
	(segment
		(start 65.207896 -30.928564)
		(end 64.9732 -30.928564)
		(width 0.1397)
		(layer "B.Cu")
		(net "SATA3_RX_C_DN0")
	)
	(segment
		(start 64.7446 -30.699964)
		(end 63.946532 -30.699964)
		(width 0.1397)
		(layer "B.Cu")
		(net "SATA3_RX_C_DN0")
	)
	(segment
		(start 66.51625 -29.97835)
		(end 66.15811 -29.97835)
		(width 0.1397)
		(layer "B.Cu")
		(net "SATA3_RX_C_DN0")
	)
	(segment
		(start 66.15811 -29.97835)
		(end 65.207896 -30.928564)
		(width 0.1397)
		(layer "B.Cu")
		(net "SATA3_RX_C_DN0")
	)
	(segment
		(start 66.7258 -29.7688)
		(end 66.51625 -29.97835)
		(width 0.1397)
		(layer "B.Cu")
		(net "SATA3_RX_C_DN0")
	)
	(segment
		(start 63.946532 -28.299918)
		(end 64.6684 -28.299918)
		(width 0.1397)
		(layer "B.Cu")
		(net "SATA3_TX_C_DN0")
	)
	(segment
		(start 64.8716 -28.096718)
		(end 66.501518 -28.096718)
		(width 0.1397)
		(layer "B.Cu")
		(net "SATA3_TX_C_DN0")
	)
	(segment
		(start 64.6684 -28.299918)
		(end 64.8716 -28.096718)
		(width 0.1397)
		(layer "B.Cu")
		(net "SATA3_TX_C_DN0")
	)
	(segment
		(start 66.501518 -28.096718)
		(end 66.7258 -28.321)
		(width 0.1397)
		(layer "B.Cu")
		(net "SATA3_TX_C_DN0")
	)
	(segment
		(start 64.7446 -31.500064)
		(end 63.946532 -31.500064)
		(width 0.1397)
		(layer "B.Cu")
		(net "SATA3_RX_C_DP0")
	)
	(segment
		(start 66.30035 -30.32125)
		(end 65.350136 -31.271464)
		(width 0.1397)
		(layer "B.Cu")
		(net "SATA3_RX_C_DP0")
	)
	(segment
		(start 66.51625 -30.32125)
		(end 66.30035 -30.32125)
		(width 0.1397)
		(layer "B.Cu")
		(net "SATA3_RX_C_DP0")
	)
	(segment
		(start 64.9732 -31.271464)
		(end 64.7446 -31.500064)
		(width 0.1397)
		(layer "B.Cu")
		(net "SATA3_RX_C_DP0")
	)
	(segment
		(start 66.7258 -30.5308)
		(end 66.51625 -30.32125)
		(width 0.1397)
		(layer "B.Cu")
		(net "SATA3_RX_C_DP0")
	)
	(segment
		(start 65.350136 -31.271464)
		(end 64.9732 -31.271464)
		(width 0.1397)
		(layer "B.Cu")
		(net "SATA3_RX_C_DP0")
	)
	(via
		(at 114.681 -63.7921)
		(size 0.7112)
		(drill 0.3556)
		(layers "F.Cu" "B.Cu")
		(net "P3V0_BAT")
	)
	(segment
		(start 115.4303 -63.7921)
		(end 114.681 -63.7921)
		(width 0.127)
		(layer "B.Cu")
		(net "P3V0_BAT")
	)
	(segment
		(start 112.6109 -63.7921)
		(end 114.681 -63.7921)
		(width 0.127)
		(layer "B.Cu")
		(net "P3V0_BAT")
	)
	(segment
		(start 111.618014 -64.784986)
		(end 112.6109 -63.7921)
		(width 0.127)
		(layer "B.Cu")
		(net "P3V0_BAT")
	)
	(segment
		(start 111.618014 -66.174874)
		(end 111.618014 -64.784986)
		(width 0.127)
		(layer "B.Cu")
		(net "P3V0_BAT")
	)
	(segment
		(start 115.6462 -64.008)
		(end 115.4303 -63.7921)
		(width 0.127)
		(layer "B.Cu")
		(net "P3V0_BAT")
	)
	(via
		(at 116.5098 -64.9224)
		(size 0.7112)
		(drill 0.3556)
		(layers "F.Cu" "B.Cu")
		(net "P3V0_BAT_R")
	)
	(segment
		(start 116.5098 -64.008)
		(end 116.5098 -64.9224)
		(width 0.127)
		(layer "B.Cu")
		(net "P3V0_BAT_R")
	)
	(segment
		(start 116.5098 -64.9732)
		(end 116.01704 -65.46596)
		(width 0.127)
		(layer "B.Cu")
		(net "P3V0_BAT_R")
	)
	(segment
		(start 116.5098 -64.9224)
		(end 116.5098 -64.9732)
		(width 0.127)
		(layer "B.Cu")
		(net "P3V0_BAT_R")
	)
	(segment
		(start 116.01704 -65.46596)
		(end 116.01704 -65.986914)
		(width 0.127)
		(layer "B.Cu")
		(net "P3V0_BAT_R")
	)
	(segment
		(start 36.83 -39.5478)
		(end 36.83 -39.558976)
		(width 0.127)
		(layer "F.Cu")
		(net "P3V3_RTC")
	)
	(segment
		(start 91.102942 -39.5478)
		(end 91.059 -39.5478)
		(width 0.127)
		(layer "F.Cu")
		(net "P3V3_RTC")
	)
	(segment
		(start 91.450668 -39.200074)
		(end 91.102942 -39.5478)
		(width 0.127)
		(layer "F.Cu")
		(net "P3V3_RTC")
	)
	(segment
		(start 36.83 -39.558976)
		(end 36.703 -39.685976)
		(width 0.127)
		(layer "F.Cu")
		(net "P3V3_RTC")
	)
	(segment
		(start 36.703 -39.685976)
		(end 36.703 -40.3606)
		(width 0.127)
		(layer "F.Cu")
		(net "P3V3_RTC")
	)
	(via
		(at 91.059 -39.5478)
		(size 0.4318)
		(drill 0.2032)
		(layers "F.Cu" "B.Cu")
		(net "P3V3_RTC")
	)
	(via
		(at 36.703 -40.3606)
		(size 0.508)
		(drill 0.254)
		(layers "F.Cu" "B.Cu")
		(net "P3V3_RTC")
	)
	(via
		(at 115.697 -68.453)
		(size 0.7112)
		(drill 0.3556)
		(layers "F.Cu" "B.Cu")
		(net "P3V3_RTC")
	)
	(via
		(at 114.935 -69.9008)
		(size 0.508)
		(drill 0.254)
		(layers "F.Cu" "B.Cu")
		(net "P3V3_RTC")
	)
	(segment
		(start 116.967 -68.125086)
		(end 116.024914 -68.125086)
		(width 0.127)
		(layer "B.Cu")
		(net "P3V3_RTC")
	)
	(segment
		(start 116.024914 -68.125086)
		(end 115.697 -68.453)
		(width 0.127)
		(layer "B.Cu")
		(net "P3V3_RTC")
	)
	(segment
		(start 114.935 -69.40931)
		(end 114.173 -68.64731)
		(width 0.127)
		(layer "B.Cu")
		(net "P3V3_RTC")
	)
	(segment
		(start 77.272642 -35.042094)
		(end 72.557894 -35.042094)
		(width 0.127)
		(layer "B.Cu")
		(net "P3V3_RTC")
	)
	(segment
		(start 89.35212 -38.3667)
		(end 90.7415 -38.3667)
		(width 0.127)
		(layer "B.Cu")
		(net "P3V3_RTC")
	)
	(segment
		(start 80.560164 -36.49345)
		(end 80.236314 -36.1696)
		(width 0.127)
		(layer "B.Cu")
		(net "P3V3_RTC")
	)
	(segment
		(start 89.2429 -38.25748)
		(end 89.35212 -38.3667)
		(width 0.127)
		(layer "B.Cu")
		(net "P3V3_RTC")
	)
	(segment
		(start 79.378048 -35.5473)
		(end 77.777848 -35.5473)
		(width 0.127)
		(layer "B.Cu")
		(net "P3V3_RTC")
	)
	(segment
		(start 87.32012 -38.25748)
		(end 89.2429 -38.25748)
		(width 0.127)
		(layer "B.Cu")
		(net "P3V3_RTC")
	)
	(segment
		(start 91.059 -38.6842)
		(end 90.9574 -38.5826)
		(width 0.127)
		(layer "B.Cu")
		(net "P3V3_RTC")
	)
	(segment
		(start 115.6208 -68.5292)
		(end 114.173 -68.5292)
		(width 0.127)
		(layer "B.Cu")
		(net "P3V3_RTC")
	)
	(segment
		(start 80.000348 -36.1696)
		(end 79.378048 -35.5473)
		(width 0.127)
		(layer "B.Cu")
		(net "P3V3_RTC")
	)
	(segment
		(start 91.059 -39.5478)
		(end 91.059 -38.6842)
		(width 0.127)
		(layer "B.Cu")
		(net "P3V3_RTC")
	)
	(segment
		(start 115.697 -68.453)
		(end 115.6208 -68.5292)
		(width 0.127)
		(layer "B.Cu")
		(net "P3V3_RTC")
	)
	(segment
		(start 114.173 -68.64731)
		(end 114.173 -68.5292)
		(width 0.127)
		(layer "B.Cu")
		(net "P3V3_RTC")
	)
	(segment
		(start 114.935 -69.9008)
		(end 114.935 -69.40931)
		(width 0.127)
		(layer "B.Cu")
		(net "P3V3_RTC")
	)
	(segment
		(start 72.557894 -35.042094)
		(end 71.9328 -34.417)
		(width 0.127)
		(layer "B.Cu")
		(net "P3V3_RTC")
	)
	(segment
		(start 81.69783 -36.49345)
		(end 80.560164 -36.49345)
		(width 0.127)
		(layer "B.Cu")
		(net "P3V3_RTC")
	)
	(segment
		(start 85.69198 -36.6903)
		(end 84.614512 -36.6903)
		(width 0.127)
		(layer "B.Cu")
		(net "P3V3_RTC")
	)
	(segment
		(start 90.7415 -38.3667)
		(end 90.9574 -38.5826)
		(width 0.127)
		(layer "B.Cu")
		(net "P3V3_RTC")
	)
	(segment
		(start 81.895696 -36.691316)
		(end 81.69783 -36.49345)
		(width 0.127)
		(layer "B.Cu")
		(net "P3V3_RTC")
	)
	(segment
		(start 87.26424 -38.2016)
		(end 87.32012 -38.25748)
		(width 0.127)
		(layer "B.Cu")
		(net "P3V3_RTC")
	)
	(segment
		(start 77.777848 -35.5473)
		(end 77.272642 -35.042094)
		(width 0.127)
		(layer "B.Cu")
		(net "P3V3_RTC")
	)
	(segment
		(start 80.236314 -36.1696)
		(end 80.000348 -36.1696)
		(width 0.127)
		(layer "B.Cu")
		(net "P3V3_RTC")
	)
	(segment
		(start 84.614512 -36.6903)
		(end 84.613496 -36.691316)
		(width 0.127)
		(layer "B.Cu")
		(net "P3V3_RTC")
	)
	(segment
		(start 84.613496 -36.691316)
		(end 81.895696 -36.691316)
		(width 0.127)
		(layer "B.Cu")
		(net "P3V3_RTC")
	)
	(segment
		(start 87.26424 -38.2016)
		(end 87.20328 -38.2016)
		(width 0.127)
		(layer "B.Cu")
		(net "P3V3_RTC")
	)
	(segment
		(start 87.20328 -38.2016)
		(end 85.69198 -36.6903)
		(width 0.127)
		(layer "B.Cu")
		(net "P3V3_RTC")
	)
	(segment
		(start 90.5256 -42.364152)
		(end 90.5256 -40.386)
		(width 0.127)
		(layer "In2.Cu")
		(net "P3V3_RTC")
	)
	(segment
		(start 91.059 -39.8526)
		(end 91.059 -39.5478)
		(width 0.127)
		(layer "In2.Cu")
		(net "P3V3_RTC")
	)
	(segment
		(start 111.4044 -69.22516)
		(end 111.94796 -68.6816)
		(width 0.127)
		(layer "In2.Cu")
		(net "P3V3_RTC")
	)
	(segment
		(start 50.6984 -50.2158)
		(end 52.739036 -52.256436)
		(width 0.127)
		(layer "In2.Cu")
		(net "P3V3_RTC")
	)
	(segment
		(start 92.80525 -63.4619)
		(end 92.80525 -57.637172)
		(width 0.127)
		(layer "In2.Cu")
		(net "P3V3_RTC")
	)
	(segment
		(start 91.87815 -56.709818)
		(end 91.87815 -50.312574)
		(width 0.127)
		(layer "In2.Cu")
		(net "P3V3_RTC")
	)
	(segment
		(start 111.94796 -68.6816)
		(end 114.20729 -68.6816)
		(width 0.127)
		(layer "In2.Cu")
		(net "P3V3_RTC")
	)
	(segment
		(start 39.0525 -41.677336)
		(end 39.0525 -42.814494)
		(width 0.127)
		(layer "In2.Cu")
		(net "P3V3_RTC")
	)
	(segment
		(start 52.739036 -52.256436)
		(end 52.739036 -52.374038)
		(width 0.127)
		(layer "In2.Cu")
		(net "P3V3_RTC")
	)
	(segment
		(start 69.987414 -63.15075)
		(end 88.19515 -63.15075)
		(width 0.127)
		(layer "In2.Cu")
		(net "P3V3_RTC")
	)
	(segment
		(start 92.7989 -63.46825)
		(end 94.86265 -65.532)
		(width 0.127)
		(layer "In2.Cu")
		(net "P3V3_RTC")
	)
	(segment
		(start 111.4044 -70.358)
		(end 111.4044 -69.22516)
		(width 0.127)
		(layer "In2.Cu")
		(net "P3V3_RTC")
	)
	(segment
		(start 91.0082 -42.846752)
		(end 90.5256 -42.364152)
		(width 0.127)
		(layer "In2.Cu")
		(net "P3V3_RTC")
	)
	(segment
		(start 58.99785 -62.073028)
		(end 60.481972 -63.55715)
		(width 0.127)
		(layer "In2.Cu")
		(net "P3V3_RTC")
	)
	(segment
		(start 65.33515 -63.55715)
		(end 66.6115 -64.8335)
		(width 0.127)
		(layer "In2.Cu")
		(net "P3V3_RTC")
	)
	(segment
		(start 91.022678 -47.43831)
		(end 91.0336 -47.427388)
		(width 0.127)
		(layer "In2.Cu")
		(net "P3V3_RTC")
	)
	(segment
		(start 36.703 -40.3606)
		(end 37.2872 -40.9448)
		(width 0.127)
		(layer "In2.Cu")
		(net "P3V3_RTC")
	)
	(segment
		(start 54.447948 -54.08295)
		(end 55.188104 -54.08295)
		(width 0.127)
		(layer "In2.Cu")
		(net "P3V3_RTC")
	)
	(segment
		(start 101.981 -71.52005)
		(end 110.24235 -71.52005)
		(width 0.127)
		(layer "In2.Cu")
		(net "P3V3_RTC")
	)
	(segment
		(start 44.579286 -46.611286)
		(end 45.59046 -46.611286)
		(width 0.127)
		(layer "In2.Cu")
		(net "P3V3_RTC")
	)
	(segment
		(start 92.7989 -63.46825)
		(end 92.80525 -63.4619)
		(width 0.127)
		(layer "In2.Cu")
		(net "P3V3_RTC")
	)
	(segment
		(start 101.2317 -67.898264)
		(end 101.2317 -70.77075)
		(width 0.127)
		(layer "In2.Cu")
		(net "P3V3_RTC")
	)
	(segment
		(start 88.19515 -63.15075)
		(end 88.51265 -63.46825)
		(width 0.127)
		(layer "In2.Cu")
		(net "P3V3_RTC")
	)
	(segment
		(start 114.935 -69.40931)
		(end 114.935 -69.9008)
		(width 0.127)
		(layer "In2.Cu")
		(net "P3V3_RTC")
	)
	(segment
		(start 88.51265 -63.46825)
		(end 92.7989 -63.46825)
		(width 0.127)
		(layer "In2.Cu")
		(net "P3V3_RTC")
	)
	(segment
		(start 39.0525 -42.814494)
		(end 41.145206 -44.9072)
		(width 0.127)
		(layer "In2.Cu")
		(net "P3V3_RTC")
	)
	(segment
		(start 68.304664 -64.8335)
		(end 69.987414 -63.15075)
		(width 0.127)
		(layer "In2.Cu")
		(net "P3V3_RTC")
	)
	(segment
		(start 110.24235 -71.52005)
		(end 111.4044 -70.358)
		(width 0.127)
		(layer "In2.Cu")
		(net "P3V3_RTC")
	)
	(segment
		(start 45.59046 -46.611286)
		(end 49.194974 -50.2158)
		(width 0.127)
		(layer "In2.Cu")
		(net "P3V3_RTC")
	)
	(segment
		(start 58.99785 -57.892696)
		(end 58.99785 -62.073028)
		(width 0.127)
		(layer "In2.Cu")
		(net "P3V3_RTC")
	)
	(segment
		(start 94.86265 -65.532)
		(end 98.865436 -65.532)
		(width 0.127)
		(layer "In2.Cu")
		(net "P3V3_RTC")
	)
	(segment
		(start 101.2317 -70.77075)
		(end 101.981 -71.52005)
		(width 0.127)
		(layer "In2.Cu")
		(net "P3V3_RTC")
	)
	(segment
		(start 42.8752 -44.9072)
		(end 44.579286 -46.611286)
		(width 0.127)
		(layer "In2.Cu")
		(net "P3V3_RTC")
	)
	(segment
		(start 66.6115 -64.8335)
		(end 68.304664 -64.8335)
		(width 0.127)
		(layer "In2.Cu")
		(net "P3V3_RTC")
	)
	(segment
		(start 55.188104 -54.08295)
		(end 58.99785 -57.892696)
		(width 0.127)
		(layer "In2.Cu")
		(net "P3V3_RTC")
	)
	(segment
		(start 38.319964 -40.9448)
		(end 39.0525 -41.677336)
		(width 0.127)
		(layer "In2.Cu")
		(net "P3V3_RTC")
	)
	(segment
		(start 37.2872 -40.9448)
		(end 38.319964 -40.9448)
		(width 0.127)
		(layer "In2.Cu")
		(net "P3V3_RTC")
	)
	(segment
		(start 49.194974 -50.2158)
		(end 50.6984 -50.2158)
		(width 0.127)
		(layer "In2.Cu")
		(net "P3V3_RTC")
	)
	(segment
		(start 91.0082 -47.086012)
		(end 91.0082 -42.846752)
		(width 0.127)
		(layer "In2.Cu")
		(net "P3V3_RTC")
	)
	(segment
		(start 114.20729 -68.6816)
		(end 114.935 -69.40931)
		(width 0.127)
		(layer "In2.Cu")
		(net "P3V3_RTC")
	)
	(segment
		(start 91.457526 -49.89195)
		(end 91.454224 -49.89195)
		(width 0.127)
		(layer "In2.Cu")
		(net "P3V3_RTC")
	)
	(segment
		(start 91.87815 -50.312574)
		(end 91.457526 -49.89195)
		(width 0.127)
		(layer "In2.Cu")
		(net "P3V3_RTC")
	)
	(segment
		(start 41.145206 -44.9072)
		(end 42.8752 -44.9072)
		(width 0.127)
		(layer "In2.Cu")
		(net "P3V3_RTC")
	)
	(segment
		(start 98.865436 -65.532)
		(end 101.2317 -67.898264)
		(width 0.127)
		(layer "In2.Cu")
		(net "P3V3_RTC")
	)
	(segment
		(start 52.739036 -52.374038)
		(end 54.447948 -54.08295)
		(width 0.127)
		(layer "In2.Cu")
		(net "P3V3_RTC")
	)
	(segment
		(start 91.0336 -47.111412)
		(end 91.0082 -47.086012)
		(width 0.127)
		(layer "In2.Cu")
		(net "P3V3_RTC")
	)
	(segment
		(start 91.022678 -49.460404)
		(end 91.022678 -47.43831)
		(width 0.127)
		(layer "In2.Cu")
		(net "P3V3_RTC")
	)
	(segment
		(start 91.454224 -49.89195)
		(end 91.022678 -49.460404)
		(width 0.127)
		(layer "In2.Cu")
		(net "P3V3_RTC")
	)
	(segment
		(start 60.481972 -63.55715)
		(end 65.33515 -63.55715)
		(width 0.127)
		(layer "In2.Cu")
		(net "P3V3_RTC")
	)
	(segment
		(start 91.0336 -47.427388)
		(end 91.0336 -47.111412)
		(width 0.127)
		(layer "In2.Cu")
		(net "P3V3_RTC")
	)
	(segment
		(start 90.5256 -40.386)
		(end 91.059 -39.8526)
		(width 0.127)
		(layer "In2.Cu")
		(net "P3V3_RTC")
	)
	(segment
		(start 92.80525 -57.637172)
		(end 91.87815 -56.709818)
		(width 0.127)
		(layer "In2.Cu")
		(net "P3V3_RTC")
	)
	(via
		(at 199.771 -70.104)
		(size 0.7112)
		(drill 0.3556)
		(layers "F.Cu" "B.Cu")
		(net "PWR_STATUS_LED_D")
	)
	(segment
		(start 199.771 -70.104)
		(end 198.173086 -70.104)
		(width 0.127)
		(layer "B.Cu")
		(net "PWR_STATUS_LED_D")
	)
	(segment
		(start 200.062084 -71.300086)
		(end 200.062084 -70.395084)
		(width 0.127)
		(layer "B.Cu")
		(net "PWR_STATUS_LED_D")
	)
	(segment
		(start 200.062084 -70.395084)
		(end 199.771 -70.104)
		(width 0.127)
		(layer "B.Cu")
		(net "PWR_STATUS_LED_D")
	)
	(segment
		(start 69.596 -58.0644)
		(end 68.9102 -58.0644)
		(width 0.127)
		(layer "F.Cu")
		(net "P3V3_SENSE")
	)
	(segment
		(start 68.8086 -59.799982)
		(end 68.8848 -59.876182)
		(width 0.127)
		(layer "F.Cu")
		(net "P3V3_SENSE")
	)
	(segment
		(start 71.3613 -62.41796)
		(end 69.478906 -62.41796)
		(width 0.127)
		(layer "F.Cu")
		(net "P3V3_SENSE")
	)
	(segment
		(start 69.065648 -62.004702)
		(end 69.065648 -60.05703)
		(width 0.127)
		(layer "F.Cu")
		(net "P3V3_SENSE")
	)
	(segment
		(start 68.8086 -58.9534)
		(end 68.8086 -59.799982)
		(width 0.127)
		(layer "F.Cu")
		(net "P3V3_SENSE")
	)
	(segment
		(start 69.065648 -60.05703)
		(end 68.8848 -59.876182)
		(width 0.127)
		(layer "F.Cu")
		(net "P3V3_SENSE")
	)
	(segment
		(start 69.478906 -62.41796)
		(end 69.065648 -62.004702)
		(width 0.127)
		(layer "F.Cu")
		(net "P3V3_SENSE")
	)
	(segment
		(start 68.834 -58.928)
		(end 68.8086 -58.9534)
		(width 0.127)
		(layer "F.Cu")
		(net "P3V3_SENSE")
	)
	(segment
		(start 68.9102 -58.0644)
		(end 68.834 -58.1406)
		(width 0.127)
		(layer "F.Cu")
		(net "P3V3_SENSE")
	)
	(segment
		(start 68.834 -58.1406)
		(end 68.834 -58.928)
		(width 0.127)
		(layer "F.Cu")
		(net "P3V3_SENSE")
	)
	(via
		(at 68.8848 -59.876182)
		(size 0.7112)
		(drill 0.3556)
		(layers "F.Cu" "B.Cu")
		(net "P3V3_SENSE")
	)
	(segment
		(start 71.969122 -59.817)
		(end 74.434954 -57.351168)
		(width 0.127)
		(layer "F.Cu")
		(net "P1V0_SENSE")
	)
	(segment
		(start 71.3613 -59.817)
		(end 71.969122 -59.817)
		(width 0.127)
		(layer "F.Cu")
		(net "P1V0_SENSE")
	)
	(segment
		(start 73.64476 -55.5498)
		(end 74.34199 -56.24703)
		(width 0.127)
		(layer "F.Cu")
		(net "P1V0_SENSE")
	)
	(segment
		(start 72.6694 -55.5498)
		(end 73.533 -55.5498)
		(width 0.127)
		(layer "F.Cu")
		(net "P1V0_SENSE")
	)
	(segment
		(start 74.434954 -57.351168)
		(end 74.434954 -56.339994)
		(width 0.127)
		(layer "F.Cu")
		(net "P1V0_SENSE")
	)
	(segment
		(start 74.434954 -56.339994)
		(end 74.34199 -56.24703)
		(width 0.127)
		(layer "F.Cu")
		(net "P1V0_SENSE")
	)
	(segment
		(start 72.5932 -55.626)
		(end 72.6694 -55.5498)
		(width 0.127)
		(layer "F.Cu")
		(net "P1V0_SENSE")
	)
	(segment
		(start 73.533 -55.5498)
		(end 73.64476 -55.5498)
		(width 0.127)
		(layer "F.Cu")
		(net "P1V0_SENSE")
	)
	(via
		(at 74.34199 -56.24703)
		(size 0.7112)
		(drill 0.3556)
		(layers "F.Cu" "B.Cu")
		(net "P1V0_SENSE")
	)
	(segment
		(start 72.517 -64.84239)
		(end 72.517 -61.09462)
		(width 0.127)
		(layer "F.Cu")
		(net "PVNN_SENSE")
	)
	(segment
		(start 72.517 -61.09462)
		(end 71.88962 -60.46724)
		(width 0.127)
		(layer "F.Cu")
		(net "PVNN_SENSE")
	)
	(segment
		(start 77.724 -64.4144)
		(end 77.724 -64.5414)
		(width 0.127)
		(layer "F.Cu")
		(net "PVNN_SENSE")
	)
	(segment
		(start 71.88962 -60.46724)
		(end 71.3613 -60.46724)
		(width 0.127)
		(layer "F.Cu")
		(net "PVNN_SENSE")
	)
	(segment
		(start 77.2033 -65.0621)
		(end 72.73671 -65.0621)
		(width 0.127)
		(layer "F.Cu")
		(net "PVNN_SENSE")
	)
	(segment
		(start 72.73671 -65.0621)
		(end 72.517 -64.84239)
		(width 0.127)
		(layer "F.Cu")
		(net "PVNN_SENSE")
	)
	(segment
		(start 77.724 -64.5414)
		(end 77.2033 -65.0621)
		(width 0.127)
		(layer "F.Cu")
		(net "PVNN_SENSE")
	)
	(via
		(at 77.724 -64.4144)
		(size 0.508)
		(drill 0.254)
		(layers "F.Cu" "B.Cu")
		(net "PVNN_SENSE")
	)
	(via
		(at 76.0984 -60.5028)
		(size 0.7112)
		(drill 0.3556)
		(layers "F.Cu" "B.Cu")
		(net "PVNN_SENSE")
	)
	(segment
		(start 75.819 -61.4172)
		(end 76.708 -62.3062)
		(width 0.127)
		(layer "B.Cu")
		(net "PVNN_SENSE")
	)
	(segment
		(start 77.724 -64.4144)
		(end 77.724 -63.3476)
		(width 0.127)
		(layer "B.Cu")
		(net "PVNN_SENSE")
	)
	(segment
		(start 77.724 -63.3476)
		(end 76.708 -62.3316)
		(width 0.127)
		(layer "B.Cu")
		(net "PVNN_SENSE")
	)
	(segment
		(start 76.0984 -60.5028)
		(end 75.819 -60.7822)
		(width 0.127)
		(layer "B.Cu")
		(net "PVNN_SENSE")
	)
	(segment
		(start 76.708 -62.3062)
		(end 76.708 -62.3316)
		(width 0.127)
		(layer "B.Cu")
		(net "PVNN_SENSE")
	)
	(segment
		(start 75.819 -60.7822)
		(end 75.819 -61.4172)
		(width 0.127)
		(layer "B.Cu")
		(net "PVNN_SENSE")
	)
	(segment
		(start 70.612 -64.39916)
		(end 70.612 -64.008)
		(width 0.127)
		(layer "F.Cu")
		(net "P12V_SENSE")
	)
	(segment
		(start 70.7898 -64.57696)
		(end 70.612 -64.39916)
		(width 0.127)
		(layer "F.Cu")
		(net "P12V_SENSE")
	)
	(segment
		(start 70.612 -64.008)
		(end 70.90283 -63.71717)
		(width 0.127)
		(layer "F.Cu")
		(net "P12V_SENSE")
	)
	(segment
		(start 70.90283 -63.71717)
		(end 71.3613 -63.71717)
		(width 0.127)
		(layer "F.Cu")
		(net "P12V_SENSE")
	)
	(via
		(at 70.7898 -64.57696)
		(size 0.508)
		(drill 0.254)
		(layers "F.Cu" "B.Cu")
		(net "P12V_SENSE")
	)
	(via
		(at 67.564 -62.0268)
		(size 0.7112)
		(drill 0.3556)
		(layers "F.Cu" "B.Cu")
		(net "P12V_SENSE")
	)
	(segment
		(start 69.731382 -65.0113)
		(end 70.35546 -65.0113)
		(width 0.127)
		(layer "B.Cu")
		(net "P12V_SENSE")
	)
	(segment
		(start 69.342 -62.3062)
		(end 69.215 -62.1792)
		(width 0.127)
		(layer "B.Cu")
		(net "P12V_SENSE")
	)
	(segment
		(start 69.6468 -62.865)
		(end 69.342 -62.5602)
		(width 0.127)
		(layer "B.Cu")
		(net "P12V_SENSE")
	)
	(segment
		(start 69.6468 -64.156082)
		(end 69.4563 -64.346582)
		(width 0.127)
		(layer "B.Cu")
		(net "P12V_SENSE")
	)
	(segment
		(start 69.4563 -64.346582)
		(end 69.4563 -64.736218)
		(width 0.127)
		(layer "B.Cu")
		(net "P12V_SENSE")
	)
	(segment
		(start 69.0626 -62.0268)
		(end 69.215 -62.1792)
		(width 0.127)
		(layer "B.Cu")
		(net "P12V_SENSE")
	)
	(segment
		(start 69.342 -62.5602)
		(end 69.342 -62.3062)
		(width 0.127)
		(layer "B.Cu")
		(net "P12V_SENSE")
	)
	(segment
		(start 69.4563 -64.736218)
		(end 69.731382 -65.0113)
		(width 0.127)
		(layer "B.Cu")
		(net "P12V_SENSE")
	)
	(segment
		(start 68.453 -62.0268)
		(end 69.0626 -62.0268)
		(width 0.127)
		(layer "B.Cu")
		(net "P12V_SENSE")
	)
	(segment
		(start 68.453 -62.0268)
		(end 67.564 -62.0268)
		(width 0.127)
		(layer "B.Cu")
		(net "P12V_SENSE")
	)
	(segment
		(start 70.35546 -65.0113)
		(end 70.7898 -64.57696)
		(width 0.127)
		(layer "B.Cu")
		(net "P12V_SENSE")
	)
	(segment
		(start 69.6468 -62.865)
		(end 69.6468 -64.156082)
		(width 0.127)
		(layer "B.Cu")
		(net "P12V_SENSE")
	)
	(segment
		(start 70.8406 -57.5818)
		(end 70.8406 -56.4388)
		(width 0.127)
		(layer "F.Cu")
		(net "P1V8_SENSE")
	)
	(segment
		(start 69.4563 -59.738768)
		(end 70.2818 -58.913268)
		(width 0.127)
		(layer "F.Cu")
		(net "P1V8_SENSE")
	)
	(segment
		(start 69.637148 -61.76772)
		(end 69.4563 -61.586872)
		(width 0.127)
		(layer "F.Cu")
		(net "P1V8_SENSE")
	)
	(segment
		(start 70.8406 -56.4388)
		(end 70.0278 -55.626)
		(width 0.127)
		(layer "F.Cu")
		(net "P1V8_SENSE")
	)
	(segment
		(start 69.4563 -61.586872)
		(end 69.4563 -59.738768)
		(width 0.127)
		(layer "F.Cu")
		(net "P1V8_SENSE")
	)
	(segment
		(start 71.3613 -61.76772)
		(end 69.637148 -61.76772)
		(width 0.127)
		(layer "F.Cu")
		(net "P1V8_SENSE")
	)
	(segment
		(start 70.2818 -58.1406)
		(end 70.358 -58.0644)
		(width 0.127)
		(layer "F.Cu")
		(net "P1V8_SENSE")
	)
	(segment
		(start 70.2818 -58.913268)
		(end 70.2818 -58.1406)
		(width 0.127)
		(layer "F.Cu")
		(net "P1V8_SENSE")
	)
	(segment
		(start 70.358 -58.0644)
		(end 70.8406 -57.5818)
		(width 0.127)
		(layer "F.Cu")
		(net "P1V8_SENSE")
	)
	(via
		(at 69.637148 -61.76772)
		(size 0.7112)
		(drill 0.3556)
		(layers "F.Cu" "B.Cu")
		(net "P1V8_SENSE")
	)
	(segment
		(start 72.03948 -61.11748)
		(end 72.263 -61.341)
		(width 0.127)
		(layer "F.Cu")
		(net "PVCCP_SENSE")
	)
	(segment
		(start 72.703944 -65.388744)
		(end 77.5462 -65.388744)
		(width 0.127)
		(layer "F.Cu")
		(net "PVCCP_SENSE")
	)
	(segment
		(start 72.263 -64.9478)
		(end 72.703944 -65.388744)
		(width 0.127)
		(layer "F.Cu")
		(net "PVCCP_SENSE")
	)
	(segment
		(start 78.5876 -65.1256)
		(end 78.232 -65.4812)
		(width 0.127)
		(layer "F.Cu")
		(net "PVCCP_SENSE")
	)
	(segment
		(start 72.263 -61.341)
		(end 72.263 -64.9478)
		(width 0.127)
		(layer "F.Cu")
		(net "PVCCP_SENSE")
	)
	(segment
		(start 71.3613 -61.11748)
		(end 72.03948 -61.11748)
		(width 0.127)
		(layer "F.Cu")
		(net "PVCCP_SENSE")
	)
	(segment
		(start 78.5876 -64.4144)
		(end 78.5876 -65.1256)
		(width 0.127)
		(layer "F.Cu")
		(net "PVCCP_SENSE")
	)
	(segment
		(start 77.638656 -65.4812)
		(end 78.232 -65.4812)
		(width 0.127)
		(layer "F.Cu")
		(net "PVCCP_SENSE")
	)
	(segment
		(start 77.5462 -65.388744)
		(end 77.638656 -65.4812)
		(width 0.127)
		(layer "F.Cu")
		(net "PVCCP_SENSE")
	)
	(via
		(at 78.5876 -64.4144)
		(size 0.508)
		(drill 0.254)
		(layers "F.Cu" "B.Cu")
		(net "PVCCP_SENSE")
	)
	(via
		(at 78.5622 -63.4238)
		(size 0.7112)
		(drill 0.3556)
		(layers "F.Cu" "B.Cu")
		(net "PVCCP_SENSE")
	)
	(segment
		(start 77.47 -62.3316)
		(end 78.5622 -63.4238)
		(width 0.127)
		(layer "B.Cu")
		(net "PVCCP_SENSE")
	)
	(segment
		(start 78.5876 -63.4492)
		(end 78.5622 -63.4238)
		(width 0.127)
		(layer "B.Cu")
		(net "PVCCP_SENSE")
	)
	(segment
		(start 78.5876 -64.4144)
		(end 78.5876 -63.4492)
		(width 0.127)
		(layer "B.Cu")
		(net "PVCCP_SENSE")
	)
	(segment
		(start 75.49515 -62.860682)
		(end 75.702668 -63.0682)
		(width 0.1143)
		(layer "F.Cu")
		(net "VOL1_SEN_DATA")
	)
	(segment
		(start 75.702668 -63.0682)
		(end 76.8731 -63.0682)
		(width 0.1143)
		(layer "F.Cu")
		(net "VOL1_SEN_DATA")
	)
	(segment
		(start 75.946762 -58.293)
		(end 75.49515 -58.744612)
		(width 0.1143)
		(layer "F.Cu")
		(net "VOL1_SEN_DATA")
	)
	(segment
		(start 76.8858 -58.293)
		(end 75.946762 -58.293)
		(width 0.1143)
		(layer "F.Cu")
		(net "VOL1_SEN_DATA")
	)
	(segment
		(start 75.49515 -58.744612)
		(end 75.49515 -62.860682)
		(width 0.1143)
		(layer "F.Cu")
		(net "VOL1_SEN_DATA")
	)
	(segment
		(start 78.0542 -57.1246)
		(end 76.8858 -58.293)
		(width 0.1143)
		(layer "F.Cu")
		(net "VOL1_SEN_DATA")
	)
	(via
		(at 78.0542 -57.1246)
		(size 0.508)
		(drill 0.254)
		(layers "F.Cu" "B.Cu")
		(net "VOL1_SEN_DATA")
	)
	(via
		(at 78.48854 -58.03646)
		(size 0.7112)
		(drill 0.3556)
		(layers "F.Cu" "B.Cu")
		(net "VOL1_SEN_DATA")
	)
	(segment
		(start 78.130654 -57.1246)
		(end 78.0542 -57.1246)
		(width 0.1143)
		(layer "B.Cu")
		(net "VOL1_SEN_DATA")
	)
	(segment
		(start 78.543404 -56.71185)
		(end 78.130654 -57.1246)
		(width 0.1143)
		(layer "B.Cu")
		(net "VOL1_SEN_DATA")
	)
	(segment
		(start 78.48854 -58.03646)
		(end 79.12735 -57.39765)
		(width 0.1143)
		(layer "B.Cu")
		(net "VOL1_SEN_DATA")
	)
	(segment
		(start 75.9968 -58.674)
		(end 77.851 -58.674)
		(width 0.1143)
		(layer "B.Cu")
		(net "VOL1_SEN_DATA")
	)
	(segment
		(start 79.12735 -57.39765)
		(end 79.12735 -56.953404)
		(width 0.1143)
		(layer "B.Cu")
		(net "VOL1_SEN_DATA")
	)
	(segment
		(start 77.851 -58.674)
		(end 78.48854 -58.03646)
		(width 0.1143)
		(layer "B.Cu")
		(net "VOL1_SEN_DATA")
	)
	(segment
		(start 78.885796 -56.71185)
		(end 78.543404 -56.71185)
		(width 0.1143)
		(layer "B.Cu")
		(net "VOL1_SEN_DATA")
	)
	(segment
		(start 79.12735 -56.953404)
		(end 78.885796 -56.71185)
		(width 0.1143)
		(layer "B.Cu")
		(net "VOL1_SEN_DATA")
	)
	(segment
		(start 76.335636 -62.41796)
		(end 76.8731 -62.41796)
		(width 0.1143)
		(layer "F.Cu")
		(net "VOL1_SEN_CLK")
	)
	(segment
		(start 75.99045 -58.949844)
		(end 75.99045 -62.072774)
		(width 0.1143)
		(layer "F.Cu")
		(net "VOL1_SEN_CLK")
	)
	(segment
		(start 75.99045 -62.072774)
		(end 76.335636 -62.41796)
		(width 0.1143)
		(layer "F.Cu")
		(net "VOL1_SEN_CLK")
	)
	(segment
		(start 76.190094 -58.7502)
		(end 75.99045 -58.949844)
		(width 0.1143)
		(layer "F.Cu")
		(net "VOL1_SEN_CLK")
	)
	(segment
		(start 78.7146 -57.1246)
		(end 77.089 -58.7502)
		(width 0.1143)
		(layer "F.Cu")
		(net "VOL1_SEN_CLK")
	)
	(segment
		(start 77.089 -58.7502)
		(end 76.190094 -58.7502)
		(width 0.1143)
		(layer "F.Cu")
		(net "VOL1_SEN_CLK")
	)
	(via
		(at 77.089 -57.912)
		(size 0.7112)
		(drill 0.3556)
		(layers "F.Cu" "B.Cu")
		(net "VOL1_SEN_CLK")
	)
	(via
		(at 78.7146 -57.1246)
		(size 0.508)
		(drill 0.254)
		(layers "F.Cu" "B.Cu")
		(net "VOL1_SEN_CLK")
	)
	(segment
		(start 75.9968 -57.912)
		(end 77.089 -57.912)
		(width 0.1143)
		(layer "B.Cu")
		(net "VOL1_SEN_CLK")
	)
	(segment
		(start 78.264766 -57.49671)
		(end 78.34249 -57.49671)
		(width 0.1143)
		(layer "B.Cu")
		(net "VOL1_SEN_CLK")
	)
	(segment
		(start 78.34249 -57.49671)
		(end 78.7146 -57.1246)
		(width 0.1143)
		(layer "B.Cu")
		(net "VOL1_SEN_CLK")
	)
	(segment
		(start 77.849476 -57.912)
		(end 78.264766 -57.49671)
		(width 0.1143)
		(layer "B.Cu")
		(net "VOL1_SEN_CLK")
	)
	(segment
		(start 77.089 -57.912)
		(end 77.849476 -57.912)
		(width 0.1143)
		(layer "B.Cu")
		(net "VOL1_SEN_CLK")
	)
	(via
		(at 68.8086 -15.6718)
		(size 0.7112)
		(drill 0.3556)
		(layers "F.Cu" "B.Cu")
		(net "P1V8_STBY_VOUT")
	)
	(segment
		(start 42.4688 -49.0728)
		(end 41.783 -49.0728)
		(width 0.1143)
		(layer "F.Cu")
		(net "P3V3_CPU_DELAY_IN")
	)
	(segment
		(start 41.268904 -49.0728)
		(end 40.900604 -48.7045)
		(width 0.1143)
		(layer "F.Cu")
		(net "P3V3_CPU_DELAY_IN")
	)
	(segment
		(start 42.5704 -49.1744)
		(end 42.4688 -49.0728)
		(width 0.1143)
		(layer "F.Cu")
		(net "P3V3_CPU_DELAY_IN")
	)
	(segment
		(start 40.2082 -48.012096)
		(end 40.900604 -48.7045)
		(width 0.1143)
		(layer "F.Cu")
		(net "P3V3_CPU_DELAY_IN")
	)
	(segment
		(start 40.2082 -47.59452)
		(end 40.2082 -48.012096)
		(width 0.1143)
		(layer "F.Cu")
		(net "P3V3_CPU_DELAY_IN")
	)
	(segment
		(start 41.783 -49.0728)
		(end 41.268904 -49.0728)
		(width 0.1143)
		(layer "F.Cu")
		(net "P3V3_CPU_DELAY_IN")
	)
	(via
		(at 40.900604 -48.7045)
		(size 0.7112)
		(drill 0.3556)
		(layers "F.Cu" "B.Cu")
		(net "P3V3_CPU_DELAY_IN")
	)
	(via
		(at 176.911 -31.242)
		(size 0.7112)
		(drill 0.3556)
		(layers "F.Cu" "B.Cu")
		(net "P1V2_STBY_LDO_OUT1")
	)
	(via
		(at 176.657 -24.003)
		(size 0.7112)
		(drill 0.3556)
		(layers "F.Cu" "B.Cu")
		(net "P1V2_STBY_LDO_OUT2")
	)
	(via
		(at 169.6212 -22.8854)
		(size 0.7112)
		(drill 0.3556)
		(layers "F.Cu" "B.Cu")
		(net "P1V8_STBY_LDO_IN2")
	)
	(via
		(at 169.3672 -30.0736)
		(size 0.7112)
		(drill 0.3556)
		(layers "F.Cu" "B.Cu")
		(net "P1V8_STBY_LDO_IN1")
	)
	(via
		(at 58.801 -53.721)
		(size 0.7112)
		(drill 0.3556)
		(layers "F.Cu" "B.Cu")
		(net "P1V0_STBY_VOUT")
	)
	(segment
		(start 160.401 -29.927042)
		(end 160.401 -30.48)
		(width 0.127)
		(layer "F.Cu")
		(net "DISABLE_H")
	)
	(segment
		(start 161.34715 -32.53105)
		(end 161.34715 -31.877)
		(width 0.127)
		(layer "F.Cu")
		(net "DISABLE_H")
	)
	(segment
		(start 161.34715 -31.42615)
		(end 161.34715 -31.877)
		(width 0.127)
		(layer "F.Cu")
		(net "DISABLE_H")
	)
	(segment
		(start 160.401 -30.48)
		(end 161.34715 -31.42615)
		(width 0.127)
		(layer "F.Cu")
		(net "DISABLE_H")
	)
	(segment
		(start 161.036 -32.8422)
		(end 161.34715 -32.53105)
		(width 0.127)
		(layer "F.Cu")
		(net "DISABLE_H")
	)
	(via
		(at 161.34715 -31.877)
		(size 0.7112)
		(drill 0.3556)
		(layers "F.Cu" "B.Cu")
		(net "DISABLE_H")
	)
	(segment
		(start 173.366176 -55.741824)
		(end 173.355 -55.753)
		(width 0.127)
		(layer "F.Cu")
		(net "EEPROM_A2")
	)
	(segment
		(start 174.371 -54.2925)
		(end 174.371 -54.737)
		(width 0.127)
		(layer "F.Cu")
		(net "EEPROM_A2")
	)
	(segment
		(start 174.371 -54.737)
		(end 173.366176 -55.741824)
		(width 0.127)
		(layer "F.Cu")
		(net "EEPROM_A2")
	)
	(segment
		(start 173.355 -55.753)
		(end 173.355 -56.7182)
		(width 0.127)
		(layer "F.Cu")
		(net "EEPROM_A2")
	)
	(segment
		(start 173.355 -56.7182)
		(end 174.117 -56.7182)
		(width 0.127)
		(layer "F.Cu")
		(net "EEPROM_A2")
	)
	(via
		(at 173.366176 -55.741824)
		(size 0.7112)
		(drill 0.3556)
		(layers "F.Cu" "B.Cu")
		(net "EEPROM_A2")
	)
	(segment
		(start 176.911 -54.2925)
		(end 176.911 -55.6006)
		(width 0.127)
		(layer "F.Cu")
		(net "EEPROM_A0")
	)
	(segment
		(start 177.165 -55.8546)
		(end 177.0888 -55.7784)
		(width 0.127)
		(layer "F.Cu")
		(net "EEPROM_A0")
	)
	(segment
		(start 177.165 -56.7182)
		(end 177.165 -55.8546)
		(width 0.127)
		(layer "F.Cu")
		(net "EEPROM_A0")
	)
	(segment
		(start 176.911 -55.6006)
		(end 177.0888 -55.7784)
		(width 0.127)
		(layer "F.Cu")
		(net "EEPROM_A0")
	)
	(segment
		(start 176.403 -56.7182)
		(end 177.165 -56.7182)
		(width 0.127)
		(layer "F.Cu")
		(net "EEPROM_A0")
	)
	(via
		(at 177.0888 -55.7784)
		(size 0.7112)
		(drill 0.3556)
		(layers "F.Cu" "B.Cu")
		(net "EEPROM_A0")
	)
	(via
		(at 73.279 -49.733708)
		(size 0.7112)
		(drill 0.3556)
		(layers "F.Cu" "B.Cu")
		(net "MEMORY_HOT_N_LV_B1")
	)
	(segment
		(start 72.8726 -51.816)
		(end 72.8726 -50.8254)
		(width 0.1143)
		(layer "B.Cu")
		(net "MEMORY_HOT_N_LV_B1")
	)
	(segment
		(start 72.8726 -50.8254)
		(end 72.7202 -50.673)
		(width 0.1143)
		(layer "B.Cu")
		(net "MEMORY_HOT_N_LV_B1")
	)
	(segment
		(start 72.7202 -50.292508)
		(end 73.279 -49.733708)
		(width 0.1143)
		(layer "B.Cu")
		(net "MEMORY_HOT_N_LV_B1")
	)
	(segment
		(start 72.7202 -50.673)
		(end 72.7202 -50.292508)
		(width 0.1143)
		(layer "B.Cu")
		(net "MEMORY_HOT_N_LV_B1")
	)
	(segment
		(start 89.850468 -40.800274)
		(end 89.755726 -40.800274)
		(width 0.1143)
		(layer "F.Cu")
		(net "MEMORY_CPU_HOT#")
	)
	(segment
		(start 89.755726 -40.800274)
		(end 89.408 -41.148)
		(width 0.1143)
		(layer "F.Cu")
		(net "MEMORY_CPU_HOT#")
	)
	(via
		(at 77.6732 -48.514)
		(size 0.7112)
		(drill 0.3556)
		(layers "F.Cu" "B.Cu")
		(net "MEMORY_CPU_HOT#")
	)
	(via
		(at 89.408 -41.148)
		(size 0.4318)
		(drill 0.2032)
		(layers "F.Cu" "B.Cu")
		(net "MEMORY_CPU_HOT#")
	)
	(segment
		(start 83.072732 -43.433238)
		(end 84.572856 -43.433238)
		(width 0.1143)
		(layer "B.Cu")
		(net "MEMORY_CPU_HOT#")
	)
	(segment
		(start 84.572856 -43.433238)
		(end 84.81695 -43.189144)
		(width 0.1143)
		(layer "B.Cu")
		(net "MEMORY_CPU_HOT#")
	)
	(segment
		(start 77.6732 -48.514)
		(end 79.102458 -48.514)
		(width 0.1143)
		(layer "B.Cu")
		(net "MEMORY_CPU_HOT#")
	)
	(segment
		(start 76.327 -50.7746)
		(end 75.438 -51.6636)
		(width 0.1143)
		(layer "B.Cu")
		(net "MEMORY_CPU_HOT#")
	)
	(segment
		(start 79.102458 -48.514)
		(end 80.626458 -46.99)
		(width 0.1143)
		(layer "B.Cu")
		(net "MEMORY_CPU_HOT#")
	)
	(segment
		(start 88.270334 -41.495726)
		(end 88.95842 -41.495726)
		(width 0.1143)
		(layer "B.Cu")
		(net "MEMORY_CPU_HOT#")
	)
	(segment
		(start 77.1906 -48.514)
		(end 76.327 -49.3776)
		(width 0.1143)
		(layer "B.Cu")
		(net "MEMORY_CPU_HOT#")
	)
	(segment
		(start 80.626458 -45.879512)
		(end 83.072732 -43.433238)
		(width 0.1143)
		(layer "B.Cu")
		(net "MEMORY_CPU_HOT#")
	)
	(segment
		(start 88.95842 -41.495726)
		(end 89.3064 -41.148)
		(width 0.1143)
		(layer "B.Cu")
		(net "MEMORY_CPU_HOT#")
	)
	(segment
		(start 84.81695 -43.189144)
		(end 84.81695 -42.923206)
		(width 0.1143)
		(layer "B.Cu")
		(net "MEMORY_CPU_HOT#")
	)
	(segment
		(start 87.573358 -41.66235)
		(end 88.10371 -41.66235)
		(width 0.1143)
		(layer "B.Cu")
		(net "MEMORY_CPU_HOT#")
	)
	(segment
		(start 89.3064 -41.148)
		(end 89.408 -41.148)
		(width 0.1143)
		(layer "B.Cu")
		(net "MEMORY_CPU_HOT#")
	)
	(segment
		(start 74.7776 -52.324)
		(end 75.438 -51.6636)
		(width 0.1143)
		(layer "B.Cu")
		(net "MEMORY_CPU_HOT#")
	)
	(segment
		(start 84.81695 -42.923206)
		(end 85.036406 -42.70375)
		(width 0.1143)
		(layer "B.Cu")
		(net "MEMORY_CPU_HOT#")
	)
	(segment
		(start 76.327 -49.3776)
		(end 76.327 -50.7746)
		(width 0.1143)
		(layer "B.Cu")
		(net "MEMORY_CPU_HOT#")
	)
	(segment
		(start 80.626458 -46.99)
		(end 80.626458 -45.879512)
		(width 0.1143)
		(layer "B.Cu")
		(net "MEMORY_CPU_HOT#")
	)
	(segment
		(start 77.6732 -48.514)
		(end 77.1906 -48.514)
		(width 0.1143)
		(layer "B.Cu")
		(net "MEMORY_CPU_HOT#")
	)
	(segment
		(start 88.10371 -41.66235)
		(end 88.270334 -41.495726)
		(width 0.1143)
		(layer "B.Cu")
		(net "MEMORY_CPU_HOT#")
	)
	(segment
		(start 74.1934 -52.324)
		(end 74.7776 -52.324)
		(width 0.1143)
		(layer "B.Cu")
		(net "MEMORY_CPU_HOT#")
	)
	(segment
		(start 85.036406 -42.70375)
		(end 86.531958 -42.70375)
		(width 0.1143)
		(layer "B.Cu")
		(net "MEMORY_CPU_HOT#")
	)
	(segment
		(start 86.531958 -42.70375)
		(end 87.573358 -41.66235)
		(width 0.1143)
		(layer "B.Cu")
		(net "MEMORY_CPU_HOT#")
	)
	(via
		(at 72.2122 -54.41315)
		(size 0.7112)
		(drill 0.3556)
		(layers "F.Cu" "B.Cu")
		(net "MEMORY_HOT_LV_E1#")
	)
	(segment
		(start 73.53935 -53.444394)
		(end 72.926956 -52.832)
		(width 0.1143)
		(layer "B.Cu")
		(net "MEMORY_HOT_LV_E1#")
	)
	(segment
		(start 73.53935 -54.045104)
		(end 73.53935 -53.444394)
		(width 0.1143)
		(layer "B.Cu")
		(net "MEMORY_HOT_LV_E1#")
	)
	(segment
		(start 72.926956 -52.832)
		(end 72.8726 -52.832)
		(width 0.1143)
		(layer "B.Cu")
		(net "MEMORY_HOT_LV_E1#")
	)
	(segment
		(start 73.171304 -54.41315)
		(end 73.53935 -54.045104)
		(width 0.1143)
		(layer "B.Cu")
		(net "MEMORY_HOT_LV_E1#")
	)
	(segment
		(start 72.2122 -54.41315)
		(end 73.171304 -54.41315)
		(width 0.1143)
		(layer "B.Cu")
		(net "MEMORY_HOT_LV_E1#")
	)
	(segment
		(start 71.76135 -54.41315)
		(end 72.2122 -54.41315)
		(width 0.1143)
		(layer "B.Cu")
		(net "MEMORY_HOT_LV_E1#")
	)
	(segment
		(start 71.247 -53.8988)
		(end 71.76135 -54.41315)
		(width 0.1143)
		(layer "B.Cu")
		(net "MEMORY_HOT_LV_E1#")
	)
	(segment
		(start 131.572 -49.3014)
		(end 131.699 -49.1744)
		(width 0.1143)
		(layer "F.Cu")
		(net "MEMORY_HOT_LV_E2#")
	)
	(segment
		(start 131.699 -51.2572)
		(end 131.699 -50.419)
		(width 0.1143)
		(layer "F.Cu")
		(net "MEMORY_HOT_LV_E2#")
	)
	(segment
		(start 131.572 -50.292)
		(end 131.572 -49.3014)
		(width 0.1143)
		(layer "F.Cu")
		(net "MEMORY_HOT_LV_E2#")
	)
	(segment
		(start 131.699 -50.419)
		(end 131.572 -50.292)
		(width 0.1143)
		(layer "F.Cu")
		(net "MEMORY_HOT_LV_E2#")
	)
	(via
		(at 131.572 -50.292)
		(size 0.7112)
		(drill 0.3556)
		(layers "F.Cu" "B.Cu")
		(net "MEMORY_HOT_LV_E2#")
	)
	(segment
		(start 130.8862 -49.1744)
		(end 132.207 -47.8536)
		(width 0.1143)
		(layer "F.Cu")
		(net "MEMORY_FPGA_HOT#")
	)
	(segment
		(start 134.874 -29.972)
		(end 133.19633 -28.29433)
		(width 0.1143)
		(layer "F.Cu")
		(net "MEMORY_FPGA_HOT#")
	)
	(segment
		(start 134.874 -42.618406)
		(end 134.874 -29.972)
		(width 0.1143)
		(layer "F.Cu")
		(net "MEMORY_FPGA_HOT#")
	)
	(segment
		(start 133.19633 -28.29433)
		(end 132.1308 -28.29433)
		(width 0.1143)
		(layer "F.Cu")
		(net "MEMORY_FPGA_HOT#")
	)
	(segment
		(start 132.6896 -46.863)
		(end 132.6896 -44.802806)
		(width 0.1143)
		(layer "F.Cu")
		(net "MEMORY_FPGA_HOT#")
	)
	(segment
		(start 132.207 -47.8536)
		(end 132.6896 -47.371)
		(width 0.1143)
		(layer "F.Cu")
		(net "MEMORY_FPGA_HOT#")
	)
	(segment
		(start 132.6896 -47.371)
		(end 132.6896 -46.863)
		(width 0.1143)
		(layer "F.Cu")
		(net "MEMORY_FPGA_HOT#")
	)
	(segment
		(start 132.6896 -44.802806)
		(end 134.874 -42.618406)
		(width 0.1143)
		(layer "F.Cu")
		(net "MEMORY_FPGA_HOT#")
	)
	(segment
		(start 130.429 -49.1744)
		(end 130.8862 -49.1744)
		(width 0.1143)
		(layer "F.Cu")
		(net "MEMORY_FPGA_HOT#")
	)
	(via
		(at 132.6896 -46.863)
		(size 0.7112)
		(drill 0.3556)
		(layers "F.Cu" "B.Cu")
		(net "MEMORY_FPGA_HOT#")
	)
	(segment
		(start 132.842 -50.292)
		(end 132.842 -49.3014)
		(width 0.1143)
		(layer "F.Cu")
		(net "MEMORY_HOT_N_LV_B2")
	)
	(segment
		(start 132.715 -50.419)
		(end 132.842 -50.292)
		(width 0.1143)
		(layer "F.Cu")
		(net "MEMORY_HOT_N_LV_B2")
	)
	(segment
		(start 132.842 -49.3014)
		(end 132.715 -49.1744)
		(width 0.1143)
		(layer "F.Cu")
		(net "MEMORY_HOT_N_LV_B2")
	)
	(segment
		(start 132.715 -51.2572)
		(end 132.715 -50.419)
		(width 0.1143)
		(layer "F.Cu")
		(net "MEMORY_HOT_N_LV_B2")
	)
	(via
		(at 132.842 -50.292)
		(size 0.7112)
		(drill 0.3556)
		(layers "F.Cu" "B.Cu")
		(net "MEMORY_HOT_N_LV_B2")
	)
	(segment
		(start 165.1254 -44.8818)
		(end 164.719 -45.2882)
		(width 0.1143)
		(layer "F.Cu")
		(net "JTAG_PLD_TDO_D")
	)
	(segment
		(start 164.719 -45.2882)
		(end 164.719 -47.5996)
		(width 0.1143)
		(layer "F.Cu")
		(net "JTAG_PLD_TDO_D")
	)
	(segment
		(start 165.354 -44.8818)
		(end 165.1254 -44.8818)
		(width 0.1143)
		(layer "F.Cu")
		(net "JTAG_PLD_TDO_D")
	)
	(segment
		(start 165.5445 -45.70476)
		(end 165.5445 -45.0723)
		(width 0.1143)
		(layer "F.Cu")
		(net "JTAG_PLD_TDO_D")
	)
	(segment
		(start 165.5445 -45.0723)
		(end 165.354 -44.8818)
		(width 0.1143)
		(layer "F.Cu")
		(net "JTAG_PLD_TDO_D")
	)
	(segment
		(start 164.719 -47.5996)
		(end 164.211 -48.1076)
		(width 0.1143)
		(layer "F.Cu")
		(net "JTAG_PLD_TDO_D")
	)
	(via
		(at 165.1254 -44.8818)
		(size 0.7112)
		(drill 0.3556)
		(layers "F.Cu" "B.Cu")
		(net "JTAG_PLD_TDO_D")
	)
	(segment
		(start 162.185096 -45.24756)
		(end 162.188906 -45.24375)
		(width 0.1143)
		(layer "F.Cu")
		(net "XDP_SOC_CPU_TCK_S")
	)
	(segment
		(start 161.3281 -45.8724)
		(end 161.95294 -45.24756)
		(width 0.1143)
		(layer "F.Cu")
		(net "XDP_SOC_CPU_TCK_S")
	)
	(segment
		(start 161.3281 -46.33976)
		(end 161.3281 -45.8724)
		(width 0.1143)
		(layer "F.Cu")
		(net "XDP_SOC_CPU_TCK_S")
	)
	(segment
		(start 162.188906 -45.24375)
		(end 163.27755 -45.24375)
		(width 0.1143)
		(layer "F.Cu")
		(net "XDP_SOC_CPU_TCK_S")
	)
	(segment
		(start 163.27755 -45.24375)
		(end 163.449 -45.4152)
		(width 0.1143)
		(layer "F.Cu")
		(net "XDP_SOC_CPU_TCK_S")
	)
	(segment
		(start 161.95294 -45.24756)
		(end 162.185096 -45.24756)
		(width 0.1143)
		(layer "F.Cu")
		(net "XDP_SOC_CPU_TCK_S")
	)
	(via
		(at 162.185096 -45.24756)
		(size 0.7112)
		(drill 0.3556)
		(layers "F.Cu" "B.Cu")
		(net "XDP_SOC_CPU_TCK_S")
	)
	(segment
		(start 165.645084 -48.793654)
		(end 165.9382 -48.500538)
		(width 0.1143)
		(layer "F.Cu")
		(net "XDP_SOC_CPU_TRST#_S")
	)
	(segment
		(start 165.5445 -47.4345)
		(end 165.9382 -47.8282)
		(width 0.1143)
		(layer "F.Cu")
		(net "XDP_SOC_CPU_TRST#_S")
	)
	(segment
		(start 165.645084 -49.440592)
		(end 165.645084 -48.793654)
		(width 0.1143)
		(layer "F.Cu")
		(net "XDP_SOC_CPU_TRST#_S")
	)
	(segment
		(start 165.9382 -47.8282)
		(end 165.9382 -48.006)
		(width 0.1143)
		(layer "F.Cu")
		(net "XDP_SOC_CPU_TRST#_S")
	)
	(segment
		(start 165.5445 -47.00524)
		(end 165.5445 -47.4345)
		(width 0.1143)
		(layer "F.Cu")
		(net "XDP_SOC_CPU_TRST#_S")
	)
	(segment
		(start 165.9382 -48.500538)
		(end 165.9382 -48.006)
		(width 0.1143)
		(layer "F.Cu")
		(net "XDP_SOC_CPU_TRST#_S")
	)
	(via
		(at 165.645084 -49.440592)
		(size 0.7112)
		(drill 0.3556)
		(layers "F.Cu" "B.Cu")
		(net "XDP_SOC_CPU_TRST#_S")
	)
	(segment
		(start 159.6771 -45.3771)
		(end 159.7406 -45.3136)
		(width 0.1143)
		(layer "F.Cu")
		(net "JTAG_PLD_TCK_D")
	)
	(segment
		(start 159.6771 -46.33976)
		(end 159.6771 -45.3771)
		(width 0.1143)
		(layer "F.Cu")
		(net "JTAG_PLD_TCK_D")
	)
	(segment
		(start 161.017204 -48.2854)
		(end 161.449004 -48.7172)
		(width 0.1143)
		(layer "F.Cu")
		(net "XDP_SOC_CPU_TMS_S")
	)
	(segment
		(start 159.6771 -48.0441)
		(end 159.9184 -48.2854)
		(width 0.1143)
		(layer "F.Cu")
		(net "XDP_SOC_CPU_TMS_S")
	)
	(segment
		(start 161.925 -48.7172)
		(end 162.5092 -48.133)
		(width 0.1143)
		(layer "F.Cu")
		(net "XDP_SOC_CPU_TMS_S")
	)
	(segment
		(start 159.6771 -47.64024)
		(end 159.6771 -48.0441)
		(width 0.1143)
		(layer "F.Cu")
		(net "XDP_SOC_CPU_TMS_S")
	)
	(segment
		(start 159.9184 -48.2854)
		(end 161.017204 -48.2854)
		(width 0.1143)
		(layer "F.Cu")
		(net "XDP_SOC_CPU_TMS_S")
	)
	(segment
		(start 161.6202 -48.7172)
		(end 161.925 -48.7172)
		(width 0.1143)
		(layer "F.Cu")
		(net "XDP_SOC_CPU_TMS_S")
	)
	(segment
		(start 161.449004 -48.7172)
		(end 161.6202 -48.7172)
		(width 0.1143)
		(layer "F.Cu")
		(net "XDP_SOC_CPU_TMS_S")
	)
	(via
		(at 161.6202 -48.7172)
		(size 0.7112)
		(drill 0.3556)
		(layers "F.Cu" "B.Cu")
		(net "XDP_SOC_CPU_TMS_S")
	)
	(segment
		(start 163.83 -46.7868)
		(end 164.211 -46.4058)
		(width 0.1143)
		(layer "F.Cu")
		(net "JTAG_PLD_TMS_D")
	)
	(segment
		(start 164.211 -46.4058)
		(end 164.211 -46.2788)
		(width 0.1143)
		(layer "F.Cu")
		(net "JTAG_PLD_TMS_D")
	)
	(segment
		(start 162.06216 -47.64024)
		(end 162.9156 -46.7868)
		(width 0.1143)
		(layer "F.Cu")
		(net "JTAG_PLD_TMS_D")
	)
	(segment
		(start 162.9156 -46.7868)
		(end 163.83 -46.7868)
		(width 0.1143)
		(layer "F.Cu")
		(net "JTAG_PLD_TMS_D")
	)
	(segment
		(start 161.3281 -47.64024)
		(end 162.06216 -47.64024)
		(width 0.1143)
		(layer "F.Cu")
		(net "JTAG_PLD_TMS_D")
	)
	(segment
		(start 159.8422 -48.768)
		(end 159.219646 -49.390554)
		(width 0.1143)
		(layer "F.Cu")
		(net "XDP_SOC_CPU_TDO_S")
	)
	(segment
		(start 158.549086 -48.44796)
		(end 158.549086 -48.888396)
		(width 0.1143)
		(layer "F.Cu")
		(net "XDP_SOC_CPU_TDO_S")
	)
	(segment
		(start 159.219646 -49.390554)
		(end 159.051244 -49.390554)
		(width 0.1143)
		(layer "F.Cu")
		(net "XDP_SOC_CPU_TDO_S")
	)
	(segment
		(start 158.549086 -48.888396)
		(end 159.051244 -49.390554)
		(width 0.1143)
		(layer "F.Cu")
		(net "XDP_SOC_CPU_TDO_S")
	)
	(via
		(at 159.051244 -49.390554)
		(size 0.7112)
		(drill 0.3556)
		(layers "F.Cu" "B.Cu")
		(net "XDP_SOC_CPU_TDO_S")
	)
	(segment
		(start 168.91 -46.355)
		(end 169.291 -46.736)
		(width 0.127)
		(layer "F.Cu")
		(net "JTAG_CHAIN_EN")
	)
	(segment
		(start 158.9532 -46.143926)
		(end 158.9532 -45.339)
		(width 0.127)
		(layer "F.Cu")
		(net "JTAG_CHAIN_EN")
	)
	(segment
		(start 169.291 -49.3268)
		(end 169.291 -46.736)
		(width 0.127)
		(layer "F.Cu")
		(net "JTAG_CHAIN_EN")
	)
	(segment
		(start 158.991046 -46.99)
		(end 158.549086 -46.54804)
		(width 0.127)
		(layer "F.Cu")
		(net "JTAG_CHAIN_EN")
	)
	(segment
		(start 167.1955 -46.355)
		(end 168.91 -46.355)
		(width 0.127)
		(layer "F.Cu")
		(net "JTAG_CHAIN_EN")
	)
	(segment
		(start 159.0802 -50.3555)
		(end 157.990286 -49.265586)
		(width 0.127)
		(layer "F.Cu")
		(net "JTAG_CHAIN_EN")
	)
	(segment
		(start 168.0464 -50.1142)
		(end 168.5036 -50.1142)
		(width 0.127)
		(layer "F.Cu")
		(net "JTAG_CHAIN_EN")
	)
	(segment
		(start 168.5036 -50.1142)
		(end 169.291 -49.3268)
		(width 0.127)
		(layer "F.Cu")
		(net "JTAG_CHAIN_EN")
	)
	(segment
		(start 157.990286 -49.265586)
		(end 157.990286 -47.10684)
		(width 0.127)
		(layer "F.Cu")
		(net "JTAG_CHAIN_EN")
	)
	(segment
		(start 165.5445 -46.355)
		(end 167.1955 -46.355)
		(width 0.127)
		(layer "F.Cu")
		(net "JTAG_CHAIN_EN")
	)
	(segment
		(start 161.3281 -46.99)
		(end 159.6771 -46.99)
		(width 0.127)
		(layer "F.Cu")
		(net "JTAG_CHAIN_EN")
	)
	(segment
		(start 158.549086 -46.54804)
		(end 158.9532 -46.143926)
		(width 0.127)
		(layer "F.Cu")
		(net "JTAG_CHAIN_EN")
	)
	(segment
		(start 159.6771 -46.99)
		(end 158.991046 -46.99)
		(width 0.127)
		(layer "F.Cu")
		(net "JTAG_CHAIN_EN")
	)
	(segment
		(start 157.990286 -47.10684)
		(end 158.549086 -46.54804)
		(width 0.127)
		(layer "F.Cu")
		(net "JTAG_CHAIN_EN")
	)
	(via
		(at 168.0464 -50.1142)
		(size 0.508)
		(drill 0.254)
		(layers "F.Cu" "B.Cu")
		(net "JTAG_CHAIN_EN")
	)
	(via
		(at 159.0802 -50.3555)
		(size 0.508)
		(drill 0.254)
		(layers "F.Cu" "B.Cu")
		(net "JTAG_CHAIN_EN")
	)
	(via
		(at 167.3352 -50.8254)
		(size 0.7112)
		(drill 0.3556)
		(layers "F.Cu" "B.Cu")
		(net "JTAG_CHAIN_EN")
	)
	(segment
		(start 167.3352 -50.8254)
		(end 168.0464 -50.1142)
		(width 0.127)
		(layer "B.Cu")
		(net "JTAG_CHAIN_EN")
	)
	(segment
		(start 159.0802 -50.3555)
		(end 159.276796 -50.552096)
		(width 0.127)
		(layer "B.Cu")
		(net "JTAG_CHAIN_EN")
	)
	(segment
		(start 159.2961 -50.552096)
		(end 159.582104 -50.8381)
		(width 0.127)
		(layer "B.Cu")
		(net "JTAG_CHAIN_EN")
	)
	(segment
		(start 159.582104 -50.8381)
		(end 167.3225 -50.8381)
		(width 0.127)
		(layer "B.Cu")
		(net "JTAG_CHAIN_EN")
	)
	(segment
		(start 159.276796 -50.552096)
		(end 159.2961 -50.552096)
		(width 0.127)
		(layer "B.Cu")
		(net "JTAG_CHAIN_EN")
	)
	(segment
		(start 167.3225 -50.8381)
		(end 167.3352 -50.8254)
		(width 0.127)
		(layer "B.Cu")
		(net "JTAG_CHAIN_EN")
	)
	(segment
		(start 18.590006 -57.019952)
		(end 18.184114 -57.019952)
		(width 0.2032)
		(layer "F.Cu")
		(net "PVCCP_PVNN_R_VRHOT#")
	)
	(segment
		(start 18.184114 -57.019952)
		(end 17.980406 -56.816244)
		(width 0.2032)
		(layer "F.Cu")
		(net "PVCCP_PVNN_R_VRHOT#")
	)
	(segment
		(start 16.662146 -54.991)
		(end 16.451072 -54.779926)
		(width 0.2032)
		(layer "F.Cu")
		(net "PVCCP_PVNN_R_VRHOT#")
	)
	(segment
		(start 17.018 -54.991)
		(end 16.662146 -54.991)
		(width 0.2032)
		(layer "F.Cu")
		(net "PVCCP_PVNN_R_VRHOT#")
	)
	(segment
		(start 17.980406 -55.953406)
		(end 17.018 -54.991)
		(width 0.2032)
		(layer "F.Cu")
		(net "PVCCP_PVNN_R_VRHOT#")
	)
	(segment
		(start 17.980406 -56.816244)
		(end 17.980406 -55.953406)
		(width 0.2032)
		(layer "F.Cu")
		(net "PVCCP_PVNN_R_VRHOT#")
	)
	(segment
		(start 16.2814 -54.610254)
		(end 16.451072 -54.779926)
		(width 0.2032)
		(layer "F.Cu")
		(net "PVCCP_PVNN_R_VRHOT#")
	)
	(segment
		(start 16.2814 -53.7972)
		(end 16.2814 -54.610254)
		(width 0.2032)
		(layer "F.Cu")
		(net "PVCCP_PVNN_R_VRHOT#")
	)
	(via
		(at 16.451072 -54.779926)
		(size 0.7112)
		(drill 0.3556)
		(layers "F.Cu" "B.Cu")
		(net "PVCCP_PVNN_R_VRHOT#")
	)
	(segment
		(start 186.856116 -35.37585)
		(end 186.538362 -35.37585)
		(width 0.1143)
		(layer "F.Cu")
		(net "SVID_A_ALERT#")
	)
	(segment
		(start 184.281318 -38.1)
		(end 185.113168 -37.26815)
		(width 0.1143)
		(layer "F.Cu")
		(net "SVID_A_ALERT#")
	)
	(segment
		(start 185.113168 -37.26815)
		(end 185.227722 -37.26815)
		(width 0.1143)
		(layer "F.Cu")
		(net "SVID_A_ALERT#")
	)
	(segment
		(start 186.316366 -35.597846)
		(end 186.316366 -36.179506)
		(width 0.1143)
		(layer "F.Cu")
		(net "SVID_A_ALERT#")
	)
	(segment
		(start 185.227722 -37.26815)
		(end 185.619136 -36.876736)
		(width 0.1143)
		(layer "F.Cu")
		(net "SVID_A_ALERT#")
	)
	(segment
		(start 184.0738 -38.1)
		(end 184.281318 -38.1)
		(width 0.1143)
		(layer "F.Cu")
		(net "SVID_A_ALERT#")
	)
	(segment
		(start 186.316366 -36.179506)
		(end 185.619136 -36.876736)
		(width 0.1143)
		(layer "F.Cu")
		(net "SVID_A_ALERT#")
	)
	(segment
		(start 186.538362 -35.37585)
		(end 186.316366 -35.597846)
		(width 0.1143)
		(layer "F.Cu")
		(net "SVID_A_ALERT#")
	)
	(via
		(at 185.619136 -36.876736)
		(size 0.7112)
		(drill 0.3556)
		(layers "F.Cu" "B.Cu")
		(net "SVID_A_ALERT#")
	)
	(segment
		(start 73.940924 -21.50745)
		(end 74.429874 -21.9964)
		(width 0.127)
		(layer "F.Cu")
		(net "MSATA_PRESENT#")
	)
	(segment
		(start 77.476604 -24.605996)
		(end 77.0636 -25.019)
		(width 0.127)
		(layer "F.Cu")
		(net "MSATA_PRESENT#")
	)
	(segment
		(start 68.58 -20.6502)
		(end 69.088 -20.6502)
		(width 0.127)
		(layer "F.Cu")
		(net "MSATA_PRESENT#")
	)
	(segment
		(start 71.280274 -21.082)
		(end 71.705724 -21.50745)
		(width 0.127)
		(layer "F.Cu")
		(net "MSATA_PRESENT#")
	)
	(segment
		(start 83.571588 -31.860998)
		(end 83.573874 -31.858712)
		(width 0.127)
		(layer "F.Cu")
		(net "MSATA_PRESENT#")
	)
	(segment
		(start 69.5198 -21.082)
		(end 71.280274 -21.082)
		(width 0.127)
		(layer "F.Cu")
		(net "MSATA_PRESENT#")
	)
	(segment
		(start 77.476604 -23.975568)
		(end 77.476604 -24.605996)
		(width 0.127)
		(layer "F.Cu")
		(net "MSATA_PRESENT#")
	)
	(segment
		(start 69.088 -20.6502)
		(end 69.5198 -21.082)
		(width 0.127)
		(layer "F.Cu")
		(net "MSATA_PRESENT#")
	)
	(segment
		(start 74.429874 -21.9964)
		(end 75.497436 -21.9964)
		(width 0.127)
		(layer "F.Cu")
		(net "MSATA_PRESENT#")
	)
	(segment
		(start 71.705724 -21.50745)
		(end 73.940924 -21.50745)
		(width 0.127)
		(layer "F.Cu")
		(net "MSATA_PRESENT#")
	)
	(segment
		(start 83.647788 -32.771334)
		(end 83.571588 -32.695134)
		(width 0.127)
		(layer "F.Cu")
		(net "MSATA_PRESENT#")
	)
	(segment
		(start 75.497436 -21.9964)
		(end 77.476604 -23.975568)
		(width 0.127)
		(layer "F.Cu")
		(net "MSATA_PRESENT#")
	)
	(segment
		(start 83.571588 -32.695134)
		(end 83.571588 -31.860998)
		(width 0.127)
		(layer "F.Cu")
		(net "MSATA_PRESENT#")
	)
	(via
		(at 80.607408 -29.628592)
		(size 0.7112)
		(drill 0.3556)
		(layers "F.Cu" "B.Cu")
		(net "MSATA_PRESENT#")
	)
	(via
		(at 77.0636 -25.019)
		(size 0.508)
		(drill 0.254)
		(layers "F.Cu" "B.Cu")
		(net "MSATA_PRESENT#")
	)
	(via
		(at 83.573874 -31.858712)
		(size 0.4318)
		(drill 0.2032)
		(layers "F.Cu" "B.Cu")
		(net "MSATA_PRESENT#")
	)
	(segment
		(start 79.253588 -27.7114)
		(end 78.43393 -27.7114)
		(width 0.127)
		(layer "B.Cu")
		(net "MSATA_PRESENT#")
	)
	(segment
		(start 78.43393 -27.7114)
		(end 76.846176 -26.123646)
		(width 0.127)
		(layer "B.Cu")
		(net "MSATA_PRESENT#")
	)
	(segment
		(start 83.547712 -31.858712)
		(end 83.573874 -31.858712)
		(width 0.127)
		(layer "B.Cu")
		(net "MSATA_PRESENT#")
	)
	(segment
		(start 79.549752 -28.007564)
		(end 79.253588 -27.7114)
		(width 0.127)
		(layer "B.Cu")
		(net "MSATA_PRESENT#")
	)
	(segment
		(start 76.846176 -26.123646)
		(end 76.846176 -25.236424)
		(width 0.127)
		(layer "B.Cu")
		(net "MSATA_PRESENT#")
	)
	(segment
		(start 82.449416 -31.4706)
		(end 83.1596 -31.4706)
		(width 0.127)
		(layer "B.Cu")
		(net "MSATA_PRESENT#")
	)
	(segment
		(start 83.1596 -31.4706)
		(end 83.547712 -31.858712)
		(width 0.127)
		(layer "B.Cu")
		(net "MSATA_PRESENT#")
	)
	(segment
		(start 80.607408 -29.628592)
		(end 82.449416 -31.4706)
		(width 0.127)
		(layer "B.Cu")
		(net "MSATA_PRESENT#")
	)
	(segment
		(start 79.549752 -28.570936)
		(end 79.549752 -28.007564)
		(width 0.127)
		(layer "B.Cu")
		(net "MSATA_PRESENT#")
	)
	(segment
		(start 76.846176 -25.236424)
		(end 77.0636 -25.019)
		(width 0.127)
		(layer "B.Cu")
		(net "MSATA_PRESENT#")
	)
	(segment
		(start 80.607408 -29.628592)
		(end 79.549752 -28.570936)
		(width 0.127)
		(layer "B.Cu")
		(net "MSATA_PRESENT#")
	)
	(segment
		(start 176.6316 -47.8917)
		(end 176.6062 -47.9171)
		(width 0.1143)
		(layer "F.Cu")
		(net "EEPROM_WP")
	)
	(segment
		(start 176.6316 -47.0662)
		(end 176.6316 -47.8917)
		(width 0.1143)
		(layer "F.Cu")
		(net "EEPROM_WP")
	)
	(segment
		(start 176.5046 -46.9392)
		(end 176.6316 -47.0662)
		(width 0.1143)
		(layer "F.Cu")
		(net "EEPROM_WP")
	)
	(segment
		(start 175.641 -48.9204)
		(end 175.641 -49.3395)
		(width 0.1143)
		(layer "F.Cu")
		(net "EEPROM_WP")
	)
	(segment
		(start 176.6062 -47.9171)
		(end 176.6062 -47.9552)
		(width 0.1143)
		(layer "F.Cu")
		(net "EEPROM_WP")
	)
	(segment
		(start 176.6062 -47.9552)
		(end 175.641 -48.9204)
		(width 0.1143)
		(layer "F.Cu")
		(net "EEPROM_WP")
	)
	(via
		(at 176.6062 -47.9171)
		(size 0.7112)
		(drill 0.3556)
		(layers "F.Cu" "B.Cu")
		(net "EEPROM_WP")
	)
	(segment
		(start 175.7426 -47.521876)
		(end 175.3616 -47.902876)
		(width 0.1143)
		(layer "F.Cu")
		(net "EEPROM_CLK")
	)
	(segment
		(start 174.371 -48.893476)
		(end 174.371 -49.3395)
		(width 0.1143)
		(layer "F.Cu")
		(net "EEPROM_CLK")
	)
	(segment
		(start 175.7426 -46.9392)
		(end 175.7426 -47.521876)
		(width 0.1143)
		(layer "F.Cu")
		(net "EEPROM_CLK")
	)
	(segment
		(start 175.3616 -47.902876)
		(end 175.3616 -47.9044)
		(width 0.1143)
		(layer "F.Cu")
		(net "EEPROM_CLK")
	)
	(segment
		(start 175.3616 -47.9044)
		(end 175.360076 -47.9044)
		(width 0.1143)
		(layer "F.Cu")
		(net "EEPROM_CLK")
	)
	(segment
		(start 175.360076 -47.9044)
		(end 174.371 -48.893476)
		(width 0.1143)
		(layer "F.Cu")
		(net "EEPROM_CLK")
	)
	(via
		(at 175.3616 -47.9044)
		(size 0.7112)
		(drill 0.3556)
		(layers "F.Cu" "B.Cu")
		(net "EEPROM_CLK")
	)
	(segment
		(start 173.101 -46.6598)
		(end 173.101 -47.5742)
		(width 0.1143)
		(layer "F.Cu")
		(net "EEPROM_DATA")
	)
	(segment
		(start 172.9232 -46.482)
		(end 173.101 -46.6598)
		(width 0.1143)
		(layer "F.Cu")
		(net "EEPROM_DATA")
	)
	(segment
		(start 173.101 -49.3395)
		(end 173.101 -47.5742)
		(width 0.1143)
		(layer "F.Cu")
		(net "EEPROM_DATA")
	)
	(via
		(at 173.101 -47.5742)
		(size 0.7112)
		(drill 0.3556)
		(layers "F.Cu" "B.Cu")
		(net "EEPROM_DATA")
	)
	(segment
		(start 175.641 -55.753)
		(end 175.641 -56.7182)
		(width 0.127)
		(layer "F.Cu")
		(net "EEPROM_A1")
	)
	(segment
		(start 175.641 -56.7182)
		(end 174.879 -56.7182)
		(width 0.127)
		(layer "F.Cu")
		(net "EEPROM_A1")
	)
	(segment
		(start 175.641 -54.2925)
		(end 175.641 -55.753)
		(width 0.127)
		(layer "F.Cu")
		(net "EEPROM_A1")
	)
	(via
		(at 175.641 -55.753)
		(size 0.7112)
		(drill 0.3556)
		(layers "F.Cu" "B.Cu")
		(net "EEPROM_A1")
	)
	(segment
		(start 44.71924 -39.48176)
		(end 45.38472 -39.48176)
		(width 0.1143)
		(layer "F.Cu")
		(net "CLK_GEN_DELAY1_PG")
	)
	(segment
		(start 43.9166 -42.545)
		(end 44.2214 -42.2402)
		(width 0.1143)
		(layer "F.Cu")
		(net "CLK_GEN_DELAY1_PG")
	)
	(segment
		(start 44.2214 -42.2402)
		(end 44.2214 -39.9796)
		(width 0.1143)
		(layer "F.Cu")
		(net "CLK_GEN_DELAY1_PG")
	)
	(segment
		(start 44.2214 -39.9796)
		(end 44.71924 -39.48176)
		(width 0.1143)
		(layer "F.Cu")
		(net "CLK_GEN_DELAY1_PG")
	)
	(segment
		(start 43.51528 -42.545)
		(end 43.9166 -42.545)
		(width 0.1143)
		(layer "F.Cu")
		(net "CLK_GEN_DELAY1_PG")
	)
	(segment
		(start 43.05046 -40.132)
		(end 42.716958 -39.798498)
		(width 0.1143)
		(layer "F.Cu")
		(net "CLK_GEN_DELAY0_PG")
	)
	(segment
		(start 42.716958 -39.795958)
		(end 42.5196 -39.5986)
		(width 0.1143)
		(layer "F.Cu")
		(net "CLK_GEN_DELAY0_PG")
	)
	(segment
		(start 43.51528 -40.132)
		(end 43.05046 -40.132)
		(width 0.1143)
		(layer "F.Cu")
		(net "CLK_GEN_DELAY0_PG")
	)
	(segment
		(start 41.7322 -39.4208)
		(end 42.3418 -39.4208)
		(width 0.1143)
		(layer "F.Cu")
		(net "CLK_GEN_DELAY0_PG")
	)
	(segment
		(start 41.7322 -39.4208)
		(end 41.7322 -40.3098)
		(width 0.1143)
		(layer "F.Cu")
		(net "CLK_GEN_DELAY0_PG")
	)
	(segment
		(start 42.716958 -39.798498)
		(end 42.716958 -39.795958)
		(width 0.1143)
		(layer "F.Cu")
		(net "CLK_GEN_DELAY0_PG")
	)
	(segment
		(start 42.3418 -39.4208)
		(end 42.5196 -39.5986)
		(width 0.1143)
		(layer "F.Cu")
		(net "CLK_GEN_DELAY0_PG")
	)
	(via
		(at 41.7322 -40.3098)
		(size 0.7112)
		(drill 0.3556)
		(layers "F.Cu" "B.Cu")
		(net "CLK_GEN_DELAY0_PG")
	)
	(segment
		(start 44.596558 -42.195242)
		(end 44.89704 -41.89476)
		(width 0.1143)
		(layer "F.Cu")
		(net "CLK_GEN_DELAY2_PG")
	)
	(segment
		(start 44.08043 -43.44797)
		(end 44.596558 -42.931842)
		(width 0.1143)
		(layer "F.Cu")
		(net "CLK_GEN_DELAY2_PG")
	)
	(segment
		(start 43.943524 -43.5864)
		(end 44.08043 -43.449494)
		(width 0.1143)
		(layer "F.Cu")
		(net "CLK_GEN_DELAY2_PG")
	)
	(segment
		(start 44.596558 -42.931842)
		(end 44.596558 -42.195242)
		(width 0.1143)
		(layer "F.Cu")
		(net "CLK_GEN_DELAY2_PG")
	)
	(segment
		(start 44.89704 -41.89476)
		(end 45.38472 -41.89476)
		(width 0.1143)
		(layer "F.Cu")
		(net "CLK_GEN_DELAY2_PG")
	)
	(segment
		(start 42.6466 -43.5864)
		(end 43.943524 -43.5864)
		(width 0.1143)
		(layer "F.Cu")
		(net "CLK_GEN_DELAY2_PG")
	)
	(segment
		(start 42.418 -43.3578)
		(end 42.6466 -43.5864)
		(width 0.1143)
		(layer "F.Cu")
		(net "CLK_GEN_DELAY2_PG")
	)
	(segment
		(start 44.08043 -43.449494)
		(end 44.08043 -43.44797)
		(width 0.1143)
		(layer "F.Cu")
		(net "CLK_GEN_DELAY2_PG")
	)
	(segment
		(start 16.970502 -57.908698)
		(end 16.51 -58.3692)
		(width 0.254)
		(layer "F.Cu")
		(net "PVCC_PVNN_EN_R")
	)
	(segment
		(start 18.590006 -58.220102)
		(end 17.910302 -58.220102)
		(width 0.2032)
		(layer "F.Cu")
		(net "PVCC_PVNN_EN_R")
	)
	(segment
		(start 17.910302 -58.220102)
		(end 17.598898 -57.908698)
		(width 0.2032)
		(layer "F.Cu")
		(net "PVCC_PVNN_EN_R")
	)
	(segment
		(start 16.51 -58.3692)
		(end 16.2814 -58.3692)
		(width 0.254)
		(layer "F.Cu")
		(net "PVCC_PVNN_EN_R")
	)
	(segment
		(start 16.2814 -57.6072)
		(end 16.2814 -56.8452)
		(width 0.254)
		(layer "F.Cu")
		(net "PVCC_PVNN_EN_R")
	)
	(segment
		(start 17.598898 -57.908698)
		(end 17.224502 -57.908698)
		(width 0.2032)
		(layer "F.Cu")
		(net "PVCC_PVNN_EN_R")
	)
	(segment
		(start 16.2814 -58.3692)
		(end 16.2814 -57.6072)
		(width 0.254)
		(layer "F.Cu")
		(net "PVCC_PVNN_EN_R")
	)
	(segment
		(start 17.224502 -57.908698)
		(end 16.970502 -57.908698)
		(width 0.254)
		(layer "F.Cu")
		(net "PVCC_PVNN_EN_R")
	)
	(via
		(at 17.224502 -57.908698)
		(size 0.7112)
		(drill 0.3556)
		(layers "F.Cu" "B.Cu")
		(net "PVCC_PVNN_EN_R")
	)
	(segment
		(start 49.915572 -46.4312)
		(end 50.292 -46.4312)
		(width 0.254)
		(layer "F.Cu")
		(net "SW_P3V3_CPU_LV_G2")
	)
	(segment
		(start 50.292 -46.4312)
		(end 50.8 -45.9232)
		(width 0.254)
		(layer "F.Cu")
		(net "SW_P3V3_CPU_LV_G2")
	)
	(segment
		(start 51.562 -45.4914)
		(end 52.197 -45.4914)
		(width 0.254)
		(layer "F.Cu")
		(net "SW_P3V3_CPU_LV_G2")
	)
	(segment
		(start 52.451 -45.2374)
		(end 52.451 -44.6405)
		(width 0.254)
		(layer "F.Cu")
		(net "SW_P3V3_CPU_LV_G2")
	)
	(segment
		(start 50.8 -45.9232)
		(end 51.1302 -45.9232)
		(width 0.254)
		(layer "F.Cu")
		(net "SW_P3V3_CPU_LV_G2")
	)
	(segment
		(start 51.1302 -45.9232)
		(end 51.562 -45.4914)
		(width 0.254)
		(layer "F.Cu")
		(net "SW_P3V3_CPU_LV_G2")
	)
	(segment
		(start 52.197 -45.4914)
		(end 52.451 -45.2374)
		(width 0.254)
		(layer "F.Cu")
		(net "SW_P3V3_CPU_LV_G2")
	)
	(via
		(at 49.915572 -46.4312)
		(size 0.7112)
		(drill 0.3556)
		(layers "F.Cu" "B.Cu")
		(net "SW_P3V3_CPU_LV_G2")
	)
	(segment
		(start 53.975 -43.434)
		(end 54.356 -43.434)
		(width 0.254)
		(layer "F.Cu")
		(net "SW_P3V3_CPU_EN_LV_D")
	)
	(segment
		(start 49.2506 -46.198028)
		(end 49.728628 -45.72)
		(width 0.254)
		(layer "F.Cu")
		(net "SW_P3V3_CPU_EN_LV_D")
	)
	(segment
		(start 51.22037 -43.9039)
		(end 52.73421 -43.9039)
		(width 0.254)
		(layer "F.Cu")
		(net "SW_P3V3_CPU_EN_LV_D")
	)
	(segment
		(start 53.10124 -44.27093)
		(end 53.10124 -44.30776)
		(width 0.254)
		(layer "F.Cu")
		(net "SW_P3V3_CPU_EN_LV_D")
	)
	(segment
		(start 46.609 -47.9552)
		(end 47.6504 -47.9552)
		(width 0.254)
		(layer "F.Cu")
		(net "SW_P3V3_CPU_EN_LV_D")
	)
	(segment
		(start 53.10124 -44.30776)
		(end 53.10124 -44.6405)
		(width 0.254)
		(layer "F.Cu")
		(net "SW_P3V3_CPU_EN_LV_D")
	)
	(segment
		(start 52.73421 -43.9039)
		(end 53.10124 -44.27093)
		(width 0.254)
		(layer "F.Cu")
		(net "SW_P3V3_CPU_EN_LV_D")
	)
	(segment
		(start 45.32376 -47.9552)
		(end 46.609 -47.9552)
		(width 0.254)
		(layer "F.Cu")
		(net "SW_P3V3_CPU_EN_LV_D")
	)
	(segment
		(start 49.728628 -45.72)
		(end 50.12182 -45.72)
		(width 0.254)
		(layer "F.Cu")
		(net "SW_P3V3_CPU_EN_LV_D")
	)
	(segment
		(start 50.12182 -45.72)
		(end 50.418746 -45.423074)
		(width 0.254)
		(layer "F.Cu")
		(net "SW_P3V3_CPU_EN_LV_D")
	)
	(segment
		(start 48.061626 -47.9552)
		(end 49.2506 -46.766226)
		(width 0.254)
		(layer "F.Cu")
		(net "SW_P3V3_CPU_EN_LV_D")
	)
	(segment
		(start 55.1942 -44.2722)
		(end 54.356 -43.434)
		(width 0.254)
		(layer "F.Cu")
		(net "SW_P3V3_CPU_EN_LV_D")
	)
	(segment
		(start 49.2506 -46.766226)
		(end 49.2506 -46.198028)
		(width 0.254)
		(layer "F.Cu")
		(net "SW_P3V3_CPU_EN_LV_D")
	)
	(segment
		(start 50.418746 -45.423074)
		(end 50.418746 -44.705524)
		(width 0.254)
		(layer "F.Cu")
		(net "SW_P3V3_CPU_EN_LV_D")
	)
	(segment
		(start 53.10124 -44.30776)
		(end 53.975 -43.434)
		(width 0.254)
		(layer "F.Cu")
		(net "SW_P3V3_CPU_EN_LV_D")
	)
	(segment
		(start 45.27296 -48.006)
		(end 45.32376 -47.9552)
		(width 0.254)
		(layer "F.Cu")
		(net "SW_P3V3_CPU_EN_LV_D")
	)
	(segment
		(start 47.6504 -47.9552)
		(end 48.061626 -47.9552)
		(width 0.254)
		(layer "F.Cu")
		(net "SW_P3V3_CPU_EN_LV_D")
	)
	(segment
		(start 50.418746 -44.705524)
		(end 51.22037 -43.9039)
		(width 0.254)
		(layer "F.Cu")
		(net "SW_P3V3_CPU_EN_LV_D")
	)
	(segment
		(start 55.1942 -45.847)
		(end 55.1942 -44.2722)
		(width 0.254)
		(layer "F.Cu")
		(net "SW_P3V3_CPU_EN_LV_D")
	)
	(via
		(at 47.6504 -47.9552)
		(size 0.7112)
		(drill 0.3556)
		(layers "F.Cu" "B.Cu")
		(net "SW_P3V3_CPU_EN_LV_D")
	)
	(segment
		(start 53.391308 -47.1678)
		(end 53.645308 -47.4218)
		(width 0.254)
		(layer "F.Cu")
		(net "SW_P3V3_CPU_LV_G5")
	)
	(segment
		(start 52.705 -47.1678)
		(end 53.391308 -47.1678)
		(width 0.254)
		(layer "F.Cu")
		(net "SW_P3V3_CPU_LV_G5")
	)
	(segment
		(start 51.80076 -46.2915)
		(end 51.80076 -46.97476)
		(width 0.254)
		(layer "F.Cu")
		(net "SW_P3V3_CPU_LV_G5")
	)
	(segment
		(start 55.1942 -46.609)
		(end 54.374542 -47.428658)
		(width 0.254)
		(layer "F.Cu")
		(net "SW_P3V3_CPU_LV_G5")
	)
	(segment
		(start 51.9938 -47.1678)
		(end 52.705 -47.1678)
		(width 0.254)
		(layer "F.Cu")
		(net "SW_P3V3_CPU_LV_G5")
	)
	(segment
		(start 54.374542 -47.428658)
		(end 53.645308 -47.428658)
		(width 0.254)
		(layer "F.Cu")
		(net "SW_P3V3_CPU_LV_G5")
	)
	(segment
		(start 52.451 -46.2915)
		(end 52.451 -46.9138)
		(width 0.254)
		(layer "F.Cu")
		(net "SW_P3V3_CPU_LV_G5")
	)
	(segment
		(start 53.645308 -47.4218)
		(end 53.645308 -47.428658)
		(width 0.254)
		(layer "F.Cu")
		(net "SW_P3V3_CPU_LV_G5")
	)
	(segment
		(start 52.451 -46.9138)
		(end 52.705 -47.1678)
		(width 0.254)
		(layer "F.Cu")
		(net "SW_P3V3_CPU_LV_G5")
	)
	(segment
		(start 51.80076 -46.97476)
		(end 51.9938 -47.1678)
		(width 0.254)
		(layer "F.Cu")
		(net "SW_P3V3_CPU_LV_G5")
	)
	(via
		(at 53.645308 -47.428658)
		(size 0.7112)
		(drill 0.3556)
		(layers "F.Cu" "B.Cu")
		(net "SW_P3V3_CPU_LV_G5")
	)
	(segment
		(start 56.515 -40.63746)
		(end 56.69026 -40.4622)
		(width 0.254)
		(layer "F.Cu")
		(net "SW_P3V3_LV_G5")
	)
	(segment
		(start 56.69026 -40.4622)
		(end 57.01284 -40.4622)
		(width 0.254)
		(layer "F.Cu")
		(net "SW_P3V3_LV_G5")
	)
	(segment
		(start 57.87898 -43.244008)
		(end 57.879234 -43.243754)
		(width 0.254)
		(layer "F.Cu")
		(net "SW_P3V3_LV_G5")
	)
	(segment
		(start 58.3692 -41.783)
		(end 58.3692 -40.9448)
		(width 0.254)
		(layer "F.Cu")
		(net "SW_P3V3_LV_G5")
	)
	(segment
		(start 58.3692 -42.763694)
		(end 58.3692 -41.783)
		(width 0.254)
		(layer "F.Cu")
		(net "SW_P3V3_LV_G5")
	)
	(segment
		(start 58.293 -40.8686)
		(end 58.2676 -40.894)
		(width 0.254)
		(layer "F.Cu")
		(net "SW_P3V3_LV_G5")
	)
	(segment
		(start 57.9374 -40.894)
		(end 57.6199 -41.2115)
		(width 0.254)
		(layer "F.Cu")
		(net "SW_P3V3_LV_G5")
	)
	(segment
		(start 58.3692 -40.9448)
		(end 58.293 -40.8686)
		(width 0.254)
		(layer "F.Cu")
		(net "SW_P3V3_LV_G5")
	)
	(segment
		(start 57.879234 -43.243754)
		(end 57.88914 -43.243754)
		(width 0.254)
		(layer "F.Cu")
		(net "SW_P3V3_LV_G5")
	)
	(segment
		(start 57.01284 -40.4622)
		(end 57.16524 -40.6146)
		(width 0.254)
		(layer "F.Cu")
		(net "SW_P3V3_LV_G5")
	)
	(segment
		(start 57.16524 -40.6146)
		(end 57.16524 -41.2115)
		(width 0.254)
		(layer "F.Cu")
		(net "SW_P3V3_LV_G5")
	)
	(segment
		(start 56.515 -41.2115)
		(end 56.515 -40.63746)
		(width 0.254)
		(layer "F.Cu")
		(net "SW_P3V3_LV_G5")
	)
	(segment
		(start 57.6199 -41.2115)
		(end 57.16524 -41.2115)
		(width 0.254)
		(layer "F.Cu")
		(net "SW_P3V3_LV_G5")
	)
	(segment
		(start 57.88914 -43.243754)
		(end 58.3692 -42.763694)
		(width 0.254)
		(layer "F.Cu")
		(net "SW_P3V3_LV_G5")
	)
	(segment
		(start 58.2676 -40.894)
		(end 57.9374 -40.894)
		(width 0.254)
		(layer "F.Cu")
		(net "SW_P3V3_LV_G5")
	)
	(via
		(at 35.2044 -37.1602)
		(size 0.508)
		(drill 0.254)
		(layers "F.Cu" "B.Cu")
		(net "SW_P3V3_LV_G5")
	)
	(via
		(at 26.9494 -40.3098)
		(size 0.508)
		(drill 0.254)
		(layers "F.Cu" "B.Cu")
		(net "SW_P3V3_LV_G5")
	)
	(via
		(at 58.293 -40.8686)
		(size 0.7112)
		(drill 0.3556)
		(layers "F.Cu" "B.Cu")
		(net "SW_P3V3_LV_G5")
	)
	(via
		(at 57.87898 -43.244008)
		(size 0.508)
		(drill 0.254)
		(layers "F.Cu" "B.Cu")
		(net "SW_P3V3_LV_G5")
	)
	(segment
		(start 20.118324 -44.15155)
		(end 19.87296 -44.396914)
		(width 0.254)
		(layer "B.Cu")
		(net "SW_P3V3_LV_G5")
	)
	(segment
		(start 22.4536 -44.15155)
		(end 20.118324 -44.15155)
		(width 0.254)
		(layer "B.Cu")
		(net "SW_P3V3_LV_G5")
	)
	(segment
		(start 26.295604 -40.3098)
		(end 23.142702 -43.462702)
		(width 0.254)
		(layer "B.Cu")
		(net "SW_P3V3_LV_G5")
	)
	(segment
		(start 26.9494 -40.3098)
		(end 26.295604 -40.3098)
		(width 0.254)
		(layer "B.Cu")
		(net "SW_P3V3_LV_G5")
	)
	(segment
		(start 23.142702 -43.462702)
		(end 22.4536 -44.15155)
		(width 0.254)
		(layer "B.Cu")
		(net "SW_P3V3_LV_G5")
	)
	(segment
		(start 57.847738 -43.27525)
		(end 48.912272 -43.27525)
		(width 0.254)
		(layer "In7.Cu")
		(net "SW_P3V3_LV_G5")
	)
	(segment
		(start 44.791884 -40.804084)
		(end 42.71645 -38.72865)
		(width 0.254)
		(layer "In7.Cu")
		(net "SW_P3V3_LV_G5")
	)
	(segment
		(start 42.71645 -38.72865)
		(end 39.801546 -35.814)
		(width 0.254)
		(layer "In7.Cu")
		(net "SW_P3V3_LV_G5")
	)
	(segment
		(start 48.912272 -43.27525)
		(end 46.441106 -40.804084)
		(width 0.254)
		(layer "In7.Cu")
		(net "SW_P3V3_LV_G5")
	)
	(segment
		(start 39.801546 -35.814)
		(end 36.5506 -35.814)
		(width 0.254)
		(layer "In7.Cu")
		(net "SW_P3V3_LV_G5")
	)
	(segment
		(start 46.441106 -40.804084)
		(end 44.791884 -40.804084)
		(width 0.254)
		(layer "In7.Cu")
		(net "SW_P3V3_LV_G5")
	)
	(segment
		(start 36.5506 -35.814)
		(end 35.2044 -37.1602)
		(width 0.254)
		(layer "In7.Cu")
		(net "SW_P3V3_LV_G5")
	)
	(segment
		(start 57.87898 -43.244008)
		(end 57.847738 -43.27525)
		(width 0.254)
		(layer "In7.Cu")
		(net "SW_P3V3_LV_G5")
	)
	(segment
		(start 32.131 -35.814)
		(end 32.131 -34.925)
		(width 0.254)
		(layer "In9.Cu")
		(net "SW_P3V3_LV_G5")
	)
	(segment
		(start 28.942538 -35.306)
		(end 28.30322 -35.306)
		(width 0.254)
		(layer "In9.Cu")
		(net "SW_P3V3_LV_G5")
	)
	(segment
		(start 26.9494 -36.65982)
		(end 26.9494 -40.3098)
		(width 0.254)
		(layer "In9.Cu")
		(net "SW_P3V3_LV_G5")
	)
	(segment
		(start 30.9626 -33.7566)
		(end 30.491938 -33.7566)
		(width 0.254)
		(layer "In9.Cu")
		(net "SW_P3V3_LV_G5")
	)
	(segment
		(start 34.7472 -36.703)
		(end 33.02 -36.703)
		(width 0.254)
		(layer "In9.Cu")
		(net "SW_P3V3_LV_G5")
	)
	(segment
		(start 30.491938 -33.7566)
		(end 28.942538 -35.306)
		(width 0.254)
		(layer "In9.Cu")
		(net "SW_P3V3_LV_G5")
	)
	(segment
		(start 35.2044 -37.1602)
		(end 34.7472 -36.703)
		(width 0.254)
		(layer "In9.Cu")
		(net "SW_P3V3_LV_G5")
	)
	(segment
		(start 32.131 -34.925)
		(end 30.9626 -33.7566)
		(width 0.254)
		(layer "In9.Cu")
		(net "SW_P3V3_LV_G5")
	)
	(segment
		(start 28.30322 -35.306)
		(end 26.9494 -36.65982)
		(width 0.254)
		(layer "In9.Cu")
		(net "SW_P3V3_LV_G5")
	)
	(segment
		(start 33.02 -36.703)
		(end 32.131 -35.814)
		(width 0.254)
		(layer "In9.Cu")
		(net "SW_P3V3_LV_G5")
	)
	(segment
		(start 54.7116 -42.4688)
		(end 54.864 -42.6212)
		(width 0.254)
		(layer "F.Cu")
		(net "SW_P3V3_EN_LV_D")
	)
	(segment
		(start 51.181 -42.926)
		(end 52.5145 -42.926)
		(width 0.254)
		(layer "F.Cu")
		(net "SW_P3V3_EN_LV_D")
	)
	(segment
		(start 53.901086 -42.415714)
		(end 53.901086 -42.394886)
		(width 0.254)
		(layer "F.Cu")
		(net "SW_P3V3_EN_LV_D")
	)
	(segment
		(start 53.916072 -42.3799)
		(end 54.004972 -42.4688)
		(width 0.254)
		(layer "F.Cu")
		(net "SW_P3V3_EN_LV_D")
	)
	(segment
		(start 55.62346 -42.6212)
		(end 54.864 -42.6212)
		(width 0.254)
		(layer "F.Cu")
		(net "SW_P3V3_EN_LV_D")
	)
	(segment
		(start 55.86476 -44.03344)
		(end 55.86476 -42.8625)
		(width 0.254)
		(layer "F.Cu")
		(net "SW_P3V3_EN_LV_D")
	)
	(segment
		(start 55.753 -44.1452)
		(end 55.86476 -44.03344)
		(width 0.254)
		(layer "F.Cu")
		(net "SW_P3V3_EN_LV_D")
	)
	(segment
		(start 49.6824 -44.4246)
		(end 51.181 -42.926)
		(width 0.254)
		(layer "F.Cu")
		(net "SW_P3V3_EN_LV_D")
	)
	(segment
		(start 49.6824 -44.958)
		(end 49.6824 -44.4246)
		(width 0.254)
		(layer "F.Cu")
		(net "SW_P3V3_EN_LV_D")
	)
	(segment
		(start 52.5145 -42.926)
		(end 53.3908 -42.926)
		(width 0.254)
		(layer "F.Cu")
		(net "SW_P3V3_EN_LV_D")
	)
	(segment
		(start 53.3908 -42.926)
		(end 53.901086 -42.415714)
		(width 0.254)
		(layer "F.Cu")
		(net "SW_P3V3_EN_LV_D")
	)
	(segment
		(start 53.901086 -42.394886)
		(end 53.916072 -42.3799)
		(width 0.254)
		(layer "F.Cu")
		(net "SW_P3V3_EN_LV_D")
	)
	(segment
		(start 54.004972 -42.4688)
		(end 54.7116 -42.4688)
		(width 0.254)
		(layer "F.Cu")
		(net "SW_P3V3_EN_LV_D")
	)
	(segment
		(start 55.86476 -42.8625)
		(end 55.62346 -42.6212)
		(width 0.254)
		(layer "F.Cu")
		(net "SW_P3V3_EN_LV_D")
	)
	(via
		(at 53.916072 -42.3799)
		(size 0.7112)
		(drill 0.3556)
		(layers "F.Cu" "B.Cu")
		(net "SW_P3V3_EN_LV_D")
	)
	(segment
		(start 56.515 -44.1452)
		(end 57.465976 -44.1452)
		(width 0.254)
		(layer "F.Cu")
		(net "SW_P3V3_EN_G2")
	)
	(segment
		(start 56.515 -42.8625)
		(end 56.515 -44.1452)
		(width 0.254)
		(layer "F.Cu")
		(net "SW_P3V3_EN_G2")
	)
	(segment
		(start 57.465976 -44.1452)
		(end 57.478168 -44.133008)
		(width 0.254)
		(layer "F.Cu")
		(net "SW_P3V3_EN_G2")
	)
	(via
		(at 57.478168 -44.133008)
		(size 0.7112)
		(drill 0.3556)
		(layers "F.Cu" "B.Cu")
		(net "SW_P3V3_EN_G2")
	)
	(segment
		(start 63.142114 -25.92324)
		(end 63.142114 -24.437086)
		(width 0.254)
		(layer "F.Cu")
		(net "SW_P1V8_EN_S")
	)
	(segment
		(start 63.1698 -22.479)
		(end 63.1698 -23.241)
		(width 0.254)
		(layer "F.Cu")
		(net "SW_P1V8_EN_S")
	)
	(segment
		(start 63.1698 -24.4094)
		(end 63.1698 -23.241)
		(width 0.254)
		(layer "F.Cu")
		(net "SW_P1V8_EN_S")
	)
	(segment
		(start 63.142114 -24.437086)
		(end 63.1698 -24.4094)
		(width 0.254)
		(layer "F.Cu")
		(net "SW_P1V8_EN_S")
	)
	(via
		(at 63.1698 -24.4094)
		(size 0.7112)
		(drill 0.3556)
		(layers "F.Cu" "B.Cu")
		(net "SW_P1V8_EN_S")
	)
	(segment
		(start 62.0014 -28.7274)
		(end 62.7888 -29.5148)
		(width 0.254)
		(layer "F.Cu")
		(net "SW_P1V8_EN_LV")
	)
	(segment
		(start 65.280286 -26.8732)
		(end 65.280286 -28.521914)
		(width 0.254)
		(layer "F.Cu")
		(net "SW_P1V8_EN_LV")
	)
	(segment
		(start 64.2366 -29.5148)
		(end 64.2874 -29.464)
		(width 0.254)
		(layer "F.Cu")
		(net "SW_P1V8_EN_LV")
	)
	(segment
		(start 65.280286 -28.521914)
		(end 64.3382 -29.464)
		(width 0.254)
		(layer "F.Cu")
		(net "SW_P1V8_EN_LV")
	)
	(segment
		(start 64.897 -24.5618)
		(end 65.280286 -24.945086)
		(width 0.254)
		(layer "F.Cu")
		(net "SW_P1V8_EN_LV")
	)
	(segment
		(start 65.280286 -24.945086)
		(end 65.280286 -26.8732)
		(width 0.254)
		(layer "F.Cu")
		(net "SW_P1V8_EN_LV")
	)
	(segment
		(start 64.3382 -29.464)
		(end 64.2874 -29.464)
		(width 0.254)
		(layer "F.Cu")
		(net "SW_P1V8_EN_LV")
	)
	(segment
		(start 62.0014 -28.08224)
		(end 62.0014 -28.7274)
		(width 0.254)
		(layer "F.Cu")
		(net "SW_P1V8_EN_LV")
	)
	(segment
		(start 62.7888 -29.5148)
		(end 63.119 -29.5148)
		(width 0.254)
		(layer "F.Cu")
		(net "SW_P1V8_EN_LV")
	)
	(segment
		(start 63.119 -29.5148)
		(end 64.2366 -29.5148)
		(width 0.254)
		(layer "F.Cu")
		(net "SW_P1V8_EN_LV")
	)
	(via
		(at 64.2874 -29.464)
		(size 0.7112)
		(drill 0.3556)
		(layers "F.Cu" "B.Cu")
		(net "SW_P1V8_EN_LV")
	)
	(segment
		(start 62.065154 -26.7462)
		(end 61.402214 -26.7462)
		(width 0.254)
		(layer "F.Cu")
		(net "SW_P1V8_EN_G")
	)
	(segment
		(start 63.142114 -27.82316)
		(end 62.065154 -26.7462)
		(width 0.254)
		(layer "F.Cu")
		(net "SW_P1V8_EN_G")
	)
	(segment
		(start 60.706 -25.9588)
		(end 60.706 -26.049986)
		(width 0.254)
		(layer "F.Cu")
		(net "SW_P1V8_EN_G")
	)
	(segment
		(start 60.706 -26.049986)
		(end 61.402214 -26.7462)
		(width 0.254)
		(layer "F.Cu")
		(net "SW_P1V8_EN_G")
	)
	(via
		(at 61.402214 -26.7462)
		(size 0.7112)
		(drill 0.3556)
		(layers "F.Cu" "B.Cu")
		(net "SW_P1V8_EN_G")
	)
	(segment
		(start 80.58785 -35.263074)
		(end 81.054448 -35.263074)
		(width 0.1143)
		(layer "F.Cu")
		(net "XDP_CPU_RESET#")
	)
	(segment
		(start 75.327256 -34.622994)
		(end 76.151994 -34.622994)
		(width 0.1143)
		(layer "F.Cu")
		(net "XDP_CPU_RESET#")
	)
	(segment
		(start 78.245462 -35.625024)
		(end 80.2259 -35.625024)
		(width 0.1143)
		(layer "F.Cu")
		(net "XDP_CPU_RESET#")
	)
	(segment
		(start 30.607 -30.8356)
		(end 30.607 -32.0548)
		(width 0.1143)
		(layer "F.Cu")
		(net "XDP_CPU_RESET#")
	)
	(segment
		(start 30.607 -32.0548)
		(end 30.099 -32.5628)
		(width 0.1143)
		(layer "F.Cu")
		(net "XDP_CPU_RESET#")
	)
	(segment
		(start 74.93635 -34.11855)
		(end 74.93635 -34.232088)
		(width 0.1143)
		(layer "F.Cu")
		(net "XDP_CPU_RESET#")
	)
	(segment
		(start 31.7246 -31.8008)
		(end 30.7086 -30.7848)
		(width 0.1143)
		(layer "F.Cu")
		(net "XDP_CPU_RESET#")
	)
	(segment
		(start 77.621638 -35.0012)
		(end 78.245462 -35.625024)
		(width 0.1143)
		(layer "F.Cu")
		(net "XDP_CPU_RESET#")
	)
	(segment
		(start 80.2259 -35.625024)
		(end 80.58785 -35.263074)
		(width 0.1143)
		(layer "F.Cu")
		(net "XDP_CPU_RESET#")
	)
	(segment
		(start 74.93635 -34.232088)
		(end 75.327256 -34.622994)
		(width 0.1143)
		(layer "F.Cu")
		(net "XDP_CPU_RESET#")
	)
	(segment
		(start 74.4728 -33.655)
		(end 74.93635 -34.11855)
		(width 0.1143)
		(layer "F.Cu")
		(net "XDP_CPU_RESET#")
	)
	(segment
		(start 30.7086 -30.7848)
		(end 30.7086 -30.734)
		(width 0.1143)
		(layer "F.Cu")
		(net "XDP_CPU_RESET#")
	)
	(segment
		(start 76.5302 -35.0012)
		(end 77.621638 -35.0012)
		(width 0.1143)
		(layer "F.Cu")
		(net "XDP_CPU_RESET#")
	)
	(segment
		(start 30.7086 -30.734)
		(end 30.607 -30.8356)
		(width 0.1143)
		(layer "F.Cu")
		(net "XDP_CPU_RESET#")
	)
	(segment
		(start 32.2453 -31.8008)
		(end 31.7246 -31.8008)
		(width 0.1143)
		(layer "F.Cu")
		(net "XDP_CPU_RESET#")
	)
	(segment
		(start 76.151994 -34.622994)
		(end 76.5302 -35.0012)
		(width 0.1143)
		(layer "F.Cu")
		(net "XDP_CPU_RESET#")
	)
	(via
		(at 32.2453 -31.8008)
		(size 0.508)
		(drill 0.254)
		(layers "F.Cu" "B.Cu")
		(net "XDP_CPU_RESET#")
	)
	(via
		(at 37.1856 -35.20313)
		(size 0.508)
		(drill 0.254)
		(layers "F.Cu" "B.Cu")
		(net "XDP_CPU_RESET#")
	)
	(via
		(at 51.2191 -28.2448)
		(size 0.508)
		(drill 0.254)
		(layers "F.Cu" "B.Cu")
		(net "XDP_CPU_RESET#")
	)
	(via
		(at 75.327256 -34.622994)
		(size 0.508)
		(drill 0.254)
		(layers "F.Cu" "B.Cu")
		(net "XDP_CPU_RESET#")
	)
	(via
		(at 76.0984 -34.4932)
		(size 0.7112)
		(drill 0.3556)
		(layers "F.Cu" "B.Cu")
		(net "XDP_CPU_RESET#")
	)
	(segment
		(start 75.968606 -34.622994)
		(end 76.0984 -34.4932)
		(width 0.1143)
		(layer "B.Cu")
		(net "XDP_CPU_RESET#")
	)
	(segment
		(start 75.327256 -34.622994)
		(end 75.968606 -34.622994)
		(width 0.1143)
		(layer "B.Cu")
		(net "XDP_CPU_RESET#")
	)
	(segment
		(start 43.68927 -35.20313)
		(end 37.1856 -35.20313)
		(width 0.0889)
		(layer "In4.Cu")
		(net "XDP_CPU_RESET#")
	)
	(segment
		(start 51.2191 -28.2448)
		(end 50.6476 -28.2448)
		(width 0.0889)
		(layer "In4.Cu")
		(net "XDP_CPU_RESET#")
	)
	(segment
		(start 50.6476 -28.2448)
		(end 43.68927 -35.20313)
		(width 0.0889)
		(layer "In4.Cu")
		(net "XDP_CPU_RESET#")
	)
	(segment
		(start 54.158134 -30.255464)
		(end 54.53507 -30.6324)
		(width 0.0889)
		(layer "In7.Cu")
		(net "XDP_CPU_RESET#")
	)
	(segment
		(start 52.098956 -30.4673)
		(end 52.4891 -30.4673)
		(width 0.0889)
		(layer "In7.Cu")
		(net "XDP_CPU_RESET#")
	)
	(segment
		(start 34.19475 -33.75025)
		(end 35.73272 -33.75025)
		(width 0.0889)
		(layer "In7.Cu")
		(net "XDP_CPU_RESET#")
	)
	(segment
		(start 52.700936 -30.255464)
		(end 54.158134 -30.255464)
		(width 0.0889)
		(layer "In7.Cu")
		(net "XDP_CPU_RESET#")
	)
	(segment
		(start 73.914 -32.639508)
		(end 73.914 -32.885126)
		(width 0.0889)
		(layer "In7.Cu")
		(net "XDP_CPU_RESET#")
	)
	(segment
		(start 65.218818 -30.6324)
		(end 66.590418 -32.004)
		(width 0.0889)
		(layer "In7.Cu")
		(net "XDP_CPU_RESET#")
	)
	(segment
		(start 51.2191 -28.2448)
		(end 51.2191 -29.587444)
		(width 0.0889)
		(layer "In7.Cu")
		(net "XDP_CPU_RESET#")
	)
	(segment
		(start 74.918824 -33.963356)
		(end 75.327256 -34.371788)
		(width 0.0889)
		(layer "In7.Cu")
		(net "XDP_CPU_RESET#")
	)
	(segment
		(start 66.590418 -32.004)
		(end 73.278492 -32.004)
		(width 0.0889)
		(layer "In7.Cu")
		(net "XDP_CPU_RESET#")
	)
	(segment
		(start 75.327256 -34.371788)
		(end 75.327256 -34.622994)
		(width 0.0889)
		(layer "In7.Cu")
		(net "XDP_CPU_RESET#")
	)
	(segment
		(start 73.914 -32.885126)
		(end 74.918824 -33.88995)
		(width 0.0889)
		(layer "In7.Cu")
		(net "XDP_CPU_RESET#")
	)
	(segment
		(start 52.4891 -30.4673)
		(end 52.700936 -30.255464)
		(width 0.0889)
		(layer "In7.Cu")
		(net "XDP_CPU_RESET#")
	)
	(segment
		(start 51.2191 -29.587444)
		(end 52.098956 -30.4673)
		(width 0.0889)
		(layer "In7.Cu")
		(net "XDP_CPU_RESET#")
	)
	(segment
		(start 35.73272 -33.75025)
		(end 37.1856 -35.20313)
		(width 0.0889)
		(layer "In7.Cu")
		(net "XDP_CPU_RESET#")
	)
	(segment
		(start 54.53507 -30.6324)
		(end 65.218818 -30.6324)
		(width 0.0889)
		(layer "In7.Cu")
		(net "XDP_CPU_RESET#")
	)
	(segment
		(start 73.278492 -32.004)
		(end 73.914 -32.639508)
		(width 0.0889)
		(layer "In7.Cu")
		(net "XDP_CPU_RESET#")
	)
	(segment
		(start 74.918824 -33.88995)
		(end 74.918824 -33.963356)
		(width 0.0889)
		(layer "In7.Cu")
		(net "XDP_CPU_RESET#")
	)
	(segment
		(start 32.2453 -31.8008)
		(end 34.19475 -33.75025)
		(width 0.0889)
		(layer "In7.Cu")
		(net "XDP_CPU_RESET#")
	)
	(segment
		(start 33.3756 -31.2674)
		(end 32.5628 -31.2674)
		(width 0.1143)
		(layer "F.Cu")
		(net "XDP_CPU_R_RESET#")
	)
	(segment
		(start 27.8638 -15.24)
		(end 27.37485 -15.72895)
		(width 0.1143)
		(layer "F.Cu")
		(net "XDP_CPU_R_RESET#")
	)
	(segment
		(start 32.49295 -25.563576)
		(end 32.49295 -29.96565)
		(width 0.1143)
		(layer "F.Cu")
		(net "XDP_CPU_R_RESET#")
	)
	(segment
		(start 32.5628 -31.2674)
		(end 32.0294 -30.734)
		(width 0.1143)
		(layer "F.Cu")
		(net "XDP_CPU_R_RESET#")
	)
	(segment
		(start 29.133546 -20.747482)
		(end 29.87675 -21.490686)
		(width 0.1143)
		(layer "F.Cu")
		(net "XDP_CPU_R_RESET#")
	)
	(segment
		(start 27.37485 -15.72895)
		(end 27.37485 -19.911822)
		(width 0.1143)
		(layer "F.Cu")
		(net "XDP_CPU_R_RESET#")
	)
	(segment
		(start 27.37485 -19.911822)
		(end 28.21051 -20.747482)
		(width 0.1143)
		(layer "F.Cu")
		(net "XDP_CPU_R_RESET#")
	)
	(segment
		(start 28.21051 -20.747482)
		(end 29.133546 -20.747482)
		(width 0.1143)
		(layer "F.Cu")
		(net "XDP_CPU_R_RESET#")
	)
	(segment
		(start 36.37788 -31.05531)
		(end 33.58769 -31.05531)
		(width 0.1143)
		(layer "F.Cu")
		(net "XDP_CPU_R_RESET#")
	)
	(segment
		(start 29.87675 -22.947376)
		(end 32.49295 -25.563576)
		(width 0.1143)
		(layer "F.Cu")
		(net "XDP_CPU_R_RESET#")
	)
	(segment
		(start 33.58769 -31.05531)
		(end 33.3756 -31.2674)
		(width 0.1143)
		(layer "F.Cu")
		(net "XDP_CPU_R_RESET#")
	)
	(segment
		(start 29.87675 -21.490686)
		(end 29.87675 -22.947376)
		(width 0.1143)
		(layer "F.Cu")
		(net "XDP_CPU_R_RESET#")
	)
	(segment
		(start 32.0294 -30.4292)
		(end 32.0294 -30.734)
		(width 0.1143)
		(layer "F.Cu")
		(net "XDP_CPU_R_RESET#")
	)
	(segment
		(start 32.49295 -29.96565)
		(end 32.0294 -30.4292)
		(width 0.1143)
		(layer "F.Cu")
		(net "XDP_CPU_R_RESET#")
	)
	(via
		(at 27.2542 -13.5128)
		(size 0.7112)
		(drill 0.3556)
		(layers "F.Cu" "B.Cu")
		(net "XDP_CPU_R_RESET#")
	)
	(via
		(at 27.8638 -15.24)
		(size 0.508)
		(drill 0.254)
		(layers "F.Cu" "B.Cu")
		(net "XDP_CPU_R_RESET#")
	)
	(segment
		(start 27.2542 -13.5128)
		(end 27.2542 -14.6304)
		(width 0.1143)
		(layer "B.Cu")
		(net "XDP_CPU_R_RESET#")
	)
	(segment
		(start 27.2542 -14.6304)
		(end 27.8638 -15.24)
		(width 0.1143)
		(layer "B.Cu")
		(net "XDP_CPU_R_RESET#")
	)
	(segment
		(start 88.625934 -36.449)
		(end 88.607646 -36.449)
		(width 0.1143)
		(layer "F.Cu")
		(net "CPU_RSMRST_R#")
	)
	(segment
		(start 88.607646 -36.449)
		(end 88.56345 -36.404804)
		(width 0.1143)
		(layer "F.Cu")
		(net "CPU_RSMRST_R#")
	)
	(segment
		(start 74.549 -27.178)
		(end 75.946 -28.575)
		(width 0.1143)
		(layer "F.Cu")
		(net "CPU_RSMRST_R#")
	)
	(segment
		(start 74.0918 -27.178)
		(end 74.549 -27.178)
		(width 0.1143)
		(layer "F.Cu")
		(net "CPU_RSMRST_R#")
	)
	(segment
		(start 76.5048 -29.1338)
		(end 75.946 -28.575)
		(width 0.1143)
		(layer "F.Cu")
		(net "CPU_RSMRST_R#")
	)
	(segment
		(start 88.920828 -36.743894)
		(end 88.625934 -36.449)
		(width 0.1143)
		(layer "F.Cu")
		(net "CPU_RSMRST_R#")
	)
	(segment
		(start 77.9018 -29.1338)
		(end 76.5048 -29.1338)
		(width 0.1143)
		(layer "F.Cu")
		(net "CPU_RSMRST_R#")
	)
	(via
		(at 75.946 -28.575)
		(size 0.7112)
		(drill 0.3556)
		(layers "F.Cu" "B.Cu")
		(net "CPU_RSMRST_R#")
	)
	(via
		(at 77.9018 -29.1338)
		(size 0.4318)
		(drill 0.2032)
		(layers "F.Cu" "B.Cu")
		(net "CPU_RSMRST_R#")
	)
	(via
		(at 88.56345 -36.404804)
		(size 0.4318)
		(drill 0.2032)
		(layers "F.Cu" "B.Cu")
		(net "CPU_RSMRST_R#")
	)
	(segment
		(start 87.955882 -35.63366)
		(end 87.573612 -35.25139)
		(width 0.0889)
		(layer "In7.Cu")
		(net "CPU_RSMRST_R#")
	)
	(segment
		(start 87.955882 -35.662616)
		(end 87.955882 -35.63366)
		(width 0.0889)
		(layer "In7.Cu")
		(net "CPU_RSMRST_R#")
	)
	(segment
		(start 86.184994 -33.2105)
		(end 85.098382 -33.2105)
		(width 0.0889)
		(layer "In7.Cu")
		(net "CPU_RSMRST_R#")
	)
	(segment
		(start 84.468208 -32.234632)
		(end 84.5566 -32.14624)
		(width 0.0889)
		(layer "In7.Cu")
		(net "CPU_RSMRST_R#")
	)
	(segment
		(start 84.468208 -32.580326)
		(end 84.468208 -32.234632)
		(width 0.0889)
		(layer "In7.Cu")
		(net "CPU_RSMRST_R#")
	)
	(segment
		(start 87.573612 -35.25139)
		(end 87.573612 -33.699704)
		(width 0.0889)
		(layer "In7.Cu")
		(net "CPU_RSMRST_R#")
	)
	(segment
		(start 87.27567 -33.401762)
		(end 86.376256 -33.401762)
		(width 0.0889)
		(layer "In7.Cu")
		(net "CPU_RSMRST_R#")
	)
	(segment
		(start 78.4606 -28.575)
		(end 77.9018 -29.1338)
		(width 0.0889)
		(layer "In7.Cu")
		(net "CPU_RSMRST_R#")
	)
	(segment
		(start 84.274914 -31.447994)
		(end 83.494118 -31.447994)
		(width 0.0889)
		(layer "In7.Cu")
		(net "CPU_RSMRST_R#")
	)
	(segment
		(start 79.6798 -28.575)
		(end 78.4606 -28.575)
		(width 0.0889)
		(layer "In7.Cu")
		(net "CPU_RSMRST_R#")
	)
	(segment
		(start 87.573612 -33.699704)
		(end 87.27567 -33.401762)
		(width 0.0889)
		(layer "In7.Cu")
		(net "CPU_RSMRST_R#")
	)
	(segment
		(start 83.245452 -31.199328)
		(end 83.245452 -30.934406)
		(width 0.0889)
		(layer "In7.Cu")
		(net "CPU_RSMRST_R#")
	)
	(segment
		(start 88.56345 -36.270184)
		(end 87.955882 -35.662616)
		(width 0.0889)
		(layer "In7.Cu")
		(net "CPU_RSMRST_R#")
	)
	(segment
		(start 85.098382 -33.2105)
		(end 84.468208 -32.580326)
		(width 0.0889)
		(layer "In7.Cu")
		(net "CPU_RSMRST_R#")
	)
	(segment
		(start 83.033616 -30.72257)
		(end 81.82737 -30.72257)
		(width 0.0889)
		(layer "In7.Cu")
		(net "CPU_RSMRST_R#")
	)
	(segment
		(start 88.56345 -36.404804)
		(end 88.56345 -36.270184)
		(width 0.0889)
		(layer "In7.Cu")
		(net "CPU_RSMRST_R#")
	)
	(segment
		(start 83.245452 -30.934406)
		(end 83.033616 -30.72257)
		(width 0.0889)
		(layer "In7.Cu")
		(net "CPU_RSMRST_R#")
	)
	(segment
		(start 84.5566 -32.14624)
		(end 84.5566 -31.72968)
		(width 0.0889)
		(layer "In7.Cu")
		(net "CPU_RSMRST_R#")
	)
	(segment
		(start 86.376256 -33.401762)
		(end 86.184994 -33.2105)
		(width 0.0889)
		(layer "In7.Cu")
		(net "CPU_RSMRST_R#")
	)
	(segment
		(start 83.494118 -31.447994)
		(end 83.245452 -31.199328)
		(width 0.0889)
		(layer "In7.Cu")
		(net "CPU_RSMRST_R#")
	)
	(segment
		(start 84.5566 -31.72968)
		(end 84.274914 -31.447994)
		(width 0.0889)
		(layer "In7.Cu")
		(net "CPU_RSMRST_R#")
	)
	(segment
		(start 81.82737 -30.72257)
		(end 79.6798 -28.575)
		(width 0.0889)
		(layer "In7.Cu")
		(net "CPU_RSMRST_R#")
	)
	(segment
		(start 71.98487 -25.17267)
		(end 71.37527 -25.17267)
		(width 0.1143)
		(layer "F.Cu")
		(net "CPU_RSMRST#")
	)
	(segment
		(start 61.1124 -13.8176)
		(end 62.0776 -12.8524)
		(width 0.1143)
		(layer "F.Cu")
		(net "CPU_RSMRST#")
	)
	(segment
		(start 38.304216 -41.070784)
		(end 38.1 -41.275)
		(width 0.1143)
		(layer "F.Cu")
		(net "CPU_RSMRST#")
	)
	(segment
		(start 45.41266 -25.512268)
		(end 46.159928 -24.765)
		(width 0.1143)
		(layer "F.Cu")
		(net "CPU_RSMRST#")
	)
	(segment
		(start 38.862 -17.1196)
		(end 38.862 -17.2212)
		(width 0.1143)
		(layer "F.Cu")
		(net "CPU_RSMRST#")
	)
	(segment
		(start 38.1 -41.275)
		(end 38.1 -41.6052)
		(width 0.1143)
		(layer "F.Cu")
		(net "CPU_RSMRST#")
	)
	(segment
		(start 45.2628 -27.8384)
		(end 45.41266 -27.68854)
		(width 0.1143)
		(layer "F.Cu")
		(net "CPU_RSMRST#")
	)
	(segment
		(start 38.304216 -40.359584)
		(end 38.304216 -41.070784)
		(width 0.1143)
		(layer "F.Cu")
		(net "CPU_RSMRST#")
	)
	(segment
		(start 31.75 -16.1798)
		(end 37.9222 -16.1798)
		(width 0.1143)
		(layer "F.Cu")
		(net "CPU_RSMRST#")
	)
	(segment
		(start 73.2282 -27.178)
		(end 73.2282 -26.416)
		(width 0.1143)
		(layer "F.Cu")
		(net "CPU_RSMRST#")
	)
	(segment
		(start 60.8076 -13.8176)
		(end 61.1124 -13.8176)
		(width 0.1143)
		(layer "F.Cu")
		(net "CPU_RSMRST#")
	)
	(segment
		(start 73.2282 -26.416)
		(end 71.98487 -25.17267)
		(width 0.1143)
		(layer "F.Cu")
		(net "CPU_RSMRST#")
	)
	(segment
		(start 38.1 -41.6052)
		(end 38.862 -41.6052)
		(width 0.1143)
		(layer "F.Cu")
		(net "CPU_RSMRST#")
	)
	(segment
		(start 37.9222 -16.1798)
		(end 38.862 -17.1196)
		(width 0.1143)
		(layer "F.Cu")
		(net "CPU_RSMRST#")
	)
	(segment
		(start 45.41266 -27.68854)
		(end 45.41266 -25.512268)
		(width 0.1143)
		(layer "F.Cu")
		(net "CPU_RSMRST#")
	)
	(via
		(at 62.0776 -12.8524)
		(size 0.508)
		(drill 0.254)
		(layers "F.Cu" "B.Cu")
		(net "CPU_RSMRST#")
	)
	(via
		(at 61.2648 -24.1046)
		(size 0.508)
		(drill 0.254)
		(layers "F.Cu" "B.Cu")
		(net "CPU_RSMRST#")
	)
	(via
		(at 46.159928 -24.765)
		(size 0.508)
		(drill 0.254)
		(layers "F.Cu" "B.Cu")
		(net "CPU_RSMRST#")
	)
	(via
		(at 33.401 -37.846)
		(size 0.508)
		(drill 0.254)
		(layers "F.Cu" "B.Cu")
		(net "CPU_RSMRST#")
	)
	(via
		(at 71.37527 -25.17267)
		(size 0.508)
		(drill 0.254)
		(layers "F.Cu" "B.Cu")
		(net "CPU_RSMRST#")
	)
	(via
		(at 38.304216 -40.359584)
		(size 0.508)
		(drill 0.254)
		(layers "F.Cu" "B.Cu")
		(net "CPU_RSMRST#")
	)
	(via
		(at 62.865 -12.446)
		(size 0.7112)
		(drill 0.3556)
		(layers "F.Cu" "B.Cu")
		(net "CPU_RSMRST#")
	)
	(via
		(at 38.862 -17.2212)
		(size 0.508)
		(drill 0.254)
		(layers "F.Cu" "B.Cu")
		(net "CPU_RSMRST#")
	)
	(via
		(at 113.3094 -4.7498)
		(size 0.508)
		(drill 0.254)
		(layers "F.Cu" "B.Cu")
		(net "CPU_RSMRST#")
	)
	(segment
		(start 116.2685 -22.840442)
		(end 122.154188 -28.72613)
		(width 0.1143)
		(layer "B.Cu")
		(net "CPU_RSMRST#")
	)
	(segment
		(start 179.075588 -32.939482)
		(end 181.27345 -35.137344)
		(width 0.1143)
		(layer "B.Cu")
		(net "CPU_RSMRST#")
	)
	(segment
		(start 113.3094 -4.7498)
		(end 113.78819 -5.22859)
		(width 0.1143)
		(layer "B.Cu")
		(net "CPU_RSMRST#")
	)
	(segment
		(start 114.124232 -5.996432)
		(end 114.124232 -13.675868)
		(width 0.1143)
		(layer "B.Cu")
		(net "CPU_RSMRST#")
	)
	(segment
		(start 181.27345 -35.137344)
		(end 181.27345 -36.22675)
		(width 0.1143)
		(layer "B.Cu")
		(net "CPU_RSMRST#")
	)
	(segment
		(start 62.484 -12.446)
		(end 62.865 -12.446)
		(width 0.1143)
		(layer "B.Cu")
		(net "CPU_RSMRST#")
	)
	(segment
		(start 116.2685 -15.820136)
		(end 116.2685 -22.840442)
		(width 0.1143)
		(layer "B.Cu")
		(net "CPU_RSMRST#")
	)
	(segment
		(start 113.78819 -5.66039)
		(end 114.124232 -5.996432)
		(width 0.1143)
		(layer "B.Cu")
		(net "CPU_RSMRST#")
	)
	(segment
		(start 114.124232 -13.675868)
		(end 116.2685 -15.820136)
		(width 0.1143)
		(layer "B.Cu")
		(net "CPU_RSMRST#")
	)
	(segment
		(start 62.0776 -12.8524)
		(end 62.484 -12.446)
		(width 0.1143)
		(layer "B.Cu")
		(net "CPU_RSMRST#")
	)
	(segment
		(start 159.967676 -32.939482)
		(end 179.075588 -32.939482)
		(width 0.1143)
		(layer "B.Cu")
		(net "CPU_RSMRST#")
	)
	(segment
		(start 178.054 -39.4462)
		(end 178.054 -42.1132)
		(width 0.1143)
		(layer "B.Cu")
		(net "CPU_RSMRST#")
	)
	(segment
		(start 155.754324 -28.72613)
		(end 159.967676 -32.939482)
		(width 0.1143)
		(layer "B.Cu")
		(net "CPU_RSMRST#")
	)
	(segment
		(start 113.78819 -5.22859)
		(end 113.78819 -5.66039)
		(width 0.1143)
		(layer "B.Cu")
		(net "CPU_RSMRST#")
	)
	(segment
		(start 181.27345 -36.22675)
		(end 178.054 -39.4462)
		(width 0.1143)
		(layer "B.Cu")
		(net "CPU_RSMRST#")
	)
	(segment
		(start 122.154188 -28.72613)
		(end 155.754324 -28.72613)
		(width 0.1143)
		(layer "B.Cu")
		(net "CPU_RSMRST#")
	)
	(segment
		(start 96.37776 -11.32205)
		(end 96.06915 -11.01344)
		(width 0.0889)
		(layer "In2.Cu")
		(net "CPU_RSMRST#")
	)
	(segment
		(start 84.836 -11.684)
		(end 81.026 -11.684)
		(width 0.0889)
		(layer "In2.Cu")
		(net "CPU_RSMRST#")
	)
	(segment
		(start 35.5473 -36.1569)
		(end 33.8582 -37.846)
		(width 0.0889)
		(layer "In2.Cu")
		(net "CPU_RSMRST#")
	)
	(segment
		(start 65.00495 -10.01395)
		(end 64.492124 -10.01395)
		(width 0.0889)
		(layer "In2.Cu")
		(net "CPU_RSMRST#")
	)
	(segment
		(start 38.304216 -37.319458)
		(end 38.308026 -37.315648)
		(width 0.0889)
		(layer "In2.Cu")
		(net "CPU_RSMRST#")
	)
	(segment
		(start 113.3094 -4.7498)
		(end 113.17605 -4.88315)
		(width 0.0889)
		(layer "In2.Cu")
		(net "CPU_RSMRST#")
	)
	(segment
		(start 85.058504 -11.906504)
		(end 84.836 -11.684)
		(width 0.0889)
		(layer "In2.Cu")
		(net "CPU_RSMRST#")
	)
	(segment
		(start 38.862 -17.2212)
		(end 44.76115 -23.12035)
		(width 0.0889)
		(layer "In2.Cu")
		(net "CPU_RSMRST#")
	)
	(segment
		(start 38.304216 -40.359584)
		(end 38.304216 -37.319458)
		(width 0.0889)
		(layer "In2.Cu")
		(net "CPU_RSMRST#")
	)
	(segment
		(start 106.0704 -11.184382)
		(end 104.748076 -12.506706)
		(width 0.0889)
		(layer "In2.Cu")
		(net "CPU_RSMRST#")
	)
	(segment
		(start 97.41535 -11.948414)
		(end 96.788986 -11.32205)
		(width 0.0889)
		(layer "In2.Cu")
		(net "CPU_RSMRST#")
	)
	(segment
		(start 45.866304 -25.058624)
		(end 46.159928 -24.765)
		(width 0.0889)
		(layer "In2.Cu")
		(net "CPU_RSMRST#")
	)
	(segment
		(start 95.35414 -10.00125)
		(end 95.175324 -10.00125)
		(width 0.0889)
		(layer "In2.Cu")
		(net "CPU_RSMRST#")
	)
	(segment
		(start 104.748076 -12.506706)
		(end 97.797112 -12.506706)
		(width 0.0889)
		(layer "In2.Cu")
		(net "CPU_RSMRST#")
	)
	(segment
		(start 96.06915 -11.01344)
		(end 96.06915 -10.71626)
		(width 0.0889)
		(layer "In2.Cu")
		(net "CPU_RSMRST#")
	)
	(segment
		(start 96.788986 -11.32205)
		(end 96.37776 -11.32205)
		(width 0.0889)
		(layer "In2.Cu")
		(net "CPU_RSMRST#")
	)
	(segment
		(start 113.17605 -4.88315)
		(end 107.95381 -4.88315)
		(width 0.0889)
		(layer "In2.Cu")
		(net "CPU_RSMRST#")
	)
	(segment
		(start 94.92615 -9.535414)
		(end 94.526354 -9.135618)
		(width 0.0889)
		(layer "In2.Cu")
		(net "CPU_RSMRST#")
	)
	(segment
		(start 45.025056 -25.16505)
		(end 45.759624 -25.16505)
		(width 0.0889)
		(layer "In2.Cu")
		(net "CPU_RSMRST#")
	)
	(segment
		(start 95.175324 -10.00125)
		(end 94.92615 -9.752076)
		(width 0.0889)
		(layer "In2.Cu")
		(net "CPU_RSMRST#")
	)
	(segment
		(start 38.308026 -36.677854)
		(end 37.787072 -36.1569)
		(width 0.0889)
		(layer "In2.Cu")
		(net "CPU_RSMRST#")
	)
	(segment
		(start 80.29575 -10.95375)
		(end 80.284828 -10.946384)
		(width 0.0889)
		(layer "In2.Cu")
		(net "CPU_RSMRST#")
	)
	(segment
		(start 65.937384 -10.946384)
		(end 65.00495 -10.01395)
		(width 0.0889)
		(layer "In2.Cu")
		(net "CPU_RSMRST#")
	)
	(segment
		(start 38.308026 -37.315648)
		(end 38.308026 -36.677854)
		(width 0.0889)
		(layer "In2.Cu")
		(net "CPU_RSMRST#")
	)
	(segment
		(start 89.114376 -11.906504)
		(end 85.058504 -11.906504)
		(width 0.0889)
		(layer "In2.Cu")
		(net "CPU_RSMRST#")
	)
	(segment
		(start 97.41535 -12.124944)
		(end 97.41535 -11.948414)
		(width 0.0889)
		(layer "In2.Cu")
		(net "CPU_RSMRST#")
	)
	(segment
		(start 106.0704 -6.76656)
		(end 106.0704 -11.184382)
		(width 0.0889)
		(layer "In2.Cu")
		(net "CPU_RSMRST#")
	)
	(segment
		(start 96.06915 -10.71626)
		(end 95.35414 -10.00125)
		(width 0.0889)
		(layer "In2.Cu")
		(net "CPU_RSMRST#")
	)
	(segment
		(start 62.0776 -12.428474)
		(end 62.0776 -12.8524)
		(width 0.0889)
		(layer "In2.Cu")
		(net "CPU_RSMRST#")
	)
	(segment
		(start 44.76115 -23.12035)
		(end 44.76115 -24.901144)
		(width 0.0889)
		(layer "In2.Cu")
		(net "CPU_RSMRST#")
	)
	(segment
		(start 33.8582 -37.846)
		(end 33.401 -37.846)
		(width 0.0889)
		(layer "In2.Cu")
		(net "CPU_RSMRST#")
	)
	(segment
		(start 91.885262 -9.135618)
		(end 89.114376 -11.906504)
		(width 0.0889)
		(layer "In2.Cu")
		(net "CPU_RSMRST#")
	)
	(segment
		(start 80.284828 -10.946384)
		(end 65.937384 -10.946384)
		(width 0.0889)
		(layer "In2.Cu")
		(net "CPU_RSMRST#")
	)
	(segment
		(start 94.92615 -9.752076)
		(end 94.92615 -9.535414)
		(width 0.0889)
		(layer "In2.Cu")
		(net "CPU_RSMRST#")
	)
	(segment
		(start 94.526354 -9.135618)
		(end 91.885262 -9.135618)
		(width 0.0889)
		(layer "In2.Cu")
		(net "CPU_RSMRST#")
	)
	(segment
		(start 37.787072 -36.1569)
		(end 35.5473 -36.1569)
		(width 0.0889)
		(layer "In2.Cu")
		(net "CPU_RSMRST#")
	)
	(segment
		(start 44.76115 -24.901144)
		(end 45.025056 -25.16505)
		(width 0.0889)
		(layer "In2.Cu")
		(net "CPU_RSMRST#")
	)
	(segment
		(start 97.797112 -12.506706)
		(end 97.41535 -12.124944)
		(width 0.0889)
		(layer "In2.Cu")
		(net "CPU_RSMRST#")
	)
	(segment
		(start 81.026 -11.684)
		(end 80.29575 -10.95375)
		(width 0.0889)
		(layer "In2.Cu")
		(net "CPU_RSMRST#")
	)
	(segment
		(start 107.95381 -4.88315)
		(end 106.0704 -6.76656)
		(width 0.0889)
		(layer "In2.Cu")
		(net "CPU_RSMRST#")
	)
	(segment
		(start 45.759624 -25.16505)
		(end 45.866304 -25.058624)
		(width 0.0889)
		(layer "In2.Cu")
		(net "CPU_RSMRST#")
	)
	(segment
		(start 64.492124 -10.01395)
		(end 62.0776 -12.428474)
		(width 0.0889)
		(layer "In2.Cu")
		(net "CPU_RSMRST#")
	)
	(segment
		(start 71.37527 -24.985218)
		(end 71.37527 -25.17267)
		(width 0.0889)
		(layer "In4.Cu")
		(net "CPU_RSMRST#")
	)
	(segment
		(start 40.004238 -33.274)
		(end 46.0121 -27.266138)
		(width 0.0889)
		(layer "In4.Cu")
		(net "CPU_RSMRST#")
	)
	(segment
		(start 32.809688 -33.274)
		(end 40.004238 -33.274)
		(width 0.0889)
		(layer "In4.Cu")
		(net "CPU_RSMRST#")
	)
	(segment
		(start 61.2648 -24.1046)
		(end 61.3664 -24.003)
		(width 0.0889)
		(layer "In4.Cu")
		(net "CPU_RSMRST#")
	)
	(segment
		(start 70.132702 -23.74265)
		(end 71.37527 -24.985218)
		(width 0.0889)
		(layer "In4.Cu")
		(net "CPU_RSMRST#")
	)
	(segment
		(start 50.421794 -25.704546)
		(end 49.947576 -26.178764)
		(width 0.0889)
		(layer "In4.Cu")
		(net "CPU_RSMRST#")
	)
	(segment
		(start 61.2648 -24.1046)
		(end 60.1345 -25.2349)
		(width 0.0889)
		(layer "In4.Cu")
		(net "CPU_RSMRST#")
	)
	(segment
		(start 46.390306 -24.995378)
		(end 46.159928 -24.765)
		(width 0.0889)
		(layer "In4.Cu")
		(net "CPU_RSMRST#")
	)
	(segment
		(start 32.175196 -33.908492)
		(end 32.809688 -33.274)
		(width 0.0889)
		(layer "In4.Cu")
		(net "CPU_RSMRST#")
	)
	(segment
		(start 63.373 -24.003)
		(end 64.43345 -22.94255)
		(width 0.0889)
		(layer "In4.Cu")
		(net "CPU_RSMRST#")
	)
	(segment
		(start 32.175196 -36.620196)
		(end 32.175196 -33.908492)
		(width 0.0889)
		(layer "In4.Cu")
		(net "CPU_RSMRST#")
	)
	(segment
		(start 54.429152 -25.704546)
		(end 50.421794 -25.704546)
		(width 0.0889)
		(layer "In4.Cu")
		(net "CPU_RSMRST#")
	)
	(segment
		(start 33.401 -37.846)
		(end 32.175196 -36.620196)
		(width 0.0889)
		(layer "In4.Cu")
		(net "CPU_RSMRST#")
	)
	(segment
		(start 46.0121 -27.266138)
		(end 46.0121 -25.216612)
		(width 0.0889)
		(layer "In4.Cu")
		(net "CPU_RSMRST#")
	)
	(segment
		(start 67.652646 -22.94255)
		(end 68.452746 -23.74265)
		(width 0.0889)
		(layer "In4.Cu")
		(net "CPU_RSMRST#")
	)
	(segment
		(start 54.898798 -25.2349)
		(end 54.429152 -25.704546)
		(width 0.0889)
		(layer "In4.Cu")
		(net "CPU_RSMRST#")
	)
	(segment
		(start 46.13275 -24.792178)
		(end 46.159928 -24.765)
		(width 0.0889)
		(layer "In4.Cu")
		(net "CPU_RSMRST#")
	)
	(segment
		(start 46.13275 -25.095962)
		(end 46.13275 -24.792178)
		(width 0.0889)
		(layer "In4.Cu")
		(net "CPU_RSMRST#")
	)
	(segment
		(start 60.1345 -25.2349)
		(end 54.898798 -25.2349)
		(width 0.0889)
		(layer "In4.Cu")
		(net "CPU_RSMRST#")
	)
	(segment
		(start 46.0121 -25.216612)
		(end 46.13275 -25.095962)
		(width 0.0889)
		(layer "In4.Cu")
		(net "CPU_RSMRST#")
	)
	(segment
		(start 49.947576 -26.178764)
		(end 47.319438 -26.178764)
		(width 0.0889)
		(layer "In4.Cu")
		(net "CPU_RSMRST#")
	)
	(segment
		(start 64.43345 -22.94255)
		(end 67.652646 -22.94255)
		(width 0.0889)
		(layer "In4.Cu")
		(net "CPU_RSMRST#")
	)
	(segment
		(start 61.3664 -24.003)
		(end 63.373 -24.003)
		(width 0.0889)
		(layer "In4.Cu")
		(net "CPU_RSMRST#")
	)
	(segment
		(start 47.319438 -26.178764)
		(end 46.390306 -25.249632)
		(width 0.0889)
		(layer "In4.Cu")
		(net "CPU_RSMRST#")
	)
	(segment
		(start 46.390306 -25.249632)
		(end 46.390306 -24.995378)
		(width 0.0889)
		(layer "In4.Cu")
		(net "CPU_RSMRST#")
	)
	(segment
		(start 68.452746 -23.74265)
		(end 70.132702 -23.74265)
		(width 0.0889)
		(layer "In4.Cu")
		(net "CPU_RSMRST#")
	)
	(segment
		(start 61.2648 -24.1046)
		(end 61.58865 -23.78075)
		(width 0.0889)
		(layer "In9.Cu")
		(net "CPU_RSMRST#")
	)
	(segment
		(start 62.0014 -12.8524)
		(end 62.0776 -12.8524)
		(width 0.0889)
		(layer "In9.Cu")
		(net "CPU_RSMRST#")
	)
	(segment
		(start 60.31865 -14.53515)
		(end 62.0014 -12.8524)
		(width 0.0889)
		(layer "In9.Cu")
		(net "CPU_RSMRST#")
	)
	(segment
		(start 61.58865 -23.78075)
		(end 61.58865 -19.29765)
		(width 0.0889)
		(layer "In9.Cu")
		(net "CPU_RSMRST#")
	)
	(segment
		(start 60.31865 -18.02765)
		(end 60.31865 -14.53515)
		(width 0.0889)
		(layer "In9.Cu")
		(net "CPU_RSMRST#")
	)
	(segment
		(start 61.58865 -19.29765)
		(end 60.31865 -18.02765)
		(width 0.0889)
		(layer "In9.Cu")
		(net "CPU_RSMRST#")
	)
	(segment
		(start 96.393 -69.1134)
		(end 97.2058 -69.9262)
		(width 0.254)
		(layer "F.Cu")
		(net "TP_VDDB")
	)
	(segment
		(start 96.393 -68.58)
		(end 96.393 -69.1134)
		(width 0.254)
		(layer "F.Cu")
		(net "TP_VDDB")
	)
	(via
		(at 97.2058 -69.9262)
		(size 0.508)
		(drill 0.254)
		(layers "F.Cu" "B.Cu")
		(net "TP_VDDB")
	)
	(segment
		(start 97.270062 -69.861938)
		(end 97.2058 -69.9262)
		(width 0.254)
		(layer "B.Cu")
		(net "TP_VDDB")
	)
	(segment
		(start 97.270062 -69.08292)
		(end 97.270062 -69.861938)
		(width 0.254)
		(layer "B.Cu")
		(net "TP_VDDB")
	)
	(segment
		(start 98.298 -69.6976)
		(end 98.0694 -69.9262)
		(width 0.254)
		(layer "F.Cu")
		(net "TP_BGND")
	)
	(segment
		(start 98.298 -68.58)
		(end 98.298 -69.6976)
		(width 0.254)
		(layer "F.Cu")
		(net "TP_BGND")
	)
	(via
		(at 98.0694 -69.9262)
		(size 0.508)
		(drill 0.254)
		(layers "F.Cu" "B.Cu")
		(net "TP_BGND")
	)
	(segment
		(start 98.0694 -69.9008)
		(end 98.0694 -69.9262)
		(width 0.254)
		(layer "B.Cu")
		(net "TP_BGND")
	)
	(segment
		(start 97.769934 -69.08292)
		(end 97.769934 -69.601334)
		(width 0.254)
		(layer "B.Cu")
		(net "TP_BGND")
	)
	(segment
		(start 97.769934 -69.601334)
		(end 98.0694 -69.9008)
		(width 0.254)
		(layer "B.Cu")
		(net "TP_BGND")
	)
	(segment
		(start 101.0666 -69.8754)
		(end 100.4824 -70.4596)
		(width 0.254)
		(layer "F.Cu")
		(net "PWRGD_PVCCP_VNN_PG")
	)
	(segment
		(start 13.990828 -55.833772)
		(end 14.549628 -55.833772)
		(width 0.254)
		(layer "F.Cu")
		(net "PWRGD_PVCCP_VNN_PG")
	)
	(segment
		(start 13.3604 -63.6016)
		(end 13.5636 -63.6016)
		(width 0.254)
		(layer "F.Cu")
		(net "PWRGD_PVCCP_VNN_PG")
	)
	(segment
		(start 14.8336 -64.3382)
		(end 14.6812 -64.4906)
		(width 0.254)
		(layer "F.Cu")
		(net "PWRGD_PVCCP_VNN_PG")
	)
	(segment
		(start 100.4824 -70.4596)
		(end 96.8756 -70.4596)
		(width 0.254)
		(layer "F.Cu")
		(net "PWRGD_PVCCP_VNN_PG")
	)
	(segment
		(start 13.5636 -63.6016)
		(end 14.4526 -64.4906)
		(width 0.254)
		(layer "F.Cu")
		(net "PWRGD_PVCCP_VNN_PG")
	)
	(segment
		(start 12.9794 -56.1086)
		(end 13.716 -56.1086)
		(width 0.254)
		(layer "F.Cu")
		(net "PWRGD_PVCCP_VNN_PG")
	)
	(segment
		(start 15.5702 -64.3382)
		(end 14.8336 -64.3382)
		(width 0.254)
		(layer "F.Cu")
		(net "PWRGD_PVCCP_VNN_PG")
	)
	(segment
		(start 14.549628 -55.833772)
		(end 14.552676 -55.830724)
		(width 0.254)
		(layer "F.Cu")
		(net "PWRGD_PVCCP_VNN_PG")
	)
	(segment
		(start 14.550898 -55.830724)
		(end 14.552676 -55.830724)
		(width 0.254)
		(layer "F.Cu")
		(net "PWRGD_PVCCP_VNN_PG")
	)
	(segment
		(start 15.168372 -55.833772)
		(end 14.558772 -55.833772)
		(width 0.254)
		(layer "F.Cu")
		(net "PWRGD_PVCCP_VNN_PG")
	)
	(segment
		(start 14.4526 -64.4906)
		(end 14.6812 -64.4906)
		(width 0.254)
		(layer "F.Cu")
		(net "PWRGD_PVCCP_VNN_PG")
	)
	(segment
		(start 14.5542 -55.8292)
		(end 14.552676 -55.830724)
		(width 0.254)
		(layer "F.Cu")
		(net "PWRGD_PVCCP_VNN_PG")
	)
	(segment
		(start 96.8756 -70.4596)
		(end 96.3422 -69.9262)
		(width 0.254)
		(layer "F.Cu")
		(net "PWRGD_PVCCP_VNN_PG")
	)
	(segment
		(start 14.558772 -55.833772)
		(end 14.5542 -55.8292)
		(width 0.254)
		(layer "F.Cu")
		(net "PWRGD_PVCCP_VNN_PG")
	)
	(segment
		(start 12.827 -56.261)
		(end 12.9794 -56.1086)
		(width 0.254)
		(layer "F.Cu")
		(net "PWRGD_PVCCP_VNN_PG")
	)
	(segment
		(start 101.0666 -69.2912)
		(end 101.0666 -69.8754)
		(width 0.254)
		(layer "F.Cu")
		(net "PWRGD_PVCCP_VNN_PG")
	)
	(segment
		(start 15.4178 -56.0832)
		(end 15.168372 -55.833772)
		(width 0.254)
		(layer "F.Cu")
		(net "PWRGD_PVCCP_VNN_PG")
	)
	(segment
		(start 13.716 -56.1086)
		(end 13.990828 -55.833772)
		(width 0.254)
		(layer "F.Cu")
		(net "PWRGD_PVCCP_VNN_PG")
	)
	(via
		(at 67.818 -68.9102)
		(size 0.508)
		(drill 0.254)
		(layers "F.Cu" "B.Cu")
		(net "PWRGD_PVCCP_VNN_PG")
	)
	(via
		(at 96.3422 -69.9262)
		(size 0.508)
		(drill 0.254)
		(layers "F.Cu" "B.Cu")
		(net "PWRGD_PVCCP_VNN_PG")
	)
	(via
		(at 18.796 -68.9356)
		(size 0.508)
		(drill 0.254)
		(layers "F.Cu" "B.Cu")
		(net "PWRGD_PVCCP_VNN_PG")
	)
	(via
		(at 12.827 -56.261)
		(size 0.7112)
		(drill 0.3556)
		(layers "F.Cu" "B.Cu")
		(net "PWRGD_PVCCP_VNN_PG")
	)
	(via
		(at 14.6812 -64.4906)
		(size 0.508)
		(drill 0.254)
		(layers "F.Cu" "B.Cu")
		(net "PWRGD_PVCCP_VNN_PG")
	)
	(via
		(at 14.550898 -55.830724)
		(size 0.508)
		(drill 0.254)
		(layers "F.Cu" "B.Cu")
		(net "PWRGD_PVCCP_VNN_PG")
	)
	(segment
		(start 67.996308 -69.088)
		(end 67.9958 -69.088)
		(width 0.254)
		(layer "In2.Cu")
		(net "PWRGD_PVCCP_VNN_PG")
	)
	(segment
		(start 93.87205 -72.39635)
		(end 79.71155 -72.39635)
		(width 0.254)
		(layer "In2.Cu")
		(net "PWRGD_PVCCP_VNN_PG")
	)
	(segment
		(start 79.71155 -72.39635)
		(end 78.4606 -71.1454)
		(width 0.254)
		(layer "In2.Cu")
		(net "PWRGD_PVCCP_VNN_PG")
	)
	(segment
		(start 68.170806 -69.262498)
		(end 67.996308 -69.088)
		(width 0.254)
		(layer "In2.Cu")
		(net "PWRGD_PVCCP_VNN_PG")
	)
	(segment
		(start 78.4606 -71.1454)
		(end 78.4606 -70.4596)
		(width 0.254)
		(layer "In2.Cu")
		(net "PWRGD_PVCCP_VNN_PG")
	)
	(segment
		(start 67.9958 -69.088)
		(end 67.818 -68.9102)
		(width 0.254)
		(layer "In2.Cu")
		(net "PWRGD_PVCCP_VNN_PG")
	)
	(segment
		(start 77.263498 -69.262498)
		(end 68.170806 -69.262498)
		(width 0.254)
		(layer "In2.Cu")
		(net "PWRGD_PVCCP_VNN_PG")
	)
	(segment
		(start 78.4606 -70.4596)
		(end 77.263498 -69.262498)
		(width 0.254)
		(layer "In2.Cu")
		(net "PWRGD_PVCCP_VNN_PG")
	)
	(segment
		(start 96.3422 -69.9262)
		(end 93.87205 -72.39635)
		(width 0.254)
		(layer "In2.Cu")
		(net "PWRGD_PVCCP_VNN_PG")
	)
	(segment
		(start 46.259496 -67.945)
		(end 59.2074 -67.945)
		(width 0.254)
		(layer "In4.Cu")
		(net "PWRGD_PVCCP_VNN_PG")
	)
	(segment
		(start 19.685 -68.9356)
		(end 21.1201 -70.3707)
		(width 0.254)
		(layer "In4.Cu")
		(net "PWRGD_PVCCP_VNN_PG")
	)
	(segment
		(start 14.6812 -64.4906)
		(end 15.1638 -64.4906)
		(width 0.254)
		(layer "In4.Cu")
		(net "PWRGD_PVCCP_VNN_PG")
	)
	(segment
		(start 60.1726 -68.9102)
		(end 67.818 -68.9102)
		(width 0.254)
		(layer "In4.Cu")
		(net "PWRGD_PVCCP_VNN_PG")
	)
	(segment
		(start 59.2074 -67.945)
		(end 60.1726 -68.9102)
		(width 0.254)
		(layer "In4.Cu")
		(net "PWRGD_PVCCP_VNN_PG")
	)
	(segment
		(start 15.1638 -64.4906)
		(end 15.60195 -64.05245)
		(width 0.254)
		(layer "In4.Cu")
		(net "PWRGD_PVCCP_VNN_PG")
	)
	(segment
		(start 18.796 -68.9356)
		(end 19.685 -68.9356)
		(width 0.254)
		(layer "In4.Cu")
		(net "PWRGD_PVCCP_VNN_PG")
	)
	(segment
		(start 21.1201 -70.3707)
		(end 43.833796 -70.3707)
		(width 0.254)
		(layer "In4.Cu")
		(net "PWRGD_PVCCP_VNN_PG")
	)
	(segment
		(start 14.602968 -55.830724)
		(end 14.550898 -55.830724)
		(width 0.254)
		(layer "In4.Cu")
		(net "PWRGD_PVCCP_VNN_PG")
	)
	(segment
		(start 15.60195 -64.05245)
		(end 15.60195 -56.829706)
		(width 0.254)
		(layer "In4.Cu")
		(net "PWRGD_PVCCP_VNN_PG")
	)
	(segment
		(start 43.833796 -70.3707)
		(end 46.259496 -67.945)
		(width 0.254)
		(layer "In4.Cu")
		(net "PWRGD_PVCCP_VNN_PG")
	)
	(segment
		(start 15.60195 -56.829706)
		(end 14.602968 -55.830724)
		(width 0.254)
		(layer "In4.Cu")
		(net "PWRGD_PVCCP_VNN_PG")
	)
	(segment
		(start 15.8496 -66.9798)
		(end 15.8496 -65.659)
		(width 0.254)
		(layer "In9.Cu")
		(net "PWRGD_PVCCP_VNN_PG")
	)
	(segment
		(start 15.8496 -65.659)
		(end 14.6812 -64.4906)
		(width 0.254)
		(layer "In9.Cu")
		(net "PWRGD_PVCCP_VNN_PG")
	)
	(segment
		(start 18.796 -68.9356)
		(end 17.8054 -68.9356)
		(width 0.254)
		(layer "In9.Cu")
		(net "PWRGD_PVCCP_VNN_PG")
	)
	(segment
		(start 17.8054 -68.9356)
		(end 15.8496 -66.9798)
		(width 0.254)
		(layer "In9.Cu")
		(net "PWRGD_PVCCP_VNN_PG")
	)
	(segment
		(start 114.09045 -65.190624)
		(end 114.17681 -65.10401)
		(width 0.1143)
		(layer "F.Cu")
		(net "CLK_GEN_INA_PG")
	)
	(segment
		(start 114.427 -66.75628)
		(end 114.427 -65.91173)
		(width 0.1143)
		(layer "F.Cu")
		(net "CLK_GEN_INA_PG")
	)
	(segment
		(start 112.1664 -65.4558)
		(end 112.1664 -64.7192)
		(width 0.1143)
		(layer "F.Cu")
		(net "CLK_GEN_INA_PG")
	)
	(segment
		(start 114.17681 -65.10401)
		(end 113.792 -64.7192)
		(width 0.1143)
		(layer "F.Cu")
		(net "CLK_GEN_INA_PG")
	)
	(segment
		(start 114.09045 -65.57518)
		(end 114.09045 -65.190624)
		(width 0.1143)
		(layer "F.Cu")
		(net "CLK_GEN_INA_PG")
	)
	(segment
		(start 114.427 -65.91173)
		(end 114.09045 -65.57518)
		(width 0.1143)
		(layer "F.Cu")
		(net "CLK_GEN_INA_PG")
	)
	(segment
		(start 113.792 -64.7192)
		(end 112.9284 -64.7192)
		(width 0.1143)
		(layer "F.Cu")
		(net "CLK_GEN_INA_PG")
	)
	(segment
		(start 112.1664 -64.7192)
		(end 112.9284 -64.7192)
		(width 0.1143)
		(layer "F.Cu")
		(net "CLK_GEN_INA_PG")
	)
	(segment
		(start 112.395 -65.6844)
		(end 112.1664 -65.4558)
		(width 0.1143)
		(layer "F.Cu")
		(net "CLK_GEN_INA_PG")
	)
	(via
		(at 112.395 -65.6844)
		(size 0.7112)
		(drill 0.3556)
		(layers "F.Cu" "B.Cu")
		(net "CLK_GEN_INA_PG")
	)
	(segment
		(start 108.077 -63.1444)
		(end 107.5944 -62.6618)
		(width 0.1143)
		(layer "F.Cu")
		(net "DDR3_DRAM_PWROK")
	)
	(segment
		(start 110.53572 -64.643)
		(end 110.151926 -64.643)
		(width 0.1143)
		(layer "F.Cu")
		(net "DDR3_DRAM_PWROK")
	)
	(segment
		(start 108.653326 -63.1444)
		(end 108.077 -63.1444)
		(width 0.1143)
		(layer "F.Cu")
		(net "DDR3_DRAM_PWROK")
	)
	(segment
		(start 73.32345 -31.01975)
		(end 72.500744 -31.01975)
		(width 0.1143)
		(layer "F.Cu")
		(net "DDR3_DRAM_PWROK")
	)
	(segment
		(start 110.151926 -64.643)
		(end 108.653326 -63.1444)
		(width 0.1143)
		(layer "F.Cu")
		(net "DDR3_DRAM_PWROK")
	)
	(segment
		(start 72.500744 -31.01975)
		(end 72.214994 -30.734)
		(width 0.1143)
		(layer "F.Cu")
		(net "DDR3_DRAM_PWROK")
	)
	(segment
		(start 73.6092 -30.734)
		(end 73.32345 -31.01975)
		(width 0.1143)
		(layer "F.Cu")
		(net "DDR3_DRAM_PWROK")
	)
	(segment
		(start 71.2216 -31.3182)
		(end 71.8058 -30.734)
		(width 0.1143)
		(layer "F.Cu")
		(net "DDR3_DRAM_PWROK")
	)
	(segment
		(start 72.214994 -30.734)
		(end 71.8058 -30.734)
		(width 0.1143)
		(layer "F.Cu")
		(net "DDR3_DRAM_PWROK")
	)
	(segment
		(start 71.2216 -32.82315)
		(end 71.2216 -31.3182)
		(width 0.1143)
		(layer "F.Cu")
		(net "DDR3_DRAM_PWROK")
	)
	(via
		(at 77.253846 -32.600646)
		(size 0.4318)
		(drill 0.2032)
		(layers "F.Cu" "B.Cu")
		(net "DDR3_DRAM_PWROK")
	)
	(via
		(at 107.5944 -62.6618)
		(size 0.508)
		(drill 0.254)
		(layers "F.Cu" "B.Cu")
		(net "DDR3_DRAM_PWROK")
	)
	(via
		(at 86.9188 -50.8254)
		(size 0.7112)
		(drill 0.3556)
		(layers "F.Cu" "B.Cu")
		(net "DDR3_DRAM_PWROK")
	)
	(via
		(at 86.1822 -44.2214)
		(size 0.4318)
		(drill 0.2032)
		(layers "F.Cu" "B.Cu")
		(net "DDR3_DRAM_PWROK")
	)
	(via
		(at 71.2216 -32.82315)
		(size 0.508)
		(drill 0.254)
		(layers "F.Cu" "B.Cu")
		(net "DDR3_DRAM_PWROK")
	)
	(segment
		(start 85.9536 -44.45)
		(end 86.1822 -44.2214)
		(width 0.1143)
		(layer "B.Cu")
		(net "DDR3_DRAM_PWROK")
	)
	(segment
		(start 103.655114 -60.85205)
		(end 103.65105 -60.85205)
		(width 0.1143)
		(layer "B.Cu")
		(net "DDR3_DRAM_PWROK")
	)
	(segment
		(start 102.31755 -59.51855)
		(end 96.29775 -59.51855)
		(width 0.1143)
		(layer "B.Cu")
		(net "DDR3_DRAM_PWROK")
	)
	(segment
		(start 107.5944 -62.6618)
		(end 107.1118 -63.1444)
		(width 0.1143)
		(layer "B.Cu")
		(net "DDR3_DRAM_PWROK")
	)
	(segment
		(start 86.9188 -50.8254)
		(end 86.25205 -50.15865)
		(width 0.1143)
		(layer "B.Cu")
		(net "DDR3_DRAM_PWROK")
	)
	(segment
		(start 92.43822 -53.184552)
		(end 91.67622 -52.422552)
		(width 0.1143)
		(layer "B.Cu")
		(net "DDR3_DRAM_PWROK")
	)
	(segment
		(start 88.515952 -52.422552)
		(end 86.9188 -50.8254)
		(width 0.1143)
		(layer "B.Cu")
		(net "DDR3_DRAM_PWROK")
	)
	(segment
		(start 86.25205 -50.15865)
		(end 86.25205 -45.73905)
		(width 0.1143)
		(layer "B.Cu")
		(net "DDR3_DRAM_PWROK")
	)
	(segment
		(start 85.9536 -45.4406)
		(end 85.9536 -44.45)
		(width 0.1143)
		(layer "B.Cu")
		(net "DDR3_DRAM_PWROK")
	)
	(segment
		(start 103.65105 -60.85205)
		(end 102.31755 -59.51855)
		(width 0.1143)
		(layer "B.Cu")
		(net "DDR3_DRAM_PWROK")
	)
	(segment
		(start 107.1118 -63.1444)
		(end 105.947464 -63.1444)
		(width 0.1143)
		(layer "B.Cu")
		(net "DDR3_DRAM_PWROK")
	)
	(segment
		(start 92.43822 -55.65902)
		(end 92.43822 -53.184552)
		(width 0.1143)
		(layer "B.Cu")
		(net "DDR3_DRAM_PWROK")
	)
	(segment
		(start 91.67622 -52.422552)
		(end 88.515952 -52.422552)
		(width 0.1143)
		(layer "B.Cu")
		(net "DDR3_DRAM_PWROK")
	)
	(segment
		(start 105.947464 -63.1444)
		(end 103.655114 -60.85205)
		(width 0.1143)
		(layer "B.Cu")
		(net "DDR3_DRAM_PWROK")
	)
	(segment
		(start 96.29775 -59.51855)
		(end 92.43822 -55.65902)
		(width 0.1143)
		(layer "B.Cu")
		(net "DDR3_DRAM_PWROK")
	)
	(segment
		(start 86.25205 -45.73905)
		(end 85.9536 -45.4406)
		(width 0.1143)
		(layer "B.Cu")
		(net "DDR3_DRAM_PWROK")
	)
	(segment
		(start 74.89825 -32.78505)
		(end 74.4474 -32.3342)
		(width 0.0889)
		(layer "In2.Cu")
		(net "DDR3_DRAM_PWROK")
	)
	(segment
		(start 74.4474 -32.3342)
		(end 71.71055 -32.3342)
		(width 0.0889)
		(layer "In2.Cu")
		(net "DDR3_DRAM_PWROK")
	)
	(segment
		(start 71.71055 -32.3342)
		(end 71.2216 -32.82315)
		(width 0.0889)
		(layer "In2.Cu")
		(net "DDR3_DRAM_PWROK")
	)
	(segment
		(start 77.253846 -32.600646)
		(end 77.069442 -32.78505)
		(width 0.0889)
		(layer "In2.Cu")
		(net "DDR3_DRAM_PWROK")
	)
	(segment
		(start 77.069442 -32.78505)
		(end 74.89825 -32.78505)
		(width 0.0889)
		(layer "In2.Cu")
		(net "DDR3_DRAM_PWROK")
	)
	(segment
		(start 81.740248 -43.310048)
		(end 79.7052 -41.275)
		(width 0.0889)
		(layer "In9.Cu")
		(net "DDR3_DRAM_PWROK")
	)
	(segment
		(start 86.1822 -44.196)
		(end 85.5472 -43.561)
		(width 0.0889)
		(layer "In9.Cu")
		(net "DDR3_DRAM_PWROK")
	)
	(segment
		(start 86.1822 -44.2214)
		(end 86.1822 -44.196)
		(width 0.0889)
		(layer "In9.Cu")
		(net "DDR3_DRAM_PWROK")
	)
	(segment
		(start 79.7052 -41.275)
		(end 79.7052 -38.4302)
		(width 0.0889)
		(layer "In9.Cu")
		(net "DDR3_DRAM_PWROK")
	)
	(segment
		(start 77.3176 -32.6644)
		(end 77.253846 -32.600646)
		(width 0.0889)
		(layer "In9.Cu")
		(net "DDR3_DRAM_PWROK")
	)
	(segment
		(start 79.7052 -38.4302)
		(end 77.3176 -36.0426)
		(width 0.0889)
		(layer "In9.Cu")
		(net "DDR3_DRAM_PWROK")
	)
	(segment
		(start 85.5472 -43.561)
		(end 82.484976 -43.561)
		(width 0.0889)
		(layer "In9.Cu")
		(net "DDR3_DRAM_PWROK")
	)
	(segment
		(start 82.484976 -43.561)
		(end 82.234024 -43.310048)
		(width 0.0889)
		(layer "In9.Cu")
		(net "DDR3_DRAM_PWROK")
	)
	(segment
		(start 77.3176 -36.0426)
		(end 77.3176 -32.6644)
		(width 0.0889)
		(layer "In9.Cu")
		(net "DDR3_DRAM_PWROK")
	)
	(segment
		(start 82.234024 -43.310048)
		(end 81.740248 -43.310048)
		(width 0.0889)
		(layer "In9.Cu")
		(net "DDR3_DRAM_PWROK")
	)
	(segment
		(start 101.0666 -68.4276)
		(end 100.9396 -68.5546)
		(width 0.2032)
		(layer "F.Cu")
		(net "VR_P1V1_EN")
	)
	(segment
		(start 100.9396 -68.5546)
		(end 100.1522 -68.5546)
		(width 0.2032)
		(layer "F.Cu")
		(net "VR_P1V1_EN")
	)
	(segment
		(start 100.1776 -68.5292)
		(end 100.1522 -68.5546)
		(width 0.2032)
		(layer "F.Cu")
		(net "VR_P1V1_EN")
	)
	(segment
		(start 100.1522 -68.5546)
		(end 99.4664 -68.5546)
		(width 0.2032)
		(layer "F.Cu")
		(net "VR_P1V1_EN")
	)
	(segment
		(start 99.4664 -68.5546)
		(end 99.187 -68.2752)
		(width 0.2032)
		(layer "F.Cu")
		(net "VR_P1V1_EN")
	)
	(segment
		(start 100.1776 -67.5894)
		(end 100.1776 -68.5292)
		(width 0.2032)
		(layer "F.Cu")
		(net "VR_P1V1_EN")
	)
	(via
		(at 100.1522 -68.5546)
		(size 0.7112)
		(drill 0.3556)
		(layers "F.Cu" "B.Cu")
		(net "VR_P1V1_EN")
	)
	(via
		(at 99.187 -68.2752)
		(size 0.508)
		(drill 0.254)
		(layers "F.Cu" "B.Cu")
		(net "VR_P1V1_EN")
	)
	(segment
		(start 98.443796 -68.159122)
		(end 99.070922 -68.159122)
		(width 0.2032)
		(layer "B.Cu")
		(net "VR_P1V1_EN")
	)
	(segment
		(start 99.070922 -68.159122)
		(end 99.187 -68.2752)
		(width 0.2032)
		(layer "B.Cu")
		(net "VR_P1V1_EN")
	)
	(via
		(at 101.4222 -66.6496)
		(size 0.7112)
		(drill 0.3556)
		(layers "F.Cu" "B.Cu")
		(net "VR_P1V1_VFB")
	)
	(segment
		(start 102.362 -66.8782)
		(end 103.0986 -66.8782)
		(width 0.254)
		(layer "B.Cu")
		(net "VR_P1V1_VFB")
	)
	(segment
		(start 101.4222 -66.6496)
		(end 101.6508 -66.8782)
		(width 0.254)
		(layer "B.Cu")
		(net "VR_P1V1_VFB")
	)
	(segment
		(start 100.33 -66.0908)
		(end 100.261674 -66.159126)
		(width 0.254)
		(layer "B.Cu")
		(net "VR_P1V1_VFB")
	)
	(segment
		(start 101.4222 -66.6496)
		(end 100.8634 -66.0908)
		(width 0.254)
		(layer "B.Cu")
		(net "VR_P1V1_VFB")
	)
	(segment
		(start 100.261674 -66.159126)
		(end 98.443796 -66.159126)
		(width 0.254)
		(layer "B.Cu")
		(net "VR_P1V1_VFB")
	)
	(segment
		(start 103.0986 -66.8782)
		(end 103.124 -66.8528)
		(width 0.254)
		(layer "B.Cu")
		(net "VR_P1V1_VFB")
	)
	(segment
		(start 101.6508 -66.8782)
		(end 102.362 -66.8782)
		(width 0.254)
		(layer "B.Cu")
		(net "VR_P1V1_VFB")
	)
	(segment
		(start 100.8634 -66.0908)
		(end 100.33 -66.0908)
		(width 0.254)
		(layer "B.Cu")
		(net "VR_P1V1_VFB")
	)
	(via
		(at 88.138 -66.04)
		(size 0.7112)
		(drill 0.3556)
		(layers "F.Cu" "B.Cu")
		(net "VR_P1V1_PVIN")
	)
	(via
		(at 100.2411 -67.04076)
		(size 0.7112)
		(drill 0.3556)
		(layers "F.Cu" "B.Cu")
		(net "VR_P1V1_SS")
	)
	(segment
		(start 99.859338 -66.658998)
		(end 100.2411 -67.04076)
		(width 0.254)
		(layer "B.Cu")
		(net "VR_P1V1_SS")
	)
	(segment
		(start 98.443796 -66.658998)
		(end 99.859338 -66.658998)
		(width 0.254)
		(layer "B.Cu")
		(net "VR_P1V1_SS")
	)
	(segment
		(start 100.33 -67.8688)
		(end 100.33 -67.12966)
		(width 0.254)
		(layer "B.Cu")
		(net "VR_P1V1_SS")
	)
	(segment
		(start 100.33 -67.12966)
		(end 100.2411 -67.04076)
		(width 0.254)
		(layer "B.Cu")
		(net "VR_P1V1_SS")
	)
	(via
		(at 104.14 -67.691)
		(size 0.7112)
		(drill 0.3556)
		(layers "F.Cu" "B.Cu")
		(net "VR_P1V1_VFBR")
	)
	(segment
		(start 104.14 -66.9544)
		(end 103.9368 -66.7512)
		(width 0.254)
		(layer "B.Cu")
		(net "VR_P1V1_VFBR")
	)
	(segment
		(start 101.092 -67.8942)
		(end 102.2096 -67.8942)
		(width 0.254)
		(layer "B.Cu")
		(net "VR_P1V1_VFBR")
	)
	(segment
		(start 103.0986 -67.7418)
		(end 102.362 -67.7418)
		(width 0.254)
		(layer "B.Cu")
		(net "VR_P1V1_VFBR")
	)
	(segment
		(start 103.124 -67.7672)
		(end 104.0638 -67.7672)
		(width 0.254)
		(layer "B.Cu")
		(net "VR_P1V1_VFBR")
	)
	(segment
		(start 104.14 -67.691)
		(end 104.14 -66.9544)
		(width 0.254)
		(layer "B.Cu")
		(net "VR_P1V1_VFBR")
	)
	(segment
		(start 102.2096 -67.8942)
		(end 102.362 -67.7418)
		(width 0.254)
		(layer "B.Cu")
		(net "VR_P1V1_VFBR")
	)
	(segment
		(start 103.124 -67.7672)
		(end 103.0986 -67.7418)
		(width 0.254)
		(layer "B.Cu")
		(net "VR_P1V1_VFBR")
	)
	(segment
		(start 104.0638 -67.7672)
		(end 104.14 -67.691)
		(width 0.254)
		(layer "B.Cu")
		(net "VR_P1V1_VFBR")
	)
	(via
		(at 99.440746 -64.304926)
		(size 0.7112)
		(drill 0.3556)
		(layers "F.Cu" "B.Cu")
		(net "VR_P1V1_AVIN")
	)
	(segment
		(start 100.3046 -64.3382)
		(end 100.271326 -64.304926)
		(width 0.3048)
		(layer "B.Cu")
		(net "VR_P1V1_AVIN")
	)
	(segment
		(start 100.33 -64.3128)
		(end 100.3046 -64.3382)
		(width 0.3048)
		(layer "B.Cu")
		(net "VR_P1V1_AVIN")
	)
	(segment
		(start 98.848926 -65.158874)
		(end 99.440746 -64.567054)
		(width 0.3048)
		(layer "B.Cu")
		(net "VR_P1V1_AVIN")
	)
	(segment
		(start 100.457 -64.1858)
		(end 100.33 -64.3128)
		(width 0.3048)
		(layer "B.Cu")
		(net "VR_P1V1_AVIN")
	)
	(segment
		(start 101.092 -64.1858)
		(end 100.457 -64.1858)
		(width 0.3048)
		(layer "B.Cu")
		(net "VR_P1V1_AVIN")
	)
	(segment
		(start 99.440746 -64.567054)
		(end 99.440746 -64.304926)
		(width 0.3048)
		(layer "B.Cu")
		(net "VR_P1V1_AVIN")
	)
	(segment
		(start 98.443796 -65.158874)
		(end 98.848926 -65.158874)
		(width 0.3048)
		(layer "B.Cu")
		(net "VR_P1V1_AVIN")
	)
	(segment
		(start 100.271326 -64.304926)
		(end 99.440746 -64.304926)
		(width 0.3048)
		(layer "B.Cu")
		(net "VR_P1V1_AVIN")
	)
	(segment
		(start 40.767 -44.51604)
		(end 39.55796 -45.72508)
		(width 0.254)
		(layer "F.Cu")
		(net "P3V3_CPU_PG_S1")
	)
	(segment
		(start 40.767 -43.86072)
		(end 40.767 -44.51604)
		(width 0.254)
		(layer "F.Cu")
		(net "P3V3_CPU_PG_S1")
	)
	(segment
		(start 38.53688 -45.72508)
		(end 39.55796 -45.72508)
		(width 0.254)
		(layer "F.Cu")
		(net "P3V3_CPU_PG_S1")
	)
	(segment
		(start 37.9476 -45.1358)
		(end 38.53688 -45.72508)
		(width 0.254)
		(layer "F.Cu")
		(net "P3V3_CPU_PG_S1")
	)
	(via
		(at 37.9476 -45.1358)
		(size 0.7112)
		(drill 0.3556)
		(layers "F.Cu" "B.Cu")
		(net "P3V3_CPU_PG_S1")
	)
	(segment
		(start 38.862 -43.3832)
		(end 38.862 -42.4688)
		(width 0.254)
		(layer "F.Cu")
		(net "P3V3_CPU_PG_S2")
	)
	(segment
		(start 39.33952 -41.99128)
		(end 40.11676 -41.99128)
		(width 0.254)
		(layer "F.Cu")
		(net "P3V3_CPU_PG_S2")
	)
	(segment
		(start 38.8874 -43.4086)
		(end 38.862 -43.3832)
		(width 0.254)
		(layer "F.Cu")
		(net "P3V3_CPU_PG_S2")
	)
	(segment
		(start 38.862 -42.4688)
		(end 39.33952 -41.99128)
		(width 0.254)
		(layer "F.Cu")
		(net "P3V3_CPU_PG_S2")
	)
	(via
		(at 38.8874 -43.4086)
		(size 0.7112)
		(drill 0.3556)
		(layers "F.Cu" "B.Cu")
		(net "P3V3_CPU_PG_S2")
	)
	(via
		(at 41.6306 -44.3738)
		(size 0.7112)
		(drill 0.3556)
		(layers "F.Cu" "B.Cu")
		(net "CLK_GEN_R_PG")
	)
	(segment
		(start 43.046142 -45.459142)
		(end 42.4815 -44.8945)
		(width 0.1143)
		(layer "B.Cu")
		(net "CLK_GEN_R_PG")
	)
	(segment
		(start 43.836844 -45.459142)
		(end 43.046142 -45.459142)
		(width 0.1143)
		(layer "B.Cu")
		(net "CLK_GEN_R_PG")
	)
	(segment
		(start 42.4815 -44.8945)
		(end 42.1513 -44.8945)
		(width 0.1143)
		(layer "B.Cu")
		(net "CLK_GEN_R_PG")
	)
	(segment
		(start 41.402 -43.4086)
		(end 41.6306 -43.6372)
		(width 0.1143)
		(layer "B.Cu")
		(net "CLK_GEN_R_PG")
	)
	(segment
		(start 44.058586 -46.087792)
		(end 44.058586 -45.680884)
		(width 0.1143)
		(layer "B.Cu")
		(net "CLK_GEN_R_PG")
	)
	(segment
		(start 44.058586 -45.680884)
		(end 43.836844 -45.459142)
		(width 0.1143)
		(layer "B.Cu")
		(net "CLK_GEN_R_PG")
	)
	(segment
		(start 42.1513 -44.8945)
		(end 41.6306 -44.3738)
		(width 0.1143)
		(layer "B.Cu")
		(net "CLK_GEN_R_PG")
	)
	(segment
		(start 41.6306 -43.6372)
		(end 41.6306 -44.3738)
		(width 0.1143)
		(layer "B.Cu")
		(net "CLK_GEN_R_PG")
	)
	(segment
		(start 41.402 -42.7228)
		(end 41.402 -43.4086)
		(width 0.1143)
		(layer "B.Cu")
		(net "CLK_GEN_R_PG")
	)
	(segment
		(start 112.1664 -63.402972)
		(end 112.1664 -63.8556)
		(width 0.1143)
		(layer "F.Cu")
		(net "CLK_GEN_PG")
	)
	(segment
		(start 99.050856 -66.186558)
		(end 102.530402 -62.707012)
		(width 0.1143)
		(layer "F.Cu")
		(net "CLK_GEN_PG")
	)
	(segment
		(start 83.648042 -66.186558)
		(end 99.050856 -66.186558)
		(width 0.1143)
		(layer "F.Cu")
		(net "CLK_GEN_PG")
	)
	(segment
		(start 81.4578 -68.3768)
		(end 83.648042 -66.186558)
		(width 0.1143)
		(layer "F.Cu")
		(net "CLK_GEN_PG")
	)
	(segment
		(start 110.440724 -60.90285)
		(end 111.252 -61.714126)
		(width 0.1143)
		(layer "F.Cu")
		(net "CLK_GEN_PG")
	)
	(segment
		(start 42.418 -42.4942)
		(end 42.418 -41.82491)
		(width 0.1143)
		(layer "F.Cu")
		(net "CLK_GEN_PG")
	)
	(segment
		(start 111.252 -61.714126)
		(end 111.252 -62.488572)
		(width 0.1143)
		(layer "F.Cu")
		(net "CLK_GEN_PG")
	)
	(segment
		(start 104.100376 -60.90285)
		(end 110.440724 -60.90285)
		(width 0.1143)
		(layer "F.Cu")
		(net "CLK_GEN_PG")
	)
	(segment
		(start 102.530402 -62.472824)
		(end 104.100376 -60.90285)
		(width 0.1143)
		(layer "F.Cu")
		(net "CLK_GEN_PG")
	)
	(segment
		(start 102.530402 -62.707012)
		(end 102.530402 -62.472824)
		(width 0.1143)
		(layer "F.Cu")
		(net "CLK_GEN_PG")
	)
	(segment
		(start 42.418 -41.82491)
		(end 42.565574 -41.677336)
		(width 0.1143)
		(layer "F.Cu")
		(net "CLK_GEN_PG")
	)
	(segment
		(start 111.252 -62.488572)
		(end 112.1664 -63.402972)
		(width 0.1143)
		(layer "F.Cu")
		(net "CLK_GEN_PG")
	)
	(segment
		(start 79.0956 -68.3768)
		(end 81.4578 -68.3768)
		(width 0.1143)
		(layer "F.Cu")
		(net "CLK_GEN_PG")
	)
	(via
		(at 79.0956 -68.3768)
		(size 0.508)
		(drill 0.254)
		(layers "F.Cu" "B.Cu")
		(net "CLK_GEN_PG")
	)
	(via
		(at 66.9544 -60.9219)
		(size 0.508)
		(drill 0.254)
		(layers "F.Cu" "B.Cu")
		(net "CLK_GEN_PG")
	)
	(via
		(at 47.625 -27.051)
		(size 0.508)
		(drill 0.254)
		(layers "F.Cu" "B.Cu")
		(net "CLK_GEN_PG")
	)
	(via
		(at 67.41795 -66.04)
		(size 0.7112)
		(drill 0.3556)
		(layers "F.Cu" "B.Cu")
		(net "CLK_GEN_PG")
	)
	(via
		(at 42.565574 -41.677336)
		(size 0.508)
		(drill 0.254)
		(layers "F.Cu" "B.Cu")
		(net "CLK_GEN_PG")
	)
	(via
		(at 110.4646 -1.75895)
		(size 0.508)
		(drill 0.254)
		(layers "F.Cu" "B.Cu")
		(net "CLK_GEN_PG")
	)
	(segment
		(start 42.38371 -41.8592)
		(end 42.565574 -41.677336)
		(width 0.1143)
		(layer "B.Cu")
		(net "CLK_GEN_PG")
	)
	(segment
		(start 67.41795 -66.04)
		(end 67.41795 -63.993522)
		(width 0.1143)
		(layer "B.Cu")
		(net "CLK_GEN_PG")
	)
	(segment
		(start 66.9544 -63.529972)
		(end 66.9544 -60.9219)
		(width 0.1143)
		(layer "B.Cu")
		(net "CLK_GEN_PG")
	)
	(segment
		(start 67.41795 -63.993522)
		(end 66.9544 -63.529972)
		(width 0.1143)
		(layer "B.Cu")
		(net "CLK_GEN_PG")
	)
	(segment
		(start 41.402 -41.8592)
		(end 42.38371 -41.8592)
		(width 0.1143)
		(layer "B.Cu")
		(net "CLK_GEN_PG")
	)
	(segment
		(start 115.2652 -0.9652)
		(end 118.745 -4.445)
		(width 0.1143)
		(layer "B.Cu")
		(net "CLK_GEN_PG")
	)
	(segment
		(start 67.41795 -66.13652)
		(end 67.41795 -66.04)
		(width 0.1143)
		(layer "B.Cu")
		(net "CLK_GEN_PG")
	)
	(segment
		(start 48.006 -27.432)
		(end 47.625 -27.051)
		(width 0.1143)
		(layer "B.Cu")
		(net "CLK_GEN_PG")
	)
	(segment
		(start 74.312526 -68.786248)
		(end 74.194924 -68.90385)
		(width 0.1143)
		(layer "B.Cu")
		(net "CLK_GEN_PG")
	)
	(segment
		(start 111.25835 -0.9652)
		(end 115.2652 -0.9652)
		(width 0.1143)
		(layer "B.Cu")
		(net "CLK_GEN_PG")
	)
	(segment
		(start 118.745 -4.445)
		(end 119.09552 -4.445)
		(width 0.1143)
		(layer "B.Cu")
		(net "CLK_GEN_PG")
	)
	(segment
		(start 79.0956 -68.3768)
		(end 78.686152 -68.786248)
		(width 0.1143)
		(layer "B.Cu")
		(net "CLK_GEN_PG")
	)
	(segment
		(start 47.52213 -25.8445)
		(end 47.52213 -26.94813)
		(width 0.1143)
		(layer "B.Cu")
		(net "CLK_GEN_PG")
	)
	(segment
		(start 74.194924 -68.90385)
		(end 70.18528 -68.90385)
		(width 0.1143)
		(layer "B.Cu")
		(net "CLK_GEN_PG")
	)
	(segment
		(start 70.18528 -68.90385)
		(end 67.41795 -66.13652)
		(width 0.1143)
		(layer "B.Cu")
		(net "CLK_GEN_PG")
	)
	(segment
		(start 110.4646 -1.75895)
		(end 111.25835 -0.9652)
		(width 0.1143)
		(layer "B.Cu")
		(net "CLK_GEN_PG")
	)
	(segment
		(start 47.52213 -26.94813)
		(end 47.625 -27.051)
		(width 0.1143)
		(layer "B.Cu")
		(net "CLK_GEN_PG")
	)
	(segment
		(start 78.686152 -68.786248)
		(end 74.312526 -68.786248)
		(width 0.1143)
		(layer "B.Cu")
		(net "CLK_GEN_PG")
	)
	(segment
		(start 48.006 -27.7622)
		(end 48.006 -27.432)
		(width 0.1143)
		(layer "B.Cu")
		(net "CLK_GEN_PG")
	)
	(segment
		(start 47.77105 -44.46905)
		(end 47.77105 -43.58005)
		(width 0.0889)
		(layer "In2.Cu")
		(net "CLK_GEN_PG")
	)
	(segment
		(start 66.9544 -60.9219)
		(end 66.9417 -60.9219)
		(width 0.0889)
		(layer "In2.Cu")
		(net "CLK_GEN_PG")
	)
	(segment
		(start 54.95544 -51.09845)
		(end 54.28488 -51.09845)
		(width 0.0889)
		(layer "In2.Cu")
		(net "CLK_GEN_PG")
	)
	(segment
		(start 52.345844 -48.076104)
		(end 52.345844 -47.099728)
		(width 0.0889)
		(layer "In2.Cu")
		(net "CLK_GEN_PG")
	)
	(segment
		(start 64.3382 -58.3184)
		(end 62.17539 -58.3184)
		(width 0.0889)
		(layer "In2.Cu")
		(net "CLK_GEN_PG")
	)
	(segment
		(start 62.17539 -58.3184)
		(end 54.95544 -51.09845)
		(width 0.0889)
		(layer "In2.Cu")
		(net "CLK_GEN_PG")
	)
	(segment
		(start 49.907444 -46.605444)
		(end 47.77105 -44.46905)
		(width 0.0889)
		(layer "In2.Cu")
		(net "CLK_GEN_PG")
	)
	(segment
		(start 54.28488 -51.09845)
		(end 52.3875 -49.20107)
		(width 0.0889)
		(layer "In2.Cu")
		(net "CLK_GEN_PG")
	)
	(segment
		(start 52.345844 -47.099728)
		(end 51.85156 -46.605444)
		(width 0.0889)
		(layer "In2.Cu")
		(net "CLK_GEN_PG")
	)
	(segment
		(start 47.77105 -43.58005)
		(end 45.89145 -41.70045)
		(width 0.0889)
		(layer "In2.Cu")
		(net "CLK_GEN_PG")
	)
	(segment
		(start 51.85156 -46.605444)
		(end 49.907444 -46.605444)
		(width 0.0889)
		(layer "In2.Cu")
		(net "CLK_GEN_PG")
	)
	(segment
		(start 52.3875 -48.11776)
		(end 52.345844 -48.076104)
		(width 0.0889)
		(layer "In2.Cu")
		(net "CLK_GEN_PG")
	)
	(segment
		(start 66.9417 -60.9219)
		(end 64.3382 -58.3184)
		(width 0.0889)
		(layer "In2.Cu")
		(net "CLK_GEN_PG")
	)
	(segment
		(start 52.3875 -49.20107)
		(end 52.3875 -48.11776)
		(width 0.0889)
		(layer "In2.Cu")
		(net "CLK_GEN_PG")
	)
	(segment
		(start 42.588688 -41.70045)
		(end 42.565574 -41.677336)
		(width 0.0889)
		(layer "In2.Cu")
		(net "CLK_GEN_PG")
	)
	(segment
		(start 45.89145 -41.70045)
		(end 42.588688 -41.70045)
		(width 0.0889)
		(layer "In2.Cu")
		(net "CLK_GEN_PG")
	)
	(segment
		(start 41.80205 -39.10965)
		(end 41.189656 -39.10965)
		(width 0.0889)
		(layer "In4.Cu")
		(net "CLK_GEN_PG")
	)
	(segment
		(start 39.586662 -38.862)
		(end 38.72992 -38.005258)
		(width 0.0889)
		(layer "In4.Cu")
		(net "CLK_GEN_PG")
	)
	(segment
		(start 32.645096 -36.425378)
		(end 32.645096 -34.10331)
		(width 0.0889)
		(layer "In4.Cu")
		(net "CLK_GEN_PG")
	)
	(segment
		(start 41.189656 -39.10965)
		(end 40.942006 -38.862)
		(width 0.0889)
		(layer "In4.Cu")
		(net "CLK_GEN_PG")
	)
	(segment
		(start 32.645096 -34.10331)
		(end 33.004506 -33.7439)
		(width 0.0889)
		(layer "In4.Cu")
		(net "CLK_GEN_PG")
	)
	(segment
		(start 36.1442 -38.227)
		(end 35.56 -37.6428)
		(width 0.0889)
		(layer "In4.Cu")
		(net "CLK_GEN_PG")
	)
	(segment
		(start 40.7035 -33.7439)
		(end 47.3964 -27.051)
		(width 0.0889)
		(layer "In4.Cu")
		(net "CLK_GEN_PG")
	)
	(segment
		(start 38.72992 -38.005258)
		(end 37.3634 -38.005258)
		(width 0.0889)
		(layer "In4.Cu")
		(net "CLK_GEN_PG")
	)
	(segment
		(start 43.18 -40.4876)
		(end 41.80205 -39.10965)
		(width 0.0889)
		(layer "In4.Cu")
		(net "CLK_GEN_PG")
	)
	(segment
		(start 37.141658 -38.227)
		(end 36.1442 -38.227)
		(width 0.0889)
		(layer "In4.Cu")
		(net "CLK_GEN_PG")
	)
	(segment
		(start 40.942006 -38.862)
		(end 39.586662 -38.862)
		(width 0.0889)
		(layer "In4.Cu")
		(net "CLK_GEN_PG")
	)
	(segment
		(start 47.3964 -27.051)
		(end 47.625 -27.051)
		(width 0.0889)
		(layer "In4.Cu")
		(net "CLK_GEN_PG")
	)
	(segment
		(start 37.3634 -38.005258)
		(end 37.141658 -38.227)
		(width 0.0889)
		(layer "In4.Cu")
		(net "CLK_GEN_PG")
	)
	(segment
		(start 33.004506 -33.7439)
		(end 40.7035 -33.7439)
		(width 0.0889)
		(layer "In4.Cu")
		(net "CLK_GEN_PG")
	)
	(segment
		(start 33.862518 -37.6428)
		(end 32.645096 -36.425378)
		(width 0.0889)
		(layer "In4.Cu")
		(net "CLK_GEN_PG")
	)
	(segment
		(start 35.56 -37.6428)
		(end 33.862518 -37.6428)
		(width 0.0889)
		(layer "In4.Cu")
		(net "CLK_GEN_PG")
	)
	(segment
		(start 43.18 -41.06291)
		(end 43.18 -40.4876)
		(width 0.0889)
		(layer "In4.Cu")
		(net "CLK_GEN_PG")
	)
	(segment
		(start 42.565574 -41.677336)
		(end 43.18 -41.06291)
		(width 0.0889)
		(layer "In4.Cu")
		(net "CLK_GEN_PG")
	)
	(segment
		(start 38.735 -13.617956)
		(end 38.735 -14.760194)
		(width 0.0889)
		(layer "In9.Cu")
		(net "CLK_GEN_PG")
	)
	(segment
		(start 80.83423 -8.71855)
		(end 64.204088 -8.71855)
		(width 0.0889)
		(layer "In9.Cu")
		(net "CLK_GEN_PG")
	)
	(segment
		(start 38.520116 -13.399516)
		(end 38.727634 -13.607034)
		(width 0.0889)
		(layer "In9.Cu")
		(net "CLK_GEN_PG")
	)
	(segment
		(start 84.77631 -11.60145)
		(end 81.586324 -11.60145)
		(width 0.0889)
		(layer "In9.Cu")
		(net "CLK_GEN_PG")
	)
	(segment
		(start 106.593894 -11.70305)
		(end 105.053638 -13.243306)
		(width 0.0889)
		(layer "In9.Cu")
		(net "CLK_GEN_PG")
	)
	(segment
		(start 105.053638 -13.243306)
		(end 96.428306 -13.243306)
		(width 0.0889)
		(layer "In9.Cu")
		(net "CLK_GEN_PG")
	)
	(segment
		(start 38.727634 -13.607034)
		(end 38.735 -13.617956)
		(width 0.0889)
		(layer "In9.Cu")
		(net "CLK_GEN_PG")
	)
	(segment
		(start 90.708988 -12.058904)
		(end 88.665812 -12.058904)
		(width 0.0889)
		(layer "In9.Cu")
		(net "CLK_GEN_PG")
	)
	(segment
		(start 47.0408 -23.065994)
		(end 47.0408 -26.4668)
		(width 0.0889)
		(layer "In9.Cu")
		(net "CLK_GEN_PG")
	)
	(segment
		(start 106.593894 -2.090674)
		(end 106.593894 -11.70305)
		(width 0.0889)
		(layer "In9.Cu")
		(net "CLK_GEN_PG")
	)
	(segment
		(start 85.83676 -12.6619)
		(end 84.77631 -11.60145)
		(width 0.0889)
		(layer "In9.Cu")
		(net "CLK_GEN_PG")
	)
	(segment
		(start 38.48481 -13.37564)
		(end 38.520116 -13.399516)
		(width 0.0889)
		(layer "In9.Cu")
		(net "CLK_GEN_PG")
	)
	(segment
		(start 38.00094 -13.37564)
		(end 38.48481 -13.37564)
		(width 0.0889)
		(layer "In9.Cu")
		(net "CLK_GEN_PG")
	)
	(segment
		(start 106.925618 -1.75895)
		(end 106.593894 -2.090674)
		(width 0.0889)
		(layer "In9.Cu")
		(net "CLK_GEN_PG")
	)
	(segment
		(start 91.546934 -12.89685)
		(end 90.708988 -12.058904)
		(width 0.0889)
		(layer "In9.Cu")
		(net "CLK_GEN_PG")
	)
	(segment
		(start 88.062816 -12.6619)
		(end 85.83676 -12.6619)
		(width 0.0889)
		(layer "In9.Cu")
		(net "CLK_GEN_PG")
	)
	(segment
		(start 88.665812 -12.058904)
		(end 88.062816 -12.6619)
		(width 0.0889)
		(layer "In9.Cu")
		(net "CLK_GEN_PG")
	)
	(segment
		(start 38.829488 -9.017)
		(end 37.81552 -10.030968)
		(width 0.0889)
		(layer "In9.Cu")
		(net "CLK_GEN_PG")
	)
	(segment
		(start 38.735 -14.760194)
		(end 47.0408 -23.065994)
		(width 0.0889)
		(layer "In9.Cu")
		(net "CLK_GEN_PG")
	)
	(segment
		(start 63.905638 -9.017)
		(end 38.829488 -9.017)
		(width 0.0889)
		(layer "In9.Cu")
		(net "CLK_GEN_PG")
	)
	(segment
		(start 96.428306 -13.243306)
		(end 96.08185 -12.89685)
		(width 0.0889)
		(layer "In9.Cu")
		(net "CLK_GEN_PG")
	)
	(segment
		(start 37.81552 -10.030968)
		(end 37.81552 -13.19022)
		(width 0.0889)
		(layer "In9.Cu")
		(net "CLK_GEN_PG")
	)
	(segment
		(start 47.0408 -26.4668)
		(end 47.625 -27.051)
		(width 0.0889)
		(layer "In9.Cu")
		(net "CLK_GEN_PG")
	)
	(segment
		(start 96.08185 -12.89685)
		(end 91.546934 -12.89685)
		(width 0.0889)
		(layer "In9.Cu")
		(net "CLK_GEN_PG")
	)
	(segment
		(start 37.81552 -13.19022)
		(end 38.00094 -13.37564)
		(width 0.0889)
		(layer "In9.Cu")
		(net "CLK_GEN_PG")
	)
	(segment
		(start 81.425542 -10.911332)
		(end 81.425542 -9.309862)
		(width 0.0889)
		(layer "In9.Cu")
		(net "CLK_GEN_PG")
	)
	(segment
		(start 110.4646 -1.75895)
		(end 106.925618 -1.75895)
		(width 0.0889)
		(layer "In9.Cu")
		(net "CLK_GEN_PG")
	)
	(segment
		(start 81.33715 -11.352276)
		(end 81.33715 -10.999724)
		(width 0.0889)
		(layer "In9.Cu")
		(net "CLK_GEN_PG")
	)
	(segment
		(start 81.425542 -9.309862)
		(end 80.83423 -8.71855)
		(width 0.0889)
		(layer "In9.Cu")
		(net "CLK_GEN_PG")
	)
	(segment
		(start 81.33715 -10.999724)
		(end 81.425542 -10.911332)
		(width 0.0889)
		(layer "In9.Cu")
		(net "CLK_GEN_PG")
	)
	(segment
		(start 81.586324 -11.60145)
		(end 81.33715 -11.352276)
		(width 0.0889)
		(layer "In9.Cu")
		(net "CLK_GEN_PG")
	)
	(segment
		(start 64.204088 -8.71855)
		(end 63.905638 -9.017)
		(width 0.0889)
		(layer "In9.Cu")
		(net "CLK_GEN_PG")
	)
	(segment
		(start 36.068 -39.5478)
		(end 35.7632 -39.8526)
		(width 0.1143)
		(layer "F.Cu")
		(net "CORE_PWROK")
	)
	(segment
		(start 111.9124 -69.6722)
		(end 111.23676 -68.99656)
		(width 0.1143)
		(layer "F.Cu")
		(net "CORE_PWROK")
	)
	(segment
		(start 111.23676 -68.99656)
		(end 111.23676 -68.5165)
		(width 0.1143)
		(layer "F.Cu")
		(net "CORE_PWROK")
	)
	(segment
		(start 35.7632 -39.8526)
		(end 35.7632 -40.3606)
		(width 0.1143)
		(layer "F.Cu")
		(net "CORE_PWROK")
	)
	(via
		(at 50.342292 -52.418996)
		(size 0.508)
		(drill 0.254)
		(layers "F.Cu" "B.Cu")
		(net "CORE_PWROK")
	)
	(via
		(at 35.7632 -40.3606)
		(size 0.508)
		(drill 0.254)
		(layers "F.Cu" "B.Cu")
		(net "CORE_PWROK")
	)
	(via
		(at 37.342572 -41.083738)
		(size 0.7112)
		(drill 0.3556)
		(layers "F.Cu" "B.Cu")
		(net "CORE_PWROK")
	)
	(via
		(at 111.9124 -69.6722)
		(size 0.508)
		(drill 0.254)
		(layers "F.Cu" "B.Cu")
		(net "CORE_PWROK")
	)
	(via
		(at 75.438 -40.6908)
		(size 0.508)
		(drill 0.254)
		(layers "F.Cu" "B.Cu")
		(net "CORE_PWROK")
	)
	(segment
		(start 75.5142 -40.6146)
		(end 75.438 -40.6908)
		(width 0.1143)
		(layer "B.Cu")
		(net "CORE_PWROK")
	)
	(segment
		(start 35.7632 -40.3606)
		(end 36.486338 -41.083738)
		(width 0.1143)
		(layer "B.Cu")
		(net "CORE_PWROK")
	)
	(segment
		(start 38.238938 -41.083738)
		(end 37.342572 -41.083738)
		(width 0.1143)
		(layer "B.Cu")
		(net "CORE_PWROK")
	)
	(segment
		(start 36.486338 -41.083738)
		(end 37.342572 -41.083738)
		(width 0.1143)
		(layer "B.Cu")
		(net "CORE_PWROK")
	)
	(segment
		(start 38.3032 -41.148)
		(end 38.238938 -41.083738)
		(width 0.1143)
		(layer "B.Cu")
		(net "CORE_PWROK")
	)
	(segment
		(start 75.5142 -40.005)
		(end 75.5142 -40.6146)
		(width 0.1143)
		(layer "B.Cu")
		(net "CORE_PWROK")
	)
	(segment
		(start 74.5998 -40.005)
		(end 75.5142 -40.005)
		(width 0.1143)
		(layer "B.Cu")
		(net "CORE_PWROK")
	)
	(segment
		(start 40.98925 -48.241204)
		(end 44.087796 -51.33975)
		(width 0.0889)
		(layer "In2.Cu")
		(net "CORE_PWROK")
	)
	(segment
		(start 57.785 -57.371488)
		(end 55.188612 -54.7751)
		(width 0.0889)
		(layer "In2.Cu")
		(net "CORE_PWROK")
	)
	(segment
		(start 40.98925 -45.442886)
		(end 40.98925 -48.241204)
		(width 0.0889)
		(layer "In2.Cu")
		(net "CORE_PWROK")
	)
	(segment
		(start 45.99178 -51.33975)
		(end 46.29023 -51.6382)
		(width 0.0889)
		(layer "In2.Cu")
		(net "CORE_PWROK")
	)
	(segment
		(start 49.76495 -51.6382)
		(end 50.342292 -52.215542)
		(width 0.0889)
		(layer "In2.Cu")
		(net "CORE_PWROK")
	)
	(segment
		(start 35.7632 -40.3606)
		(end 36.83635 -41.43375)
		(width 0.0889)
		(layer "In2.Cu")
		(net "CORE_PWROK")
	)
	(segment
		(start 100.74275 -71.00951)
		(end 100.74275 -68.100956)
		(width 0.0889)
		(layer "In2.Cu")
		(net "CORE_PWROK")
	)
	(segment
		(start 54.078378 -54.7751)
		(end 53.430932 -54.127654)
		(width 0.0889)
		(layer "In2.Cu")
		(net "CORE_PWROK")
	)
	(segment
		(start 50.342292 -52.215542)
		(end 50.342292 -52.418996)
		(width 0.0889)
		(layer "In2.Cu")
		(net "CORE_PWROK")
	)
	(segment
		(start 44.087796 -51.33975)
		(end 45.99178 -51.33975)
		(width 0.0889)
		(layer "In2.Cu")
		(net "CORE_PWROK")
	)
	(segment
		(start 111.9124 -70.6628)
		(end 110.5662 -72.009)
		(width 0.0889)
		(layer "In2.Cu")
		(net "CORE_PWROK")
	)
	(segment
		(start 70.044056 -63.78575)
		(end 68.507356 -65.32245)
		(width 0.0889)
		(layer "In2.Cu")
		(net "CORE_PWROK")
	)
	(segment
		(start 38.56355 -43.017186)
		(end 40.98925 -45.442886)
		(width 0.0889)
		(layer "In2.Cu")
		(net "CORE_PWROK")
	)
	(segment
		(start 38.116256 -41.43375)
		(end 38.56355 -41.881044)
		(width 0.0889)
		(layer "In2.Cu")
		(net "CORE_PWROK")
	)
	(segment
		(start 101.74224 -72.009)
		(end 100.74275 -71.00951)
		(width 0.0889)
		(layer "In2.Cu")
		(net "CORE_PWROK")
	)
	(segment
		(start 66.408808 -65.32245)
		(end 65.132458 -64.0461)
		(width 0.0889)
		(layer "In2.Cu")
		(net "CORE_PWROK")
	)
	(segment
		(start 55.188612 -54.7751)
		(end 54.078378 -54.7751)
		(width 0.0889)
		(layer "In2.Cu")
		(net "CORE_PWROK")
	)
	(segment
		(start 111.9124 -69.6722)
		(end 111.9124 -70.6628)
		(width 0.0889)
		(layer "In2.Cu")
		(net "CORE_PWROK")
	)
	(segment
		(start 87.64905 -63.78575)
		(end 70.044056 -63.78575)
		(width 0.0889)
		(layer "In2.Cu")
		(net "CORE_PWROK")
	)
	(segment
		(start 98.662744 -66.02095)
		(end 89.88425 -66.02095)
		(width 0.0889)
		(layer "In2.Cu")
		(net "CORE_PWROK")
	)
	(segment
		(start 110.5662 -72.009)
		(end 101.74224 -72.009)
		(width 0.0889)
		(layer "In2.Cu")
		(net "CORE_PWROK")
	)
	(segment
		(start 38.56355 -41.881044)
		(end 38.56355 -43.017186)
		(width 0.0889)
		(layer "In2.Cu")
		(net "CORE_PWROK")
	)
	(segment
		(start 52.05095 -54.127654)
		(end 50.342292 -52.418996)
		(width 0.0889)
		(layer "In2.Cu")
		(net "CORE_PWROK")
	)
	(segment
		(start 89.88425 -66.02095)
		(end 87.64905 -63.78575)
		(width 0.0889)
		(layer "In2.Cu")
		(net "CORE_PWROK")
	)
	(segment
		(start 65.132458 -64.0461)
		(end 59.778646 -64.0461)
		(width 0.0889)
		(layer "In2.Cu")
		(net "CORE_PWROK")
	)
	(segment
		(start 68.507356 -65.32245)
		(end 66.408808 -65.32245)
		(width 0.0889)
		(layer "In2.Cu")
		(net "CORE_PWROK")
	)
	(segment
		(start 53.430932 -54.127654)
		(end 52.05095 -54.127654)
		(width 0.0889)
		(layer "In2.Cu")
		(net "CORE_PWROK")
	)
	(segment
		(start 46.29023 -51.6382)
		(end 49.76495 -51.6382)
		(width 0.0889)
		(layer "In2.Cu")
		(net "CORE_PWROK")
	)
	(segment
		(start 59.778646 -64.0461)
		(end 57.785 -62.052454)
		(width 0.0889)
		(layer "In2.Cu")
		(net "CORE_PWROK")
	)
	(segment
		(start 100.74275 -68.100956)
		(end 98.662744 -66.02095)
		(width 0.0889)
		(layer "In2.Cu")
		(net "CORE_PWROK")
	)
	(segment
		(start 36.83635 -41.43375)
		(end 38.116256 -41.43375)
		(width 0.0889)
		(layer "In2.Cu")
		(net "CORE_PWROK")
	)
	(segment
		(start 57.785 -62.052454)
		(end 57.785 -57.371488)
		(width 0.0889)
		(layer "In2.Cu")
		(net "CORE_PWROK")
	)
	(segment
		(start 50.60061 -52.418996)
		(end 50.342292 -52.418996)
		(width 0.0889)
		(layer "In4.Cu")
		(net "CORE_PWROK")
	)
	(segment
		(start 66.869818 -43.2689)
		(end 62.094618 -48.0441)
		(width 0.0889)
		(layer "In4.Cu")
		(net "CORE_PWROK")
	)
	(segment
		(start 57.463182 -48.0441)
		(end 55.310532 -50.19675)
		(width 0.0889)
		(layer "In4.Cu")
		(net "CORE_PWROK")
	)
	(segment
		(start 69.68363 -43.2689)
		(end 66.869818 -43.2689)
		(width 0.0889)
		(layer "In4.Cu")
		(net "CORE_PWROK")
	)
	(segment
		(start 55.310532 -50.19675)
		(end 54.448456 -50.19675)
		(width 0.0889)
		(layer "In4.Cu")
		(net "CORE_PWROK")
	)
	(segment
		(start 70.331838 -42.620692)
		(end 69.68363 -43.2689)
		(width 0.0889)
		(layer "In4.Cu")
		(net "CORE_PWROK")
	)
	(segment
		(start 52.645056 -52.00015)
		(end 51.019456 -52.00015)
		(width 0.0889)
		(layer "In4.Cu")
		(net "CORE_PWROK")
	)
	(segment
		(start 54.448456 -50.19675)
		(end 52.645056 -52.00015)
		(width 0.0889)
		(layer "In4.Cu")
		(net "CORE_PWROK")
	)
	(segment
		(start 62.094618 -48.0441)
		(end 57.463182 -48.0441)
		(width 0.0889)
		(layer "In4.Cu")
		(net "CORE_PWROK")
	)
	(segment
		(start 51.019456 -52.00015)
		(end 50.60061 -52.418996)
		(width 0.0889)
		(layer "In4.Cu")
		(net "CORE_PWROK")
	)
	(segment
		(start 74.4982 -40.6908)
		(end 72.568308 -42.620692)
		(width 0.0889)
		(layer "In4.Cu")
		(net "CORE_PWROK")
	)
	(segment
		(start 75.438 -40.6908)
		(end 74.4982 -40.6908)
		(width 0.0889)
		(layer "In4.Cu")
		(net "CORE_PWROK")
	)
	(segment
		(start 72.568308 -42.620692)
		(end 70.331838 -42.620692)
		(width 0.0889)
		(layer "In4.Cu")
		(net "CORE_PWROK")
	)
	(segment
		(start 82.505042 -39.431214)
		(end 82.82813 -39.108126)
		(width 0.1143)
		(layer "F.Cu")
		(net "CORE_PWROK_R")
	)
	(segment
		(start 82.82813 -39.108126)
		(end 82.863436 -39.108126)
		(width 0.1143)
		(layer "F.Cu")
		(net "CORE_PWROK_R")
	)
	(segment
		(start 82.504788 -39.431214)
		(end 82.505042 -39.431214)
		(width 0.1143)
		(layer "F.Cu")
		(net "CORE_PWROK_R")
	)
	(via
		(at 77.086968 -41.24325)
		(size 0.7112)
		(drill 0.3556)
		(layers "F.Cu" "B.Cu")
		(net "CORE_PWROK_R")
	)
	(via
		(at 82.863436 -39.108126)
		(size 0.4318)
		(drill 0.2032)
		(layers "F.Cu" "B.Cu")
		(net "CORE_PWROK_R")
	)
	(segment
		(start 80.784446 -40.613584)
		(end 79.595218 -40.613584)
		(width 0.1143)
		(layer "B.Cu")
		(net "CORE_PWROK_R")
	)
	(segment
		(start 77.879702 -40.93845)
		(end 77.574902 -41.24325)
		(width 0.1143)
		(layer "B.Cu")
		(net "CORE_PWROK_R")
	)
	(segment
		(start 82.499962 -39.4716)
		(end 81.92643 -39.4716)
		(width 0.1143)
		(layer "B.Cu")
		(net "CORE_PWROK_R")
	)
	(segment
		(start 81.92643 -39.4716)
		(end 80.784446 -40.613584)
		(width 0.1143)
		(layer "B.Cu")
		(net "CORE_PWROK_R")
	)
	(segment
		(start 77.574902 -41.24325)
		(end 77.086968 -41.24325)
		(width 0.1143)
		(layer "B.Cu")
		(net "CORE_PWROK_R")
	)
	(segment
		(start 79.595218 -40.613584)
		(end 79.270352 -40.93845)
		(width 0.1143)
		(layer "B.Cu")
		(net "CORE_PWROK_R")
	)
	(segment
		(start 82.863436 -39.108126)
		(end 82.499962 -39.4716)
		(width 0.1143)
		(layer "B.Cu")
		(net "CORE_PWROK_R")
	)
	(segment
		(start 79.270352 -40.93845)
		(end 77.879702 -40.93845)
		(width 0.1143)
		(layer "B.Cu")
		(net "CORE_PWROK_R")
	)
	(segment
		(start 76.3778 -40.005)
		(end 76.3778 -40.534082)
		(width 0.1143)
		(layer "B.Cu")
		(net "CORE_PWROK_R")
	)
	(segment
		(start 76.3778 -40.534082)
		(end 77.086968 -41.24325)
		(width 0.1143)
		(layer "B.Cu")
		(net "CORE_PWROK_R")
	)
	(segment
		(start 58.4454 -25.5524)
		(end 58.801 -25.908)
		(width 0.254)
		(layer "F.Cu")
		(net "PWRGD_P1V8_PG")
	)
	(segment
		(start 58.8518 -21.844)
		(end 58.4454 -22.2504)
		(width 0.254)
		(layer "F.Cu")
		(net "PWRGD_P1V8_PG")
	)
	(segment
		(start 57.658 -45.339)
		(end 57.2262 -45.7708)
		(width 0.254)
		(layer "F.Cu")
		(net "PWRGD_P1V8_PG")
	)
	(segment
		(start 56.515 -45.0088)
		(end 57.3278 -45.0088)
		(width 0.254)
		(layer "F.Cu")
		(net "PWRGD_P1V8_PG")
	)
	(segment
		(start 58.4454 -22.2504)
		(end 58.4454 -25.5524)
		(width 0.254)
		(layer "F.Cu")
		(net "PWRGD_P1V8_PG")
	)
	(segment
		(start 57.3278 -45.0088)
		(end 57.658 -45.339)
		(width 0.254)
		(layer "F.Cu")
		(net "PWRGD_P1V8_PG")
	)
	(segment
		(start 59.17565 -26.07945)
		(end 59.17565 -27.460194)
		(width 0.254)
		(layer "F.Cu")
		(net "PWRGD_P1V8_PG")
	)
	(segment
		(start 57.2262 -45.7708)
		(end 56.9468 -45.7708)
		(width 0.254)
		(layer "F.Cu")
		(net "PWRGD_P1V8_PG")
	)
	(segment
		(start 59.0042 -25.908)
		(end 59.17565 -26.07945)
		(width 0.254)
		(layer "F.Cu")
		(net "PWRGD_P1V8_PG")
	)
	(segment
		(start 59.17565 -27.460194)
		(end 59.296808 -27.581352)
		(width 0.254)
		(layer "F.Cu")
		(net "PWRGD_P1V8_PG")
	)
	(segment
		(start 58.801 -25.908)
		(end 59.0042 -25.908)
		(width 0.254)
		(layer "F.Cu")
		(net "PWRGD_P1V8_PG")
	)
	(segment
		(start 61.267086 -21.844)
		(end 58.8518 -21.844)
		(width 0.254)
		(layer "F.Cu")
		(net "PWRGD_P1V8_PG")
	)
	(via
		(at 59.296808 -27.581352)
		(size 0.508)
		(drill 0.254)
		(layers "F.Cu" "B.Cu")
		(net "PWRGD_P1V8_PG")
	)
	(via
		(at 56.9468 -45.7708)
		(size 0.508)
		(drill 0.254)
		(layers "F.Cu" "B.Cu")
		(net "PWRGD_P1V8_PG")
	)
	(via
		(at 57.658 -45.339)
		(size 0.7112)
		(drill 0.3556)
		(layers "F.Cu" "B.Cu")
		(net "PWRGD_P1V8_PG")
	)
	(segment
		(start 60.169044 -42.29354)
		(end 60.169044 -31.111444)
		(width 0.254)
		(layer "B.Cu")
		(net "PWRGD_P1V8_PG")
	)
	(segment
		(start 56.9468 -45.2882)
		(end 59.15533 -43.07967)
		(width 0.254)
		(layer "B.Cu")
		(net "PWRGD_P1V8_PG")
	)
	(segment
		(start 59.334908 -43.07967)
		(end 59.416696 -43.045888)
		(width 0.254)
		(layer "B.Cu")
		(net "PWRGD_P1V8_PG")
	)
	(segment
		(start 59.416696 -43.045888)
		(end 60.169044 -42.29354)
		(width 0.254)
		(layer "B.Cu")
		(net "PWRGD_P1V8_PG")
	)
	(segment
		(start 56.9468 -45.7708)
		(end 56.9468 -45.2882)
		(width 0.254)
		(layer "B.Cu")
		(net "PWRGD_P1V8_PG")
	)
	(segment
		(start 60.169044 -31.111444)
		(end 59.296808 -30.239208)
		(width 0.254)
		(layer "B.Cu")
		(net "PWRGD_P1V8_PG")
	)
	(segment
		(start 59.15533 -43.07967)
		(end 59.334908 -43.07967)
		(width 0.254)
		(layer "B.Cu")
		(net "PWRGD_P1V8_PG")
	)
	(segment
		(start 59.296808 -30.239208)
		(end 59.296808 -27.581352)
		(width 0.254)
		(layer "B.Cu")
		(net "PWRGD_P1V8_PG")
	)
	(segment
		(start 61.5696 -32.6644)
		(end 61.976 -32.258)
		(width 0.254)
		(layer "F.Cu")
		(net "P1V8_B")
	)
	(segment
		(start 62.865 -32.258)
		(end 63.8302 -32.258)
		(width 0.254)
		(layer "F.Cu")
		(net "P1V8_B")
	)
	(segment
		(start 61.976 -32.258)
		(end 62.865 -32.258)
		(width 0.254)
		(layer "F.Cu")
		(net "P1V8_B")
	)
	(segment
		(start 61.214 -32.6644)
		(end 61.5696 -32.6644)
		(width 0.254)
		(layer "F.Cu")
		(net "P1V8_B")
	)
	(via
		(at 62.865 -32.258)
		(size 0.7112)
		(drill 0.3556)
		(layers "F.Cu" "B.Cu")
		(net "P1V8_B")
	)
	(segment
		(start 57.3278 -25.33015)
		(end 57.8739 -24.78405)
		(width 0.254)
		(layer "F.Cu")
		(net "P1V8_G")
	)
	(segment
		(start 61.8744 -31.3436)
		(end 62.103 -31.115)
		(width 0.254)
		(layer "F.Cu")
		(net "P1V8_G")
	)
	(segment
		(start 59.0804 -22.842474)
		(end 59.128914 -22.79396)
		(width 0.254)
		(layer "F.Cu")
		(net "P1V8_G")
	)
	(segment
		(start 60.706 -31.3436)
		(end 57.3278 -27.9654)
		(width 0.254)
		(layer "F.Cu")
		(net "P1V8_G")
	)
	(segment
		(start 57.3278 -27.9654)
		(end 57.3278 -25.33015)
		(width 0.254)
		(layer "F.Cu")
		(net "P1V8_G")
	)
	(segment
		(start 59.0804 -25.0698)
		(end 59.0804 -24.2062)
		(width 0.254)
		(layer "F.Cu")
		(net "P1V8_G")
	)
	(segment
		(start 60.706 -31.3436)
		(end 61.8744 -31.3436)
		(width 0.254)
		(layer "F.Cu")
		(net "P1V8_G")
	)
	(segment
		(start 59.0804 -24.2062)
		(end 59.0804 -22.842474)
		(width 0.254)
		(layer "F.Cu")
		(net "P1V8_G")
	)
	(segment
		(start 59.0042 -25.146)
		(end 59.0804 -25.0698)
		(width 0.254)
		(layer "F.Cu")
		(net "P1V8_G")
	)
	(via
		(at 57.8739 -24.78405)
		(size 0.508)
		(drill 0.254)
		(layers "F.Cu" "B.Cu")
		(net "P1V8_G")
	)
	(via
		(at 59.0804 -24.2062)
		(size 0.508)
		(drill 0.254)
		(layers "F.Cu" "B.Cu")
		(net "P1V8_G")
	)
	(via
		(at 62.103 -31.115)
		(size 0.7112)
		(drill 0.3556)
		(layers "F.Cu" "B.Cu")
		(net "P1V8_G")
	)
	(segment
		(start 58.45175 -24.2062)
		(end 57.8739 -24.78405)
		(width 0.254)
		(layer "B.Cu")
		(net "P1V8_G")
	)
	(segment
		(start 59.0804 -24.2062)
		(end 58.45175 -24.2062)
		(width 0.254)
		(layer "B.Cu")
		(net "P1V8_G")
	)
	(segment
		(start 185.674 -23.9014)
		(end 185.4708 -24.1046)
		(width 0.254)
		(layer "F.Cu")
		(net "PVTT_DDR_EN")
	)
	(segment
		(start 142.24762 -56.0578)
		(end 142.27302 -56.0324)
		(width 0.254)
		(layer "F.Cu")
		(net "PVTT_DDR_EN")
	)
	(segment
		(start 143.3068 -56.4642)
		(end 143.3068 -56.896)
		(width 0.254)
		(layer "F.Cu")
		(net "PVTT_DDR_EN")
	)
	(segment
		(start 141.7066 -56.0578)
		(end 142.24762 -56.0578)
		(width 0.254)
		(layer "F.Cu")
		(net "PVTT_DDR_EN")
	)
	(segment
		(start 185.674 -23.3172)
		(end 185.674 -23.9014)
		(width 0.254)
		(layer "F.Cu")
		(net "PVTT_DDR_EN")
	)
	(segment
		(start 142.875 -56.0324)
		(end 143.3068 -56.4642)
		(width 0.254)
		(layer "F.Cu")
		(net "PVTT_DDR_EN")
	)
	(segment
		(start 142.27302 -56.0324)
		(end 142.875 -56.0324)
		(width 0.254)
		(layer "F.Cu")
		(net "PVTT_DDR_EN")
	)
	(via
		(at 143.3068 -56.896)
		(size 0.508)
		(drill 0.254)
		(layers "F.Cu" "B.Cu")
		(net "PVTT_DDR_EN")
	)
	(via
		(at 181.365652 -44.491148)
		(size 0.7112)
		(drill 0.3556)
		(layers "F.Cu" "B.Cu")
		(net "PVTT_DDR_EN")
	)
	(via
		(at 80.50403 -71.527924)
		(size 0.508)
		(drill 0.254)
		(layers "F.Cu" "B.Cu")
		(net "PVTT_DDR_EN")
	)
	(via
		(at 185.4708 -24.1046)
		(size 0.508)
		(drill 0.254)
		(layers "F.Cu" "B.Cu")
		(net "PVTT_DDR_EN")
	)
	(segment
		(start 66.734182 -43.527218)
		(end 65.8368 -44.4246)
		(width 0.254)
		(layer "B.Cu")
		(net "PVTT_DDR_EN")
	)
	(segment
		(start 69.27977 -69.490082)
		(end 69.27977 -69.490336)
		(width 0.254)
		(layer "B.Cu")
		(net "PVTT_DDR_EN")
	)
	(segment
		(start 67.2592 -39.1414)
		(end 68.2498 -39.1414)
		(width 0.254)
		(layer "B.Cu")
		(net "PVTT_DDR_EN")
	)
	(segment
		(start 68.2498 -39.1414)
		(end 68.43776 -38.95344)
		(width 0.254)
		(layer "B.Cu")
		(net "PVTT_DDR_EN")
	)
	(segment
		(start 143.3068 -56.896)
		(end 144.018 -56.1848)
		(width 0.254)
		(layer "B.Cu")
		(net "PVTT_DDR_EN")
	)
	(segment
		(start 68.43776 -38.95344)
		(end 68.43776 -38.78072)
		(width 0.254)
		(layer "B.Cu")
		(net "PVTT_DDR_EN")
	)
	(segment
		(start 74.549 -69.78015)
		(end 74.672952 -69.656198)
		(width 0.254)
		(layer "B.Cu")
		(net "PVTT_DDR_EN")
	)
	(segment
		(start 66.903854 -53.542946)
		(end 65.9892 -54.4576)
		(width 0.254)
		(layer "B.Cu")
		(net "PVTT_DDR_EN")
	)
	(segment
		(start 181.365652 -44.491148)
		(end 183.780938 -42.075862)
		(width 0.254)
		(layer "B.Cu")
		(net "PVTT_DDR_EN")
	)
	(segment
		(start 181.241954 -46.592744)
		(end 181.241954 -44.614846)
		(width 0.254)
		(layer "B.Cu")
		(net "PVTT_DDR_EN")
	)
	(segment
		(start 144.018 -56.1848)
		(end 154.65933 -56.1848)
		(width 0.254)
		(layer "B.Cu")
		(net "PVTT_DDR_EN")
	)
	(segment
		(start 180.8226 -28.702508)
		(end 184.404508 -25.1206)
		(width 0.254)
		(layer "B.Cu")
		(net "PVTT_DDR_EN")
	)
	(segment
		(start 69.27977 -69.490336)
		(end 69.569584 -69.78015)
		(width 0.254)
		(layer "B.Cu")
		(net "PVTT_DDR_EN")
	)
	(segment
		(start 65.988946 -65.789302)
		(end 65.988946 -66.199258)
		(width 0.254)
		(layer "B.Cu")
		(net "PVTT_DDR_EN")
	)
	(segment
		(start 65.9892 -65.789048)
		(end 65.988946 -65.789302)
		(width 0.254)
		(layer "B.Cu")
		(net "PVTT_DDR_EN")
	)
	(segment
		(start 69.569584 -69.78015)
		(end 74.549 -69.78015)
		(width 0.254)
		(layer "B.Cu")
		(net "PVTT_DDR_EN")
	)
	(segment
		(start 65.8368 -48.8188)
		(end 66.903854 -49.885854)
		(width 0.254)
		(layer "B.Cu")
		(net "PVTT_DDR_EN")
	)
	(segment
		(start 66.734182 -39.666418)
		(end 66.734182 -43.527218)
		(width 0.254)
		(layer "B.Cu")
		(net "PVTT_DDR_EN")
	)
	(segment
		(start 183.780938 -34.15411)
		(end 182.037228 -32.4104)
		(width 0.254)
		(layer "B.Cu")
		(net "PVTT_DDR_EN")
	)
	(segment
		(start 65.988946 -66.199258)
		(end 69.27977 -69.490082)
		(width 0.254)
		(layer "B.Cu")
		(net "PVTT_DDR_EN")
	)
	(segment
		(start 184.404508 -25.1206)
		(end 184.49798 -25.1206)
		(width 0.254)
		(layer "B.Cu")
		(net "PVTT_DDR_EN")
	)
	(segment
		(start 154.65933 -56.1848)
		(end 155.95473 -54.8894)
		(width 0.254)
		(layer "B.Cu")
		(net "PVTT_DDR_EN")
	)
	(segment
		(start 66.903854 -49.885854)
		(end 66.903854 -53.542946)
		(width 0.254)
		(layer "B.Cu")
		(net "PVTT_DDR_EN")
	)
	(segment
		(start 180.8226 -31.41218)
		(end 180.8226 -28.702508)
		(width 0.254)
		(layer "B.Cu")
		(net "PVTT_DDR_EN")
	)
	(segment
		(start 67.0814 -39.3192)
		(end 66.734182 -39.666418)
		(width 0.254)
		(layer "B.Cu")
		(net "PVTT_DDR_EN")
	)
	(segment
		(start 155.95473 -54.8894)
		(end 172.945298 -54.8894)
		(width 0.254)
		(layer "B.Cu")
		(net "PVTT_DDR_EN")
	)
	(segment
		(start 65.8368 -44.4246)
		(end 65.8368 -48.8188)
		(width 0.254)
		(layer "B.Cu")
		(net "PVTT_DDR_EN")
	)
	(segment
		(start 80.50403 -71.20763)
		(end 80.50403 -71.527924)
		(width 0.254)
		(layer "B.Cu")
		(net "PVTT_DDR_EN")
	)
	(segment
		(start 185.4708 -24.14778)
		(end 185.4708 -24.1046)
		(width 0.254)
		(layer "B.Cu")
		(net "PVTT_DDR_EN")
	)
	(segment
		(start 182.037228 -32.4104)
		(end 181.82082 -32.4104)
		(width 0.254)
		(layer "B.Cu")
		(net "PVTT_DDR_EN")
	)
	(segment
		(start 65.9892 -54.4576)
		(end 65.9892 -65.789048)
		(width 0.254)
		(layer "B.Cu")
		(net "PVTT_DDR_EN")
	)
	(segment
		(start 184.49798 -25.1206)
		(end 185.4708 -24.14778)
		(width 0.254)
		(layer "B.Cu")
		(net "PVTT_DDR_EN")
	)
	(segment
		(start 67.0814 -39.3192)
		(end 67.2592 -39.1414)
		(width 0.254)
		(layer "B.Cu")
		(net "PVTT_DDR_EN")
	)
	(segment
		(start 77.047598 -69.656198)
		(end 77.4192 -70.0278)
		(width 0.254)
		(layer "B.Cu")
		(net "PVTT_DDR_EN")
	)
	(segment
		(start 172.945298 -54.8894)
		(end 181.241954 -46.592744)
		(width 0.254)
		(layer "B.Cu")
		(net "PVTT_DDR_EN")
	)
	(segment
		(start 79.3242 -70.0278)
		(end 80.50403 -71.20763)
		(width 0.254)
		(layer "B.Cu")
		(net "PVTT_DDR_EN")
	)
	(segment
		(start 74.672952 -69.656198)
		(end 77.047598 -69.656198)
		(width 0.254)
		(layer "B.Cu")
		(net "PVTT_DDR_EN")
	)
	(segment
		(start 77.4192 -70.0278)
		(end 79.3242 -70.0278)
		(width 0.254)
		(layer "B.Cu")
		(net "PVTT_DDR_EN")
	)
	(segment
		(start 181.241954 -44.614846)
		(end 181.365652 -44.491148)
		(width 0.254)
		(layer "B.Cu")
		(net "PVTT_DDR_EN")
	)
	(segment
		(start 181.82082 -32.4104)
		(end 180.8226 -31.41218)
		(width 0.254)
		(layer "B.Cu")
		(net "PVTT_DDR_EN")
	)
	(segment
		(start 183.780938 -42.075862)
		(end 183.780938 -34.15411)
		(width 0.254)
		(layer "B.Cu")
		(net "PVTT_DDR_EN")
	)
	(segment
		(start 184.375552 -23.6982)
		(end 185.0644 -23.6982)
		(width 0.254)
		(layer "In7.Cu")
		(net "PVTT_DDR_EN")
	)
	(segment
		(start 190.7032 -59.2582)
		(end 190.7032 -46.76902)
		(width 0.254)
		(layer "In7.Cu")
		(net "PVTT_DDR_EN")
	)
	(segment
		(start 80.50403 -71.527924)
		(end 81.32826 -72.352154)
		(width 0.254)
		(layer "In7.Cu")
		(net "PVTT_DDR_EN")
	)
	(segment
		(start 182.30596 -42.4434)
		(end 179.1208 -39.25824)
		(width 0.254)
		(layer "In7.Cu")
		(net "PVTT_DDR_EN")
	)
	(segment
		(start 81.32826 -72.352154)
		(end 190.120016 -72.352154)
		(width 0.254)
		(layer "In7.Cu")
		(net "PVTT_DDR_EN")
	)
	(segment
		(start 179.1208 -28.900882)
		(end 184.121552 -23.90013)
		(width 0.254)
		(layer "In7.Cu")
		(net "PVTT_DDR_EN")
	)
	(segment
		(start 179.1208 -39.25824)
		(end 179.1208 -28.900882)
		(width 0.254)
		(layer "In7.Cu")
		(net "PVTT_DDR_EN")
	)
	(segment
		(start 185.0644 -23.6982)
		(end 185.4708 -24.1046)
		(width 0.254)
		(layer "In7.Cu")
		(net "PVTT_DDR_EN")
	)
	(segment
		(start 190.7032 -46.76902)
		(end 186.37758 -42.4434)
		(width 0.254)
		(layer "In7.Cu")
		(net "PVTT_DDR_EN")
	)
	(segment
		(start 190.120016 -72.352154)
		(end 194.071748 -68.400422)
		(width 0.254)
		(layer "In7.Cu")
		(net "PVTT_DDR_EN")
	)
	(segment
		(start 194.071748 -62.626748)
		(end 190.7032 -59.2582)
		(width 0.254)
		(layer "In7.Cu")
		(net "PVTT_DDR_EN")
	)
	(segment
		(start 186.37758 -42.4434)
		(end 182.30596 -42.4434)
		(width 0.254)
		(layer "In7.Cu")
		(net "PVTT_DDR_EN")
	)
	(segment
		(start 194.071748 -68.400422)
		(end 194.071748 -62.626748)
		(width 0.254)
		(layer "In7.Cu")
		(net "PVTT_DDR_EN")
	)
	(segment
		(start 184.121552 -23.90013)
		(end 184.375552 -23.6982)
		(width 0.254)
		(layer "In7.Cu")
		(net "PVTT_DDR_EN")
	)
	(via
		(at 71.66102 -37.4904)
		(size 0.7112)
		(drill 0.3556)
		(layers "F.Cu" "B.Cu")
		(net "PMU_SLP_INB_S3#")
	)
	(segment
		(start 71.22922 -37.9222)
		(end 70.7644 -37.9222)
		(width 0.1143)
		(layer "B.Cu")
		(net "PMU_SLP_INB_S3#")
	)
	(segment
		(start 70.7644 -37.9222)
		(end 70.104 -37.9222)
		(width 0.1143)
		(layer "B.Cu")
		(net "PMU_SLP_INB_S3#")
	)
	(segment
		(start 70.104 -37.9222)
		(end 69.73824 -37.55644)
		(width 0.1143)
		(layer "B.Cu")
		(net "PMU_SLP_INB_S3#")
	)
	(segment
		(start 71.66102 -37.4904)
		(end 71.22922 -37.9222)
		(width 0.1143)
		(layer "B.Cu")
		(net "PMU_SLP_INB_S3#")
	)
	(segment
		(start 69.73824 -37.55644)
		(end 69.73824 -36.91128)
		(width 0.1143)
		(layer "B.Cu")
		(net "PMU_SLP_INB_S3#")
	)
	(segment
		(start 69.088 -37.1602)
		(end 69.088 -36.91128)
		(width 0.1143)
		(layer "B.Cu")
		(net "PMU_SLP_INA_DDRVTT#")
	)
	(segment
		(start 67.5386 -37.1602)
		(end 67.96405 -37.58565)
		(width 0.1143)
		(layer "B.Cu")
		(net "PMU_SLP_INA_DDRVTT#")
	)
	(segment
		(start 67.4624 -37.1602)
		(end 67.5386 -37.1602)
		(width 0.1143)
		(layer "B.Cu")
		(net "PMU_SLP_INA_DDRVTT#")
	)
	(segment
		(start 67.96405 -37.58565)
		(end 68.66255 -37.58565)
		(width 0.1143)
		(layer "B.Cu")
		(net "PMU_SLP_INA_DDRVTT#")
	)
	(segment
		(start 68.66255 -37.58565)
		(end 69.088 -37.1602)
		(width 0.1143)
		(layer "B.Cu")
		(net "PMU_SLP_INA_DDRVTT#")
	)
	(segment
		(start 111.887 -68.5165)
		(end 111.887 -67.8434)
		(width 0.1143)
		(layer "F.Cu")
		(net "CLK_GEN_OUT_R")
	)
	(segment
		(start 116.07673 -67.691)
		(end 116.078 -67.69227)
		(width 0.1143)
		(layer "F.Cu")
		(net "CLK_GEN_OUT_R")
	)
	(segment
		(start 111.887 -66.8655)
		(end 111.887 -67.5386)
		(width 0.1143)
		(layer "F.Cu")
		(net "CLK_GEN_OUT_R")
	)
	(segment
		(start 111.366046 -70.167754)
		(end 112.16259 -70.167754)
		(width 0.1143)
		(layer "F.Cu")
		(net "CLK_GEN_OUT_R")
	)
	(segment
		(start 112.16259 -70.167754)
		(end 112.526572 -69.803772)
		(width 0.1143)
		(layer "F.Cu")
		(net "CLK_GEN_OUT_R")
	)
	(segment
		(start 112.526572 -69.803772)
		(end 112.526572 -69.540628)
		(width 0.1143)
		(layer "F.Cu")
		(net "CLK_GEN_OUT_R")
	)
	(segment
		(start 117.094 -67.8942)
		(end 116.8908 -67.691)
		(width 0.1143)
		(layer "F.Cu")
		(net "CLK_GEN_OUT_R")
	)
	(segment
		(start 116.8908 -67.691)
		(end 116.086636 -67.691)
		(width 0.1143)
		(layer "F.Cu")
		(net "CLK_GEN_OUT_R")
	)
	(segment
		(start 112.526572 -69.540628)
		(end 111.887 -68.901056)
		(width 0.1143)
		(layer "F.Cu")
		(net "CLK_GEN_OUT_R")
	)
	(segment
		(start 110.9218 -70.612)
		(end 111.366046 -70.167754)
		(width 0.1143)
		(layer "F.Cu")
		(net "CLK_GEN_OUT_R")
	)
	(segment
		(start 110.1598 -70.612)
		(end 110.9218 -70.612)
		(width 0.1143)
		(layer "F.Cu")
		(net "CLK_GEN_OUT_R")
	)
	(segment
		(start 111.887 -68.901056)
		(end 111.887 -68.5165)
		(width 0.1143)
		(layer "F.Cu")
		(net "CLK_GEN_OUT_R")
	)
	(segment
		(start 116.078 -67.69227)
		(end 116.085366 -67.69227)
		(width 0.1143)
		(layer "F.Cu")
		(net "CLK_GEN_OUT_R")
	)
	(segment
		(start 112.0394 -67.691)
		(end 116.07673 -67.691)
		(width 0.1143)
		(layer "F.Cu")
		(net "CLK_GEN_OUT_R")
	)
	(segment
		(start 111.887 -67.8434)
		(end 112.0394 -67.691)
		(width 0.1143)
		(layer "F.Cu")
		(net "CLK_GEN_OUT_R")
	)
	(segment
		(start 111.887 -67.5386)
		(end 112.0394 -67.691)
		(width 0.1143)
		(layer "F.Cu")
		(net "CLK_GEN_OUT_R")
	)
	(segment
		(start 116.086636 -67.691)
		(end 116.085366 -67.69227)
		(width 0.1143)
		(layer "F.Cu")
		(net "CLK_GEN_OUT_R")
	)
	(via
		(at 116.085366 -67.69227)
		(size 0.7112)
		(drill 0.3556)
		(layers "F.Cu" "B.Cu")
		(net "CLK_GEN_OUT_R")
	)
	(segment
		(start 116.9162 -68.9356)
		(end 117.094 -68.7578)
		(width 0.1143)
		(layer "F.Cu")
		(net "CLK_GEN_OUT")
	)
	(segment
		(start 116.1542 -68.9356)
		(end 116.0526 -68.9356)
		(width 0.1143)
		(layer "F.Cu")
		(net "CLK_GEN_OUT")
	)
	(segment
		(start 116.1542 -68.9356)
		(end 116.9162 -68.9356)
		(width 0.1143)
		(layer "F.Cu")
		(net "CLK_GEN_OUT")
	)
	(segment
		(start 115.74272 -68.62572)
		(end 115.07724 -68.62572)
		(width 0.1143)
		(layer "F.Cu")
		(net "CLK_GEN_OUT")
	)
	(segment
		(start 116.0526 -68.9356)
		(end 115.74272 -68.62572)
		(width 0.1143)
		(layer "F.Cu")
		(net "CLK_GEN_OUT")
	)
	(via
		(at 116.1542 -68.9356)
		(size 0.7112)
		(drill 0.3556)
		(layers "F.Cu" "B.Cu")
		(net "CLK_GEN_OUT")
	)
	(segment
		(start 71.681086 -50.091086)
		(end 72.771 -51.181)
		(width 0.127)
		(layer "F.Cu")
		(net "BEEP_LED_D")
	)
	(segment
		(start 88.384126 -72.974454)
		(end 192.811146 -72.974454)
		(width 0.127)
		(layer "F.Cu")
		(net "BEEP_LED_D")
	)
	(segment
		(start 73.18375 -51.59375)
		(end 77.5462 -51.59375)
		(width 0.127)
		(layer "F.Cu")
		(net "BEEP_LED_D")
	)
	(segment
		(start 71.681086 -50.038)
		(end 71.681086 -50.091086)
		(width 0.127)
		(layer "F.Cu")
		(net "BEEP_LED_D")
	)
	(segment
		(start 81.9658 -70.5358)
		(end 82.2706 -70.231)
		(width 0.127)
		(layer "F.Cu")
		(net "BEEP_LED_D")
	)
	(segment
		(start 72.771 -51.181)
		(end 73.18375 -51.59375)
		(width 0.127)
		(layer "F.Cu")
		(net "BEEP_LED_D")
	)
	(segment
		(start 85.640672 -70.231)
		(end 88.384126 -72.974454)
		(width 0.127)
		(layer "F.Cu")
		(net "BEEP_LED_D")
	)
	(segment
		(start 82.2706 -70.231)
		(end 85.640672 -70.231)
		(width 0.127)
		(layer "F.Cu")
		(net "BEEP_LED_D")
	)
	(segment
		(start 192.811146 -72.974454)
		(end 194.4116 -71.374)
		(width 0.127)
		(layer "F.Cu")
		(net "BEEP_LED_D")
	)
	(via
		(at 72.771 -51.181)
		(size 0.7112)
		(drill 0.3556)
		(layers "F.Cu" "B.Cu")
		(net "BEEP_LED_D")
	)
	(via
		(at 194.4116 -71.374)
		(size 0.508)
		(drill 0.254)
		(layers "F.Cu" "B.Cu")
		(net "BEEP_LED_D")
	)
	(via
		(at 81.9658 -70.5358)
		(size 0.508)
		(drill 0.254)
		(layers "F.Cu" "B.Cu")
		(net "BEEP_LED_D")
	)
	(via
		(at 77.5462 -51.59375)
		(size 0.508)
		(drill 0.254)
		(layers "F.Cu" "B.Cu")
		(net "BEEP_LED_D")
	)
	(segment
		(start 71.8693 -56.7563)
		(end 72.52335 -56.10225)
		(width 0.127)
		(layer "B.Cu")
		(net "BEEP_LED_D")
	)
	(segment
		(start 77.5462 -53.29809)
		(end 77.5462 -51.59375)
		(width 0.127)
		(layer "B.Cu")
		(net "BEEP_LED_D")
	)
	(segment
		(start 81.9658 -70.5358)
		(end 78.5241 -67.0941)
		(width 0.127)
		(layer "B.Cu")
		(net "BEEP_LED_D")
	)
	(segment
		(start 78.5241 -67.0941)
		(end 77.9399 -67.0941)
		(width 0.127)
		(layer "B.Cu")
		(net "BEEP_LED_D")
	)
	(segment
		(start 77.232256 -67.801744)
		(end 75.01636 -67.801744)
		(width 0.127)
		(layer "B.Cu")
		(net "BEEP_LED_D")
	)
	(segment
		(start 74.74204 -56.10225)
		(end 77.5462 -53.29809)
		(width 0.127)
		(layer "B.Cu")
		(net "BEEP_LED_D")
	)
	(segment
		(start 196.723 -69.85)
		(end 195.9356 -69.85)
		(width 0.127)
		(layer "B.Cu")
		(net "BEEP_LED_D")
	)
	(segment
		(start 71.8693 -60.036964)
		(end 71.8693 -56.7563)
		(width 0.127)
		(layer "B.Cu")
		(net "BEEP_LED_D")
	)
	(segment
		(start 75.01636 -67.801744)
		(end 73.4695 -66.254884)
		(width 0.127)
		(layer "B.Cu")
		(net "BEEP_LED_D")
	)
	(segment
		(start 77.9399 -67.0941)
		(end 77.232256 -67.801744)
		(width 0.127)
		(layer "B.Cu")
		(net "BEEP_LED_D")
	)
	(segment
		(start 73.4695 -66.254884)
		(end 73.4695 -61.637164)
		(width 0.127)
		(layer "B.Cu")
		(net "BEEP_LED_D")
	)
	(segment
		(start 197.773036 -68.799964)
		(end 196.723 -69.85)
		(width 0.127)
		(layer "B.Cu")
		(net "BEEP_LED_D")
	)
	(segment
		(start 195.9356 -69.85)
		(end 194.4116 -71.374)
		(width 0.127)
		(layer "B.Cu")
		(net "BEEP_LED_D")
	)
	(segment
		(start 198.647558 -68.799964)
		(end 197.773036 -68.799964)
		(width 0.127)
		(layer "B.Cu")
		(net "BEEP_LED_D")
	)
	(segment
		(start 72.52335 -56.10225)
		(end 74.74204 -56.10225)
		(width 0.127)
		(layer "B.Cu")
		(net "BEEP_LED_D")
	)
	(segment
		(start 73.4695 -61.637164)
		(end 71.8693 -60.036964)
		(width 0.127)
		(layer "B.Cu")
		(net "BEEP_LED_D")
	)
	(via
		(at 201.006964 -68.799964)
		(size 0.7112)
		(drill 0.3556)
		(layers "F.Cu" "B.Cu")
		(net "BEEP_LED")
	)
	(segment
		(start 199.95261 -68.799964)
		(end 199.95261 -67.869054)
		(width 0.127)
		(layer "B.Cu")
		(net "BEEP_LED")
	)
	(segment
		(start 197.884796 -67.023996)
		(end 197.6628 -66.802)
		(width 0.127)
		(layer "B.Cu")
		(net "BEEP_LED")
	)
	(segment
		(start 199.95261 -68.799964)
		(end 201.006964 -68.799964)
		(width 0.127)
		(layer "B.Cu")
		(net "BEEP_LED")
	)
	(segment
		(start 199.95261 -67.869054)
		(end 199.107552 -67.023996)
		(width 0.127)
		(layer "B.Cu")
		(net "BEEP_LED")
	)
	(segment
		(start 199.107552 -67.023996)
		(end 197.884796 -67.023996)
		(width 0.127)
		(layer "B.Cu")
		(net "BEEP_LED")
	)
	(segment
		(start 157.6578 -31.8262)
		(end 157.7594 -31.7246)
		(width 0.1143)
		(layer "F.Cu")
		(net "FPGA_READY#")
	)
	(segment
		(start 158.242 -29.3878)
		(end 158.242 -30.734)
		(width 0.1143)
		(layer "F.Cu")
		(net "FPGA_READY#")
	)
	(segment
		(start 84.7344 -16.2052)
		(end 84.7344 -17.02435)
		(width 0.1143)
		(layer "F.Cu")
		(net "FPGA_READY#")
	)
	(segment
		(start 85.424264 -17.714214)
		(end 86.68385 -17.714214)
		(width 0.1143)
		(layer "F.Cu")
		(net "FPGA_READY#")
	)
	(segment
		(start 89.939114 -15.85595)
		(end 97.167954 -15.85595)
		(width 0.1143)
		(layer "F.Cu")
		(net "FPGA_READY#")
	)
	(segment
		(start 104.686608 -12.586208)
		(end 106.5784 -10.694416)
		(width 0.1143)
		(layer "F.Cu")
		(net "FPGA_READY#")
	)
	(segment
		(start 85.552788 -34.757614)
		(end 85.632036 -34.757614)
		(width 0.1143)
		(layer "F.Cu")
		(net "FPGA_READY#")
	)
	(segment
		(start 87.018114 -17.37995)
		(end 88.415114 -17.37995)
		(width 0.1143)
		(layer "F.Cu")
		(net "FPGA_READY#")
	)
	(segment
		(start 86.68385 -17.714214)
		(end 87.018114 -17.37995)
		(width 0.1143)
		(layer "F.Cu")
		(net "FPGA_READY#")
	)
	(segment
		(start 84.7344 -17.02435)
		(end 85.424264 -17.714214)
		(width 0.1143)
		(layer "F.Cu")
		(net "FPGA_READY#")
	)
	(segment
		(start 106.5784 -6.896354)
		(end 107.833922 -5.640832)
		(width 0.1143)
		(layer "F.Cu")
		(net "FPGA_READY#")
	)
	(segment
		(start 97.167954 -15.85595)
		(end 100.437696 -12.586208)
		(width 0.1143)
		(layer "F.Cu")
		(net "FPGA_READY#")
	)
	(segment
		(start 106.5784 -10.694416)
		(end 106.5784 -6.896354)
		(width 0.1143)
		(layer "F.Cu")
		(net "FPGA_READY#")
	)
	(segment
		(start 88.415114 -17.37995)
		(end 89.939114 -15.85595)
		(width 0.1143)
		(layer "F.Cu")
		(net "FPGA_READY#")
	)
	(segment
		(start 158.242 -31.242)
		(end 157.7594 -31.7246)
		(width 0.1143)
		(layer "F.Cu")
		(net "FPGA_READY#")
	)
	(segment
		(start 157.6578 -32.639)
		(end 157.6578 -31.8262)
		(width 0.1143)
		(layer "F.Cu")
		(net "FPGA_READY#")
	)
	(segment
		(start 100.437696 -12.586208)
		(end 104.686608 -12.586208)
		(width 0.1143)
		(layer "F.Cu")
		(net "FPGA_READY#")
	)
	(segment
		(start 85.632036 -34.757614)
		(end 85.97138 -35.096958)
		(width 0.1143)
		(layer "F.Cu")
		(net "FPGA_READY#")
	)
	(segment
		(start 158.242 -30.734)
		(end 158.242 -31.242)
		(width 0.1143)
		(layer "F.Cu")
		(net "FPGA_READY#")
	)
	(via
		(at 157.7594 -31.7246)
		(size 0.508)
		(drill 0.254)
		(layers "F.Cu" "B.Cu")
		(net "FPGA_READY#")
	)
	(via
		(at 84.7344 -16.2052)
		(size 0.508)
		(drill 0.254)
		(layers "F.Cu" "B.Cu")
		(net "FPGA_READY#")
	)
	(via
		(at 158.242 -30.734)
		(size 0.7112)
		(drill 0.3556)
		(layers "F.Cu" "B.Cu")
		(net "FPGA_READY#")
	)
	(via
		(at 107.833922 -5.640832)
		(size 0.508)
		(drill 0.254)
		(layers "F.Cu" "B.Cu")
		(net "FPGA_READY#")
	)
	(via
		(at 85.97138 -35.096958)
		(size 0.4318)
		(drill 0.2032)
		(layers "F.Cu" "B.Cu")
		(net "FPGA_READY#")
	)
	(segment
		(start 110.22965 -7.365746)
		(end 109.68355 -6.819646)
		(width 0.1143)
		(layer "B.Cu")
		(net "FPGA_READY#")
	)
	(segment
		(start 115.7732 -16.025368)
		(end 110.22965 -10.481818)
		(width 0.1143)
		(layer "B.Cu")
		(net "FPGA_READY#")
	)
	(segment
		(start 157.7594 -31.7246)
		(end 155.77693 -29.74213)
		(width 0.1143)
		(layer "B.Cu")
		(net "FPGA_READY#")
	)
	(segment
		(start 138.514074 -29.74213)
		(end 137.993374 -29.22143)
		(width 0.1143)
		(layer "B.Cu")
		(net "FPGA_READY#")
	)
	(segment
		(start 115.7732 -23.130764)
		(end 115.7732 -16.025368)
		(width 0.1143)
		(layer "B.Cu")
		(net "FPGA_READY#")
	)
	(segment
		(start 137.993374 -29.22143)
		(end 121.863866 -29.22143)
		(width 0.1143)
		(layer "B.Cu")
		(net "FPGA_READY#")
	)
	(segment
		(start 109.68355 -6.819646)
		(end 109.68355 -6.756908)
		(width 0.1143)
		(layer "B.Cu")
		(net "FPGA_READY#")
	)
	(segment
		(start 110.22965 -10.481818)
		(end 110.22965 -7.365746)
		(width 0.1143)
		(layer "B.Cu")
		(net "FPGA_READY#")
	)
	(segment
		(start 155.77693 -29.74213)
		(end 138.514074 -29.74213)
		(width 0.1143)
		(layer "B.Cu")
		(net "FPGA_READY#")
	)
	(segment
		(start 121.863866 -29.22143)
		(end 115.7732 -23.130764)
		(width 0.1143)
		(layer "B.Cu")
		(net "FPGA_READY#")
	)
	(segment
		(start 108.567474 -5.640832)
		(end 107.833922 -5.640832)
		(width 0.1143)
		(layer "B.Cu")
		(net "FPGA_READY#")
	)
	(segment
		(start 109.68355 -6.756908)
		(end 108.567474 -5.640832)
		(width 0.1143)
		(layer "B.Cu")
		(net "FPGA_READY#")
	)
	(segment
		(start 85.87105 -26.4922)
		(end 84.68995 -25.3111)
		(width 0.0889)
		(layer "In2.Cu")
		(net "FPGA_READY#")
	)
	(segment
		(start 85.87105 -28.7655)
		(end 85.87105 -26.4922)
		(width 0.0889)
		(layer "In2.Cu")
		(net "FPGA_READY#")
	)
	(segment
		(start 84.68995 -22.12975)
		(end 84.35975 -21.79955)
		(width 0.0889)
		(layer "In2.Cu")
		(net "FPGA_READY#")
	)
	(segment
		(start 85.97138 -35.096958)
		(end 86.297516 -34.770822)
		(width 0.0889)
		(layer "In2.Cu")
		(net "FPGA_READY#")
	)
	(segment
		(start 86.297516 -34.770822)
		(end 86.297516 -32.781748)
		(width 0.0889)
		(layer "In2.Cu")
		(net "FPGA_READY#")
	)
	(segment
		(start 86.59495 -32.484314)
		(end 86.59495 -29.4894)
		(width 0.0889)
		(layer "In2.Cu")
		(net "FPGA_READY#")
	)
	(segment
		(start 84.35975 -21.79955)
		(end 84.35975 -16.57985)
		(width 0.0889)
		(layer "In2.Cu")
		(net "FPGA_READY#")
	)
	(segment
		(start 84.35975 -16.57985)
		(end 84.7344 -16.2052)
		(width 0.0889)
		(layer "In2.Cu")
		(net "FPGA_READY#")
	)
	(segment
		(start 86.59495 -29.4894)
		(end 85.87105 -28.7655)
		(width 0.0889)
		(layer "In2.Cu")
		(net "FPGA_READY#")
	)
	(segment
		(start 86.297516 -32.781748)
		(end 86.59495 -32.484314)
		(width 0.0889)
		(layer "In2.Cu")
		(net "FPGA_READY#")
	)
	(segment
		(start 84.68995 -25.3111)
		(end 84.68995 -22.12975)
		(width 0.0889)
		(layer "In2.Cu")
		(net "FPGA_READY#")
	)
	(segment
		(start 159.2072 -32.893)
		(end 158.9532 -32.639)
		(width 0.127)
		(layer "F.Cu")
		(net "HEARTBEAT_R_LED")
	)
	(segment
		(start 158.259526 -32.850074)
		(end 158.4706 -32.639)
		(width 0.127)
		(layer "F.Cu")
		(net "HEARTBEAT_R_LED")
	)
	(segment
		(start 159.2072 -33.782)
		(end 159.2072 -32.893)
		(width 0.127)
		(layer "F.Cu")
		(net "HEARTBEAT_R_LED")
	)
	(segment
		(start 158.4706 -32.639)
		(end 158.9532 -32.639)
		(width 0.127)
		(layer "F.Cu")
		(net "HEARTBEAT_R_LED")
	)
	(segment
		(start 158.259526 -33.782)
		(end 158.259526 -32.850074)
		(width 0.127)
		(layer "F.Cu")
		(net "HEARTBEAT_R_LED")
	)
	(via
		(at 158.9532 -32.639)
		(size 0.7112)
		(drill 0.3556)
		(layers "F.Cu" "B.Cu")
		(net "HEARTBEAT_R_LED")
	)
	(segment
		(start 81.9912 -63.8556)
		(end 82.677 -64.5414)
		(width 0.254)
		(layer "F.Cu")
		(net "PV_VDDR_SENSE")
	)
	(segment
		(start 71.3613 -59.16803)
		(end 70.72757 -59.16803)
		(width 0.254)
		(layer "F.Cu")
		(net "PV_VDDR_SENSE")
	)
	(segment
		(start 81.9912 -63.754)
		(end 81.9912 -63.8556)
		(width 0.254)
		(layer "F.Cu")
		(net "PV_VDDR_SENSE")
	)
	(segment
		(start 82.677 -64.5414)
		(end 82.804 -64.5414)
		(width 0.254)
		(layer "F.Cu")
		(net "PV_VDDR_SENSE")
	)
	(segment
		(start 80.0862 -62.0522)
		(end 79.883 -62.0522)
		(width 0.254)
		(layer "F.Cu")
		(net "PV_VDDR_SENSE")
	)
	(segment
		(start 69.9516 -59.944)
		(end 69.9516 -60.4266)
		(width 0.254)
		(layer "F.Cu")
		(net "PV_VDDR_SENSE")
	)
	(segment
		(start 70.72757 -59.16803)
		(end 69.9516 -59.944)
		(width 0.254)
		(layer "F.Cu")
		(net "PV_VDDR_SENSE")
	)
	(segment
		(start 81.3562 -62.4332)
		(end 80.4672 -62.4332)
		(width 0.254)
		(layer "F.Cu")
		(net "PV_VDDR_SENSE")
	)
	(segment
		(start 81.3562 -62.4332)
		(end 81.9912 -63.0682)
		(width 0.254)
		(layer "F.Cu")
		(net "PV_VDDR_SENSE")
	)
	(segment
		(start 81.9912 -63.0682)
		(end 81.9912 -63.754)
		(width 0.254)
		(layer "F.Cu")
		(net "PV_VDDR_SENSE")
	)
	(segment
		(start 80.4672 -62.4332)
		(end 80.0862 -62.0522)
		(width 0.254)
		(layer "F.Cu")
		(net "PV_VDDR_SENSE")
	)
	(via
		(at 81.3562 -62.4332)
		(size 0.7112)
		(drill 0.3556)
		(layers "F.Cu" "B.Cu")
		(net "PV_VDDR_SENSE")
	)
	(via
		(at 82.804 -64.5414)
		(size 0.508)
		(drill 0.254)
		(layers "F.Cu" "B.Cu")
		(net "PV_VDDR_SENSE")
	)
	(via
		(at 69.9516 -60.4266)
		(size 0.508)
		(drill 0.254)
		(layers "F.Cu" "B.Cu")
		(net "PV_VDDR_SENSE")
	)
	(via
		(at 72.9996 -64.5414)
		(size 0.508)
		(drill 0.254)
		(layers "F.Cu" "B.Cu")
		(net "PV_VDDR_SENSE")
	)
	(segment
		(start 72.9996 -64.5414)
		(end 69.9516 -61.4934)
		(width 0.254)
		(layer "In7.Cu")
		(net "PV_VDDR_SENSE")
	)
	(segment
		(start 69.9516 -61.4934)
		(end 69.9516 -60.4266)
		(width 0.254)
		(layer "In7.Cu")
		(net "PV_VDDR_SENSE")
	)
	(segment
		(start 73.74255 -63.79845)
		(end 82.06105 -63.79845)
		(width 0.254)
		(layer "In9.Cu")
		(net "PV_VDDR_SENSE")
	)
	(segment
		(start 72.9996 -64.5414)
		(end 73.74255 -63.79845)
		(width 0.254)
		(layer "In9.Cu")
		(net "PV_VDDR_SENSE")
	)
	(segment
		(start 82.06105 -63.79845)
		(end 82.804 -64.5414)
		(width 0.254)
		(layer "In9.Cu")
		(net "PV_VDDR_SENSE")
	)
	(segment
		(start 69.8881 -63.7413)
		(end 69.8881 -64.5033)
		(width 0.127)
		(layer "F.Cu")
		(net "P3V3_STBY_SENSE")
	)
	(segment
		(start 70.5612 -63.0682)
		(end 69.8881 -63.7413)
		(width 0.127)
		(layer "F.Cu")
		(net "P3V3_STBY_SENSE")
	)
	(segment
		(start 71.3613 -63.0682)
		(end 70.5612 -63.0682)
		(width 0.127)
		(layer "F.Cu")
		(net "P3V3_STBY_SENSE")
	)
	(segment
		(start 69.8881 -64.5033)
		(end 69.9262 -64.5414)
		(width 0.127)
		(layer "F.Cu")
		(net "P3V3_STBY_SENSE")
	)
	(via
		(at 70.5612 -63.3476)
		(size 0.7112)
		(drill 0.3556)
		(layers "F.Cu" "B.Cu")
		(net "P3V3_STBY_SENSE")
	)
	(via
		(at 69.9262 -64.5414)
		(size 0.508)
		(drill 0.254)
		(layers "F.Cu" "B.Cu")
		(net "P3V3_STBY_SENSE")
	)
	(segment
		(start 70.7898 -62.0776)
		(end 70.0786 -62.0776)
		(width 0.127)
		(layer "B.Cu")
		(net "P3V3_STBY_SENSE")
	)
	(segment
		(start 70.7898 -63.119)
		(end 70.5612 -63.3476)
		(width 0.127)
		(layer "B.Cu")
		(net "P3V3_STBY_SENSE")
	)
	(segment
		(start 70.0786 -62.0776)
		(end 69.977 -62.1792)
		(width 0.127)
		(layer "B.Cu")
		(net "P3V3_STBY_SENSE")
	)
	(segment
		(start 70.5612 -63.3476)
		(end 69.9262 -63.9826)
		(width 0.127)
		(layer "B.Cu")
		(net "P3V3_STBY_SENSE")
	)
	(segment
		(start 70.7898 -62.0776)
		(end 70.7898 -63.119)
		(width 0.127)
		(layer "B.Cu")
		(net "P3V3_STBY_SENSE")
	)
	(segment
		(start 69.9262 -63.9826)
		(end 69.9262 -64.5414)
		(width 0.127)
		(layer "B.Cu")
		(net "P3V3_STBY_SENSE")
	)
	(segment
		(start 70.7898 -61.2648)
		(end 70.7898 -62.0776)
		(width 0.127)
		(layer "B.Cu")
		(net "P3V3_STBY_SENSE")
	)
	(segment
		(start 80.01508 -37.950394)
		(end 80.66278 -37.302694)
		(width 0.127)
		(layer "F.Cu")
		(net "USB_OC#")
	)
	(segment
		(start 79.24419 -37.758624)
		(end 79.43596 -37.950394)
		(width 0.127)
		(layer "F.Cu")
		(net "USB_OC#")
	)
	(segment
		(start 79.43596 -37.950394)
		(end 80.01508 -37.950394)
		(width 0.127)
		(layer "F.Cu")
		(net "USB_OC#")
	)
	(segment
		(start 75.1078 -37.465)
		(end 75.4888 -37.084)
		(width 0.127)
		(layer "F.Cu")
		(net "USB_OC#")
	)
	(segment
		(start 80.66278 -37.302694)
		(end 80.950308 -37.302694)
		(width 0.127)
		(layer "F.Cu")
		(net "USB_OC#")
	)
	(segment
		(start 75.4888 -37.084)
		(end 76.163424 -37.758624)
		(width 0.127)
		(layer "F.Cu")
		(net "USB_OC#")
	)
	(segment
		(start 76.163424 -37.758624)
		(end 79.24419 -37.758624)
		(width 0.127)
		(layer "F.Cu")
		(net "USB_OC#")
	)
	(segment
		(start 74.0918 -37.465)
		(end 75.1078 -37.465)
		(width 0.127)
		(layer "F.Cu")
		(net "USB_OC#")
	)
	(segment
		(start 161.6202 -41.275)
		(end 161.7472 -41.402)
		(width 0.127)
		(layer "F.Cu")
		(net "C_LED_NSTATUS#")
	)
	(segment
		(start 160.782 -41.275)
		(end 160.782 -42.181526)
		(width 0.127)
		(layer "F.Cu")
		(net "C_LED_NSTATUS#")
	)
	(segment
		(start 160.782 -41.275)
		(end 161.6202 -41.275)
		(width 0.127)
		(layer "F.Cu")
		(net "C_LED_NSTATUS#")
	)
	(segment
		(start 160.782 -42.181526)
		(end 161.145474 -42.545)
		(width 0.127)
		(layer "F.Cu")
		(net "C_LED_NSTATUS#")
	)
	(via
		(at 160.782 -41.275)
		(size 0.7112)
		(drill 0.3556)
		(layers "F.Cu" "B.Cu")
		(net "C_LED_NSTATUS#")
	)
	(segment
		(start 182.6768 -46.7614)
		(end 182.6768 -47.2948)
		(width 0.1143)
		(layer "F.Cu")
		(net "SMB_DPOT_CLK")
	)
	(segment
		(start 182.9054 -46.5328)
		(end 182.6768 -46.7614)
		(width 0.1143)
		(layer "F.Cu")
		(net "SMB_DPOT_CLK")
	)
	(segment
		(start 182.99176 -47.60976)
		(end 183.20004 -47.60976)
		(width 0.1143)
		(layer "F.Cu")
		(net "SMB_DPOT_CLK")
	)
	(segment
		(start 182.6768 -47.2948)
		(end 182.99176 -47.60976)
		(width 0.1143)
		(layer "F.Cu")
		(net "SMB_DPOT_CLK")
	)
	(segment
		(start 183.642 -46.5328)
		(end 182.9054 -46.5328)
		(width 0.1143)
		(layer "F.Cu")
		(net "SMB_DPOT_CLK")
	)
	(via
		(at 182.6768 -46.7614)
		(size 0.7112)
		(drill 0.3556)
		(layers "F.Cu" "B.Cu")
		(net "SMB_DPOT_CLK")
	)
	(segment
		(start 184.404 -47.0408)
		(end 184.404 -46.5328)
		(width 0.1143)
		(layer "F.Cu")
		(net "SMB_DPOT_DATA")
	)
	(segment
		(start 185.3692 -45.5676)
		(end 185.5216 -45.5676)
		(width 0.1143)
		(layer "F.Cu")
		(net "SMB_DPOT_DATA")
	)
	(segment
		(start 184.97296 -47.60976)
		(end 184.404 -47.0408)
		(width 0.1143)
		(layer "F.Cu")
		(net "SMB_DPOT_DATA")
	)
	(segment
		(start 184.404 -46.5328)
		(end 185.3692 -45.5676)
		(width 0.1143)
		(layer "F.Cu")
		(net "SMB_DPOT_DATA")
	)
	(segment
		(start 185.09996 -47.60976)
		(end 184.97296 -47.60976)
		(width 0.1143)
		(layer "F.Cu")
		(net "SMB_DPOT_DATA")
	)
	(via
		(at 185.5216 -45.5676)
		(size 0.7112)
		(drill 0.3556)
		(layers "F.Cu" "B.Cu")
		(net "SMB_DPOT_DATA")
	)
	(segment
		(start 147.828 -22.44344)
		(end 147.828 -18.796)
		(width 0.127)
		(layer "F.Cu")
		(net "C_CEO#")
	)
	(segment
		(start 147.99818 -22.61362)
		(end 147.828 -22.44344)
		(width 0.127)
		(layer "F.Cu")
		(net "C_CEO#")
	)
	(segment
		(start 147.99818 -23.9268)
		(end 147.99818 -22.61362)
		(width 0.127)
		(layer "F.Cu")
		(net "C_CEO#")
	)
	(segment
		(start 44.075096 -16.846296)
		(end 44.075096 -16.701516)
		(width 0.1143)
		(layer "F.Cu")
		(net "CLKBUFF_OE2#")
	)
	(segment
		(start 44.7548 -18.415)
		(end 45.0088 -18.161)
		(width 0.1143)
		(layer "F.Cu")
		(net "CLKBUFF_OE2#")
	)
	(segment
		(start 44.831 -17.0434)
		(end 44.2722 -17.0434)
		(width 0.1143)
		(layer "F.Cu")
		(net "CLKBUFF_OE2#")
	)
	(segment
		(start 45.0088 -17.2212)
		(end 44.9326 -17.145)
		(width 0.1143)
		(layer "F.Cu")
		(net "CLKBUFF_OE2#")
	)
	(segment
		(start 46.863 -16.51)
		(end 46.57725 -16.22425)
		(width 0.1143)
		(layer "F.Cu")
		(net "CLKBUFF_OE2#")
	)
	(segment
		(start 44.9326 -17.145)
		(end 44.831 -17.0434)
		(width 0.1143)
		(layer "F.Cu")
		(net "CLKBUFF_OE2#")
	)
	(segment
		(start 44.552362 -16.22425)
		(end 44.075096 -16.701516)
		(width 0.1143)
		(layer "F.Cu")
		(net "CLKBUFF_OE2#")
	)
	(segment
		(start 45.0088 -18.161)
		(end 45.0088 -17.2212)
		(width 0.1143)
		(layer "F.Cu")
		(net "CLKBUFF_OE2#")
	)
	(segment
		(start 44.2722 -17.0434)
		(end 44.075096 -16.846296)
		(width 0.1143)
		(layer "F.Cu")
		(net "CLKBUFF_OE2#")
	)
	(segment
		(start 46.57725 -16.22425)
		(end 44.552362 -16.22425)
		(width 0.1143)
		(layer "F.Cu")
		(net "CLKBUFF_OE2#")
	)
	(via
		(at 44.075096 -16.701516)
		(size 0.7112)
		(drill 0.3556)
		(layers "F.Cu" "B.Cu")
		(net "CLKBUFF_OE2#")
	)
	(via
		(at 44.9326 -17.145)
		(size 0.508)
		(drill 0.254)
		(layers "F.Cu" "B.Cu")
		(net "CLKBUFF_OE2#")
	)
	(segment
		(start 44.9326 -17.2974)
		(end 44.9326 -17.145)
		(width 0.1143)
		(layer "B.Cu")
		(net "CLKBUFF_OE2#")
	)
	(segment
		(start 44.51985 -18.6563)
		(end 44.51985 -17.71015)
		(width 0.1143)
		(layer "B.Cu")
		(net "CLKBUFF_OE2#")
	)
	(segment
		(start 44.51985 -17.71015)
		(end 44.9326 -17.2974)
		(width 0.1143)
		(layer "B.Cu")
		(net "CLKBUFF_OE2#")
	)
	(segment
		(start 48.3108 -18.415)
		(end 48.3108 -17.4752)
		(width 0.1143)
		(layer "F.Cu")
		(net "CLKBUFF_OE3#")
	)
	(segment
		(start 47.4726 -17.5006)
		(end 48.2346 -17.5006)
		(width 0.1143)
		(layer "F.Cu")
		(net "CLKBUFF_OE3#")
	)
	(segment
		(start 48.387 -16.51)
		(end 48.387 -17.3482)
		(width 0.1143)
		(layer "F.Cu")
		(net "CLKBUFF_OE3#")
	)
	(segment
		(start 48.387 -17.3482)
		(end 48.2854 -17.4498)
		(width 0.1143)
		(layer "F.Cu")
		(net "CLKBUFF_OE3#")
	)
	(segment
		(start 48.3108 -17.4752)
		(end 48.2854 -17.4498)
		(width 0.1143)
		(layer "F.Cu")
		(net "CLKBUFF_OE3#")
	)
	(segment
		(start 48.2346 -17.5006)
		(end 48.2854 -17.4498)
		(width 0.1143)
		(layer "F.Cu")
		(net "CLKBUFF_OE3#")
	)
	(via
		(at 48.2854 -17.4498)
		(size 0.508)
		(drill 0.254)
		(layers "F.Cu" "B.Cu")
		(net "CLKBUFF_OE3#")
	)
	(via
		(at 47.4726 -17.5006)
		(size 0.7112)
		(drill 0.3556)
		(layers "F.Cu" "B.Cu")
		(net "CLKBUFF_OE3#")
	)
	(segment
		(start 48.52289 -17.68729)
		(end 48.2854 -17.4498)
		(width 0.1143)
		(layer "B.Cu")
		(net "CLKBUFF_OE3#")
	)
	(segment
		(start 48.52289 -18.6563)
		(end 48.52289 -17.68729)
		(width 0.1143)
		(layer "B.Cu")
		(net "CLKBUFF_OE3#")
	)
	(segment
		(start 49.2252 -18.415)
		(end 49.2252 -17.526)
		(width 0.1143)
		(layer "F.Cu")
		(net "CLKBUFF_OE0#")
	)
	(segment
		(start 49.2252 -17.526)
		(end 49.149 -17.4498)
		(width 0.1143)
		(layer "F.Cu")
		(net "CLKBUFF_OE0#")
	)
	(segment
		(start 49.149 -16.51)
		(end 49.149 -17.4498)
		(width 0.1143)
		(layer "F.Cu")
		(net "CLKBUFF_OE0#")
	)
	(via
		(at 49.0474 -16.4846)
		(size 0.7112)
		(drill 0.3556)
		(layers "F.Cu" "B.Cu")
		(net "CLKBUFF_OE0#")
	)
	(via
		(at 49.149 -17.4498)
		(size 0.508)
		(drill 0.254)
		(layers "F.Cu" "B.Cu")
		(net "CLKBUFF_OE0#")
	)
	(segment
		(start 49.149 -17.4498)
		(end 49.149 -16.5862)
		(width 0.1143)
		(layer "B.Cu")
		(net "CLKBUFF_OE0#")
	)
	(segment
		(start 49.149 -16.5862)
		(end 49.0474 -16.4846)
		(width 0.1143)
		(layer "B.Cu")
		(net "CLKBUFF_OE0#")
	)
	(segment
		(start 49.02327 -18.6563)
		(end 49.02327 -17.57553)
		(width 0.1143)
		(layer "B.Cu")
		(net "CLKBUFF_OE0#")
	)
	(segment
		(start 49.02327 -17.57553)
		(end 49.149 -17.4498)
		(width 0.1143)
		(layer "B.Cu")
		(net "CLKBUFF_OE0#")
	)
	(segment
		(start 47.625 -16.637)
		(end 47.32655 -16.93545)
		(width 0.1143)
		(layer "F.Cu")
		(net "CLKBUFF_OE1#")
	)
	(segment
		(start 47.32655 -16.93545)
		(end 47.238412 -16.93545)
		(width 0.1143)
		(layer "F.Cu")
		(net "CLKBUFF_OE1#")
	)
	(segment
		(start 47.200312 -16.97355)
		(end 46.532546 -16.97355)
		(width 0.1143)
		(layer "F.Cu")
		(net "CLKBUFF_OE1#")
	)
	(segment
		(start 47.238412 -16.93545)
		(end 47.200312 -16.97355)
		(width 0.1143)
		(layer "F.Cu")
		(net "CLKBUFF_OE1#")
	)
	(segment
		(start 45.7962 -16.5608)
		(end 45.6692 -16.6878)
		(width 0.1143)
		(layer "F.Cu")
		(net "CLKBUFF_OE1#")
	)
	(segment
		(start 46.532546 -16.97355)
		(end 46.119796 -16.5608)
		(width 0.1143)
		(layer "F.Cu")
		(net "CLKBUFF_OE1#")
	)
	(segment
		(start 47.625 -16.51)
		(end 47.625 -16.637)
		(width 0.1143)
		(layer "F.Cu")
		(net "CLKBUFF_OE1#")
	)
	(segment
		(start 45.6692 -18.415)
		(end 45.6692 -16.6878)
		(width 0.1143)
		(layer "F.Cu")
		(net "CLKBUFF_OE1#")
	)
	(segment
		(start 46.119796 -16.5608)
		(end 45.7962 -16.5608)
		(width 0.1143)
		(layer "F.Cu")
		(net "CLKBUFF_OE1#")
	)
	(via
		(at 45.6692 -16.6878)
		(size 0.508)
		(drill 0.254)
		(layers "F.Cu" "B.Cu")
		(net "CLKBUFF_OE1#")
	)
	(via
		(at 46.355 -16.002)
		(size 0.7112)
		(drill 0.3556)
		(layers "F.Cu" "B.Cu")
		(net "CLKBUFF_OE1#")
	)
	(segment
		(start 46.355 -16.002)
		(end 45.6692 -16.6878)
		(width 0.1143)
		(layer "B.Cu")
		(net "CLKBUFF_OE1#")
	)
	(segment
		(start 45.02023 -18.6563)
		(end 45.02023 -17.69237)
		(width 0.1143)
		(layer "B.Cu")
		(net "CLKBUFF_OE1#")
	)
	(segment
		(start 45.6692 -17.0434)
		(end 45.6692 -16.6878)
		(width 0.1143)
		(layer "B.Cu")
		(net "CLKBUFF_OE1#")
	)
	(segment
		(start 45.02023 -17.69237)
		(end 45.6692 -17.0434)
		(width 0.1143)
		(layer "B.Cu")
		(net "CLKBUFF_OE1#")
	)
	(via
		(at 15.5194 -56.3372)
		(size 0.7112)
		(drill 0.3556)
		(layers "F.Cu" "B.Cu")
		(net "RST_PCIE_PCH_DEV_R#")
	)
	(segment
		(start 14.166088 -55.3466)
		(end 13.812774 -55.699914)
		(width 0.1143)
		(layer "B.Cu")
		(net "RST_PCIE_PCH_DEV_R#")
	)
	(segment
		(start 13.812774 -55.699914)
		(end 13.125196 -55.699914)
		(width 0.1143)
		(layer "B.Cu")
		(net "RST_PCIE_PCH_DEV_R#")
	)
	(segment
		(start 15.4432 -55.372)
		(end 15.4178 -55.3466)
		(width 0.1143)
		(layer "B.Cu")
		(net "RST_PCIE_PCH_DEV_R#")
	)
	(segment
		(start 15.4178 -55.3466)
		(end 14.166088 -55.3466)
		(width 0.1143)
		(layer "B.Cu")
		(net "RST_PCIE_PCH_DEV_R#")
	)
	(segment
		(start 15.4432 -55.372)
		(end 15.5194 -55.4482)
		(width 0.1143)
		(layer "B.Cu")
		(net "RST_PCIE_PCH_DEV_R#")
	)
	(segment
		(start 15.5194 -55.4482)
		(end 15.5194 -56.3372)
		(width 0.1143)
		(layer "B.Cu")
		(net "RST_PCIE_PCH_DEV_R#")
	)
	(segment
		(start 81.94421 -10.73785)
		(end 82.340704 -11.134344)
		(width 0.1143)
		(layer "F.Cu")
		(net "BMC_SYS_RESET#")
	)
	(segment
		(start 70.29196 -11.87704)
		(end 70.7898 -11.3792)
		(width 0.1143)
		(layer "F.Cu")
		(net "BMC_SYS_RESET#")
	)
	(segment
		(start 80.310736 -10.80135)
		(end 81.51749 -10.80135)
		(width 0.1143)
		(layer "F.Cu")
		(net "BMC_SYS_RESET#")
	)
	(segment
		(start 82.340704 -11.134344)
		(end 82.340704 -12.3444)
		(width 0.1143)
		(layer "F.Cu")
		(net "BMC_SYS_RESET#")
	)
	(segment
		(start 81.58099 -10.73785)
		(end 81.94421 -10.73785)
		(width 0.1143)
		(layer "F.Cu")
		(net "BMC_SYS_RESET#")
	)
	(segment
		(start 70.29196 -12.17676)
		(end 70.29196 -11.87704)
		(width 0.1143)
		(layer "F.Cu")
		(net "BMC_SYS_RESET#")
	)
	(segment
		(start 80.139286 -10.9728)
		(end 80.310736 -10.80135)
		(width 0.1143)
		(layer "F.Cu")
		(net "BMC_SYS_RESET#")
	)
	(segment
		(start 81.51749 -10.80135)
		(end 81.58099 -10.73785)
		(width 0.1143)
		(layer "F.Cu")
		(net "BMC_SYS_RESET#")
	)
	(segment
		(start 70.7898 -11.3792)
		(end 71.1962 -10.9728)
		(width 0.1143)
		(layer "F.Cu")
		(net "BMC_SYS_RESET#")
	)
	(segment
		(start 71.1962 -10.9728)
		(end 80.139286 -10.9728)
		(width 0.1143)
		(layer "F.Cu")
		(net "BMC_SYS_RESET#")
	)
	(via
		(at 85.09 -11.83005)
		(size 0.7112)
		(drill 0.3556)
		(layers "F.Cu" "B.Cu")
		(net "BMC_SYS_RESET#")
	)
	(via
		(at 70.7898 -11.3792)
		(size 0.508)
		(drill 0.254)
		(layers "F.Cu" "B.Cu")
		(net "BMC_SYS_RESET#")
	)
	(via
		(at 82.340704 -12.3444)
		(size 0.508)
		(drill 0.254)
		(layers "F.Cu" "B.Cu")
		(net "BMC_SYS_RESET#")
	)
	(segment
		(start 82.855054 -11.83005)
		(end 82.340704 -12.3444)
		(width 0.1143)
		(layer "B.Cu")
		(net "BMC_SYS_RESET#")
	)
	(segment
		(start 88.6206 -11.1125)
		(end 87.6808 -12.0523)
		(width 0.1143)
		(layer "B.Cu")
		(net "BMC_SYS_RESET#")
	)
	(segment
		(start 88.6206 -9.1186)
		(end 88.6206 -11.1125)
		(width 0.1143)
		(layer "B.Cu")
		(net "BMC_SYS_RESET#")
	)
	(segment
		(start 87.6808 -12.0523)
		(end 85.74405 -12.0523)
		(width 0.1143)
		(layer "B.Cu")
		(net "BMC_SYS_RESET#")
	)
	(segment
		(start 70.358 -11.811)
		(end 70.7898 -11.3792)
		(width 0.1143)
		(layer "B.Cu")
		(net "BMC_SYS_RESET#")
	)
	(segment
		(start 70.358 -12.5222)
		(end 70.358 -11.811)
		(width 0.1143)
		(layer "B.Cu")
		(net "BMC_SYS_RESET#")
	)
	(segment
		(start 88.35009 -5.814568)
		(end 88.35009 -8.84809)
		(width 0.1143)
		(layer "B.Cu")
		(net "BMC_SYS_RESET#")
	)
	(segment
		(start 88.35009 -8.84809)
		(end 88.6206 -9.1186)
		(width 0.1143)
		(layer "B.Cu")
		(net "BMC_SYS_RESET#")
	)
	(segment
		(start 85.74405 -12.0523)
		(end 85.5218 -11.83005)
		(width 0.1143)
		(layer "B.Cu")
		(net "BMC_SYS_RESET#")
	)
	(segment
		(start 85.5218 -11.83005)
		(end 85.09 -11.83005)
		(width 0.1143)
		(layer "B.Cu")
		(net "BMC_SYS_RESET#")
	)
	(segment
		(start 85.09 -11.83005)
		(end 82.855054 -11.83005)
		(width 0.1143)
		(layer "B.Cu")
		(net "BMC_SYS_RESET#")
	)
	(segment
		(start 132.65912 -22.81174)
		(end 132.264658 -22.417278)
		(width 0.1143)
		(layer "F.Cu")
		(net "BIOS_POST_CMPLT#")
	)
	(segment
		(start 115.641882 -2.9845)
		(end 113.9571 -2.9845)
		(width 0.1143)
		(layer "F.Cu")
		(net "BIOS_POST_CMPLT#")
	)
	(segment
		(start 132.264658 -22.41042)
		(end 131.76885 -21.914612)
		(width 0.1143)
		(layer "F.Cu")
		(net "BIOS_POST_CMPLT#")
	)
	(segment
		(start 113.9571 -2.9845)
		(end 113.4872 -2.5146)
		(width 0.1143)
		(layer "F.Cu")
		(net "BIOS_POST_CMPLT#")
	)
	(segment
		(start 132.264658 -22.417278)
		(end 132.264658 -22.41042)
		(width 0.1143)
		(layer "F.Cu")
		(net "BIOS_POST_CMPLT#")
	)
	(segment
		(start 131.76885 -14.515846)
		(end 129.891282 -12.638278)
		(width 0.1143)
		(layer "F.Cu")
		(net "BIOS_POST_CMPLT#")
	)
	(segment
		(start 119.803926 -4.616196)
		(end 117.273578 -4.616196)
		(width 0.1143)
		(layer "F.Cu")
		(net "BIOS_POST_CMPLT#")
	)
	(segment
		(start 88.213946 -40.716454)
		(end 87.8586 -41.0718)
		(width 0.1143)
		(layer "F.Cu")
		(net "BIOS_POST_CMPLT#")
	)
	(segment
		(start 131.76885 -21.914612)
		(end 131.76885 -14.515846)
		(width 0.1143)
		(layer "F.Cu")
		(net "BIOS_POST_CMPLT#")
	)
	(segment
		(start 127.826008 -12.638278)
		(end 119.803926 -4.616196)
		(width 0.1143)
		(layer "F.Cu")
		(net "BIOS_POST_CMPLT#")
	)
	(segment
		(start 117.273578 -4.616196)
		(end 115.641882 -2.9845)
		(width 0.1143)
		(layer "F.Cu")
		(net "BIOS_POST_CMPLT#")
	)
	(segment
		(start 88.219788 -40.716454)
		(end 88.213946 -40.716454)
		(width 0.1143)
		(layer "F.Cu")
		(net "BIOS_POST_CMPLT#")
	)
	(segment
		(start 129.891282 -12.638278)
		(end 127.826008 -12.638278)
		(width 0.1143)
		(layer "F.Cu")
		(net "BIOS_POST_CMPLT#")
	)
	(via
		(at 113.4872 -2.5146)
		(size 0.508)
		(drill 0.254)
		(layers "F.Cu" "B.Cu")
		(net "BIOS_POST_CMPLT#")
	)
	(via
		(at 132.334 -24.511)
		(size 0.7112)
		(drill 0.3556)
		(layers "F.Cu" "B.Cu")
		(net "BIOS_POST_CMPLT#")
	)
	(via
		(at 87.8586 -41.0718)
		(size 0.4318)
		(drill 0.2032)
		(layers "F.Cu" "B.Cu")
		(net "BIOS_POST_CMPLT#")
	)
	(via
		(at 132.65912 -22.81174)
		(size 0.508)
		(drill 0.254)
		(layers "F.Cu" "B.Cu")
		(net "BIOS_POST_CMPLT#")
	)
	(segment
		(start 75.849734 -49.423066)
		(end 75.3618 -49.911)
		(width 0.1143)
		(layer "B.Cu")
		(net "BIOS_POST_CMPLT#")
	)
	(segment
		(start 82.867754 -42.227246)
		(end 82.458814 -42.636186)
		(width 0.1143)
		(layer "B.Cu")
		(net "BIOS_POST_CMPLT#")
	)
	(segment
		(start 132.7912 -24.0538)
		(end 132.7912 -23.622)
		(width 0.1143)
		(layer "B.Cu")
		(net "BIOS_POST_CMPLT#")
	)
	(segment
		(start 87.8586 -41.0718)
		(end 87.552784 -41.0718)
		(width 0.1143)
		(layer "B.Cu")
		(net "BIOS_POST_CMPLT#")
	)
	(segment
		(start 80.194658 -46.551342)
		(end 79.67726 -47.06874)
		(width 0.1143)
		(layer "B.Cu")
		(net "BIOS_POST_CMPLT#")
	)
	(segment
		(start 132.7912 -22.94382)
		(end 132.65912 -22.81174)
		(width 0.1143)
		(layer "B.Cu")
		(net "BIOS_POST_CMPLT#")
	)
	(segment
		(start 76.2889 -47.06874)
		(end 75.849734 -47.507906)
		(width 0.1143)
		(layer "B.Cu")
		(net "BIOS_POST_CMPLT#")
	)
	(segment
		(start 80.194658 -44.725844)
		(end 80.194658 -46.551342)
		(width 0.1143)
		(layer "B.Cu")
		(net "BIOS_POST_CMPLT#")
	)
	(segment
		(start 86.397338 -42.227246)
		(end 82.867754 -42.227246)
		(width 0.1143)
		(layer "B.Cu")
		(net "BIOS_POST_CMPLT#")
	)
	(segment
		(start 75.849734 -47.507906)
		(end 75.849734 -49.423066)
		(width 0.1143)
		(layer "B.Cu")
		(net "BIOS_POST_CMPLT#")
	)
	(segment
		(start 82.284316 -42.636186)
		(end 80.194658 -44.725844)
		(width 0.1143)
		(layer "B.Cu")
		(net "BIOS_POST_CMPLT#")
	)
	(segment
		(start 132.7912 -23.622)
		(end 132.7912 -22.94382)
		(width 0.1143)
		(layer "B.Cu")
		(net "BIOS_POST_CMPLT#")
	)
	(segment
		(start 132.334 -24.511)
		(end 132.7912 -24.0538)
		(width 0.1143)
		(layer "B.Cu")
		(net "BIOS_POST_CMPLT#")
	)
	(segment
		(start 87.552784 -41.0718)
		(end 86.397338 -42.227246)
		(width 0.1143)
		(layer "B.Cu")
		(net "BIOS_POST_CMPLT#")
	)
	(segment
		(start 82.458814 -42.636186)
		(end 82.284316 -42.636186)
		(width 0.1143)
		(layer "B.Cu")
		(net "BIOS_POST_CMPLT#")
	)
	(segment
		(start 79.67726 -47.06874)
		(end 76.2889 -47.06874)
		(width 0.1143)
		(layer "B.Cu")
		(net "BIOS_POST_CMPLT#")
	)
	(segment
		(start 86.48065 -16.05915)
		(end 94.770194 -16.05915)
		(width 0.0889)
		(layer "In9.Cu")
		(net "BIOS_POST_CMPLT#")
	)
	(segment
		(start 106.386376 -16.456406)
		(end 110.31855 -12.524232)
		(width 0.0889)
		(layer "In9.Cu")
		(net "BIOS_POST_CMPLT#")
	)
	(segment
		(start 87.8586 -41.0718)
		(end 87.0458 -40.259)
		(width 0.0889)
		(layer "In9.Cu")
		(net "BIOS_POST_CMPLT#")
	)
	(segment
		(start 81.4451 -27.86126)
		(end 81.4451 -25.414986)
		(width 0.0889)
		(layer "In9.Cu")
		(net "BIOS_POST_CMPLT#")
	)
	(segment
		(start 87.0458 -40.259)
		(end 86.660736 -40.259)
		(width 0.0889)
		(layer "In9.Cu")
		(net "BIOS_POST_CMPLT#")
	)
	(segment
		(start 81.4451 -25.414986)
		(end 81.52003 -25.340056)
		(width 0.0889)
		(layer "In9.Cu")
		(net "BIOS_POST_CMPLT#")
	)
	(segment
		(start 81.42859 -29.21889)
		(end 81.89722 -28.75026)
		(width 0.0889)
		(layer "In9.Cu")
		(net "BIOS_POST_CMPLT#")
	)
	(segment
		(start 81.788 -36.2204)
		(end 81.788 -35.052)
		(width 0.0889)
		(layer "In9.Cu")
		(net "BIOS_POST_CMPLT#")
	)
	(segment
		(start 81.7626 -31.7754)
		(end 81.7626 -30.735778)
		(width 0.0889)
		(layer "In9.Cu")
		(net "BIOS_POST_CMPLT#")
	)
	(segment
		(start 86.660736 -40.259)
		(end 86.35111 -39.949374)
		(width 0.0889)
		(layer "In9.Cu")
		(net "BIOS_POST_CMPLT#")
	)
	(segment
		(start 81.10855 -21.751036)
		(end 85.487002 -17.372584)
		(width 0.0889)
		(layer "In9.Cu")
		(net "BIOS_POST_CMPLT#")
	)
	(segment
		(start 85.650324 -36.6776)
		(end 82.2452 -36.6776)
		(width 0.0889)
		(layer "In9.Cu")
		(net "BIOS_POST_CMPLT#")
	)
	(segment
		(start 85.93963 -36.966906)
		(end 85.650324 -36.6776)
		(width 0.0889)
		(layer "In9.Cu")
		(net "BIOS_POST_CMPLT#")
	)
	(segment
		(start 80.999584 -32.538416)
		(end 81.7626 -31.7754)
		(width 0.0889)
		(layer "In9.Cu")
		(net "BIOS_POST_CMPLT#")
	)
	(segment
		(start 81.42859 -30.401768)
		(end 81.42859 -29.21889)
		(width 0.0889)
		(layer "In9.Cu")
		(net "BIOS_POST_CMPLT#")
	)
	(segment
		(start 81.52003 -23.022306)
		(end 81.10855 -22.610826)
		(width 0.0889)
		(layer "In9.Cu")
		(net "BIOS_POST_CMPLT#")
	)
	(segment
		(start 86.35111 -38.94582)
		(end 85.93963 -38.53434)
		(width 0.0889)
		(layer "In9.Cu")
		(net "BIOS_POST_CMPLT#")
	)
	(segment
		(start 112.803432 -2.5146)
		(end 113.4872 -2.5146)
		(width 0.0889)
		(layer "In9.Cu")
		(net "BIOS_POST_CMPLT#")
	)
	(segment
		(start 80.999584 -34.263584)
		(end 80.999584 -32.538416)
		(width 0.0889)
		(layer "In9.Cu")
		(net "BIOS_POST_CMPLT#")
	)
	(segment
		(start 86.35111 -39.949374)
		(end 86.35111 -38.94582)
		(width 0.0889)
		(layer "In9.Cu")
		(net "BIOS_POST_CMPLT#")
	)
	(segment
		(start 81.89722 -28.75026)
		(end 81.89722 -28.31338)
		(width 0.0889)
		(layer "In9.Cu")
		(net "BIOS_POST_CMPLT#")
	)
	(segment
		(start 94.770194 -16.05915)
		(end 95.16745 -16.456406)
		(width 0.0889)
		(layer "In9.Cu")
		(net "BIOS_POST_CMPLT#")
	)
	(segment
		(start 82.2452 -36.6776)
		(end 81.788 -36.2204)
		(width 0.0889)
		(layer "In9.Cu")
		(net "BIOS_POST_CMPLT#")
	)
	(segment
		(start 95.16745 -16.456406)
		(end 106.386376 -16.456406)
		(width 0.0889)
		(layer "In9.Cu")
		(net "BIOS_POST_CMPLT#")
	)
	(segment
		(start 85.93963 -38.53434)
		(end 85.93963 -36.966906)
		(width 0.0889)
		(layer "In9.Cu")
		(net "BIOS_POST_CMPLT#")
	)
	(segment
		(start 81.788 -35.052)
		(end 80.999584 -34.263584)
		(width 0.0889)
		(layer "In9.Cu")
		(net "BIOS_POST_CMPLT#")
	)
	(segment
		(start 81.7626 -30.735778)
		(end 81.42859 -30.401768)
		(width 0.0889)
		(layer "In9.Cu")
		(net "BIOS_POST_CMPLT#")
	)
	(segment
		(start 110.31855 -12.524232)
		(end 110.31855 -4.999482)
		(width 0.0889)
		(layer "In9.Cu")
		(net "BIOS_POST_CMPLT#")
	)
	(segment
		(start 81.89722 -28.31338)
		(end 81.4451 -27.86126)
		(width 0.0889)
		(layer "In9.Cu")
		(net "BIOS_POST_CMPLT#")
	)
	(segment
		(start 110.31855 -4.999482)
		(end 112.803432 -2.5146)
		(width 0.0889)
		(layer "In9.Cu")
		(net "BIOS_POST_CMPLT#")
	)
	(segment
		(start 85.487002 -17.372584)
		(end 85.487002 -17.052798)
		(width 0.0889)
		(layer "In9.Cu")
		(net "BIOS_POST_CMPLT#")
	)
	(segment
		(start 81.52003 -25.340056)
		(end 81.52003 -23.022306)
		(width 0.0889)
		(layer "In9.Cu")
		(net "BIOS_POST_CMPLT#")
	)
	(segment
		(start 81.10855 -22.610826)
		(end 81.10855 -21.751036)
		(width 0.0889)
		(layer "In9.Cu")
		(net "BIOS_POST_CMPLT#")
	)
	(segment
		(start 85.487002 -17.052798)
		(end 86.48065 -16.05915)
		(width 0.0889)
		(layer "In9.Cu")
		(net "BIOS_POST_CMPLT#")
	)
	(segment
		(start 5.169408 -44.488608)
		(end 4.699 -44.0182)
		(width 0.1143)
		(layer "F.Cu")
		(net "TEMP_1_DATA")
	)
	(segment
		(start 5.864606 -44.488608)
		(end 5.169408 -44.488608)
		(width 0.1143)
		(layer "F.Cu")
		(net "TEMP_1_DATA")
	)
	(segment
		(start 5.0546 -45.4406)
		(end 6.0706 -45.4406)
		(width 0.1143)
		(layer "F.Cu")
		(net "TEMP_1_CLK")
	)
	(segment
		(start 4.699 -45.7962)
		(end 5.0546 -45.4406)
		(width 0.1143)
		(layer "F.Cu")
		(net "TEMP_1_CLK")
	)
	(segment
		(start 6.514846 -44.996354)
		(end 6.514846 -44.488608)
		(width 0.1143)
		(layer "F.Cu")
		(net "TEMP_1_CLK")
	)
	(segment
		(start 6.0706 -45.4406)
		(end 6.514846 -44.996354)
		(width 0.1143)
		(layer "F.Cu")
		(net "TEMP_1_CLK")
	)
	(segment
		(start 153.870406 -55.410862)
		(end 152.410668 -56.8706)
		(width 0.1143)
		(layer "F.Cu")
		(net "BMC_I2C_CLK")
	)
	(segment
		(start 153.66365 -52.532788)
		(end 153.870406 -52.739544)
		(width 0.1143)
		(layer "F.Cu")
		(net "BMC_I2C_CLK")
	)
	(segment
		(start 152.1841 -45.7962)
		(end 151.911304 -45.7962)
		(width 0.1143)
		(layer "F.Cu")
		(net "BMC_I2C_CLK")
	)
	(segment
		(start 31.862268 -11.3792)
		(end 31.09976 -12.141708)
		(width 0.1143)
		(layer "F.Cu")
		(net "BMC_I2C_CLK")
	)
	(segment
		(start 151.71547 -56.8706)
		(end 151.5999 -56.98617)
		(width 0.1143)
		(layer "F.Cu")
		(net "BMC_I2C_CLK")
	)
	(segment
		(start 151.727154 -45.98035)
		(end 151.269446 -45.98035)
		(width 0.1143)
		(layer "F.Cu")
		(net "BMC_I2C_CLK")
	)
	(segment
		(start 151.269446 -45.98035)
		(end 150.99792 -45.708824)
		(width 0.1143)
		(layer "F.Cu")
		(net "BMC_I2C_CLK")
	)
	(segment
		(start 153.870406 -52.739544)
		(end 153.870406 -55.410862)
		(width 0.1143)
		(layer "F.Cu")
		(net "BMC_I2C_CLK")
	)
	(segment
		(start 152.40635 -46.53661)
		(end 152.48255 -46.61281)
		(width 0.1143)
		(layer "F.Cu")
		(net "BMC_I2C_CLK")
	)
	(segment
		(start 150.99792 -45.708824)
		(end 150.99792 -45.1612)
		(width 0.1143)
		(layer "F.Cu")
		(net "BMC_I2C_CLK")
	)
	(segment
		(start 34.6964 -11.3792)
		(end 31.862268 -11.3792)
		(width 0.1143)
		(layer "F.Cu")
		(net "BMC_I2C_CLK")
	)
	(segment
		(start 175.7426 -46.0756)
		(end 175.7426 -45.174662)
		(width 0.1143)
		(layer "F.Cu")
		(net "BMC_I2C_CLK")
	)
	(segment
		(start 175.7426 -45.174662)
		(end 175.144938 -44.577)
		(width 0.1143)
		(layer "F.Cu")
		(net "BMC_I2C_CLK")
	)
	(segment
		(start 152.48255 -48.72355)
		(end 153.66365 -49.90465)
		(width 0.1143)
		(layer "F.Cu")
		(net "BMC_I2C_CLK")
	)
	(segment
		(start 152.410668 -56.8706)
		(end 151.71547 -56.8706)
		(width 0.1143)
		(layer "F.Cu")
		(net "BMC_I2C_CLK")
	)
	(segment
		(start 152.1841 -45.7962)
		(end 152.40635 -46.01845)
		(width 0.1143)
		(layer "F.Cu")
		(net "BMC_I2C_CLK")
	)
	(segment
		(start 31.09976 -12.141708)
		(end 31.09976 -12.5095)
		(width 0.1143)
		(layer "F.Cu")
		(net "BMC_I2C_CLK")
	)
	(segment
		(start 151.911304 -45.7962)
		(end 151.727154 -45.98035)
		(width 0.1143)
		(layer "F.Cu")
		(net "BMC_I2C_CLK")
	)
	(segment
		(start 73.050908 -57.15)
		(end 73.101708 -57.2008)
		(width 0.1143)
		(layer "F.Cu")
		(net "BMC_I2C_CLK")
	)
	(segment
		(start 152.40635 -46.01845)
		(end 152.40635 -46.53661)
		(width 0.1143)
		(layer "F.Cu")
		(net "BMC_I2C_CLK")
	)
	(segment
		(start 152.48255 -46.61281)
		(end 152.48255 -48.72355)
		(width 0.1143)
		(layer "F.Cu")
		(net "BMC_I2C_CLK")
	)
	(segment
		(start 153.66365 -49.90465)
		(end 153.66365 -52.532788)
		(width 0.1143)
		(layer "F.Cu")
		(net "BMC_I2C_CLK")
	)
	(segment
		(start 29.972 -12.9032)
		(end 30.3657 -12.5095)
		(width 0.1143)
		(layer "F.Cu")
		(net "BMC_I2C_CLK")
	)
	(segment
		(start 30.3657 -12.5095)
		(end 31.09976 -12.5095)
		(width 0.1143)
		(layer "F.Cu")
		(net "BMC_I2C_CLK")
	)
	(segment
		(start 72.3138 -57.15)
		(end 73.050908 -57.15)
		(width 0.1143)
		(layer "F.Cu")
		(net "BMC_I2C_CLK")
	)
	(via
		(at 34.6964 -11.3792)
		(size 0.508)
		(drill 0.254)
		(layers "F.Cu" "B.Cu")
		(net "BMC_I2C_CLK")
	)
	(via
		(at 73.101708 -57.2008)
		(size 0.508)
		(drill 0.254)
		(layers "F.Cu" "B.Cu")
		(net "BMC_I2C_CLK")
	)
	(via
		(at 109.1946 -69.83476)
		(size 0.508)
		(drill 0.254)
		(layers "F.Cu" "B.Cu")
		(net "BMC_I2C_CLK")
	)
	(via
		(at 152.1841 -45.7962)
		(size 0.508)
		(drill 0.254)
		(layers "F.Cu" "B.Cu")
		(net "BMC_I2C_CLK")
	)
	(via
		(at 175.144938 -44.577)
		(size 0.508)
		(drill 0.254)
		(layers "F.Cu" "B.Cu")
		(net "BMC_I2C_CLK")
	)
	(via
		(at 153.0731 -45.0215)
		(size 0.7112)
		(drill 0.3556)
		(layers "F.Cu" "B.Cu")
		(net "BMC_I2C_CLK")
	)
	(segment
		(start 152.9588 -45.0215)
		(end 153.0731 -45.0215)
		(width 0.1143)
		(layer "B.Cu")
		(net "BMC_I2C_CLK")
	)
	(segment
		(start 152.1841 -45.7962)
		(end 152.9588 -45.0215)
		(width 0.1143)
		(layer "B.Cu")
		(net "BMC_I2C_CLK")
	)
	(segment
		(start 154.90825 -43.18635)
		(end 173.754288 -43.18635)
		(width 0.1143)
		(layer "B.Cu")
		(net "BMC_I2C_CLK")
	)
	(segment
		(start 153.0731 -45.0215)
		(end 154.90825 -43.18635)
		(width 0.1143)
		(layer "B.Cu")
		(net "BMC_I2C_CLK")
	)
	(segment
		(start 173.754288 -43.18635)
		(end 175.144938 -44.577)
		(width 0.1143)
		(layer "B.Cu")
		(net "BMC_I2C_CLK")
	)
	(segment
		(start 127.387604 -72.523604)
		(end 190.108078 -72.523604)
		(width 0.0889)
		(layer "In2.Cu")
		(net "BMC_I2C_CLK")
	)
	(segment
		(start 109.1946 -69.6468)
		(end 110.64875 -68.19265)
		(width 0.0889)
		(layer "In2.Cu")
		(net "BMC_I2C_CLK")
	)
	(segment
		(start 182.019702 -44.577)
		(end 175.144938 -44.577)
		(width 0.0889)
		(layer "In2.Cu")
		(net "BMC_I2C_CLK")
	)
	(segment
		(start 113.908586 -68.19265)
		(end 115.943126 -66.15811)
		(width 0.0889)
		(layer "In2.Cu")
		(net "BMC_I2C_CLK")
	)
	(segment
		(start 194.0941 -63.339218)
		(end 186.12485 -55.369968)
		(width 0.0889)
		(layer "In2.Cu")
		(net "BMC_I2C_CLK")
	)
	(segment
		(start 123.1392 -68.2752)
		(end 127.387604 -72.523604)
		(width 0.0889)
		(layer "In2.Cu")
		(net "BMC_I2C_CLK")
	)
	(segment
		(start 185.2803 -47.445422)
		(end 182.411624 -44.576746)
		(width 0.0889)
		(layer "In2.Cu")
		(net "BMC_I2C_CLK")
	)
	(segment
		(start 185.2803 -52.359306)
		(end 185.2803 -47.445422)
		(width 0.0889)
		(layer "In2.Cu")
		(net "BMC_I2C_CLK")
	)
	(segment
		(start 186.12485 -53.203856)
		(end 185.2803 -52.359306)
		(width 0.0889)
		(layer "In2.Cu")
		(net "BMC_I2C_CLK")
	)
	(segment
		(start 182.019956 -44.576746)
		(end 182.019702 -44.577)
		(width 0.0889)
		(layer "In2.Cu")
		(net "BMC_I2C_CLK")
	)
	(segment
		(start 182.411624 -44.576746)
		(end 182.019956 -44.576746)
		(width 0.0889)
		(layer "In2.Cu")
		(net "BMC_I2C_CLK")
	)
	(segment
		(start 109.1946 -69.83476)
		(end 109.1946 -69.6468)
		(width 0.0889)
		(layer "In2.Cu")
		(net "BMC_I2C_CLK")
	)
	(segment
		(start 121.737628 -66.15811)
		(end 123.1392 -67.559682)
		(width 0.0889)
		(layer "In2.Cu")
		(net "BMC_I2C_CLK")
	)
	(segment
		(start 115.943126 -66.15811)
		(end 121.737628 -66.15811)
		(width 0.0889)
		(layer "In2.Cu")
		(net "BMC_I2C_CLK")
	)
	(segment
		(start 186.12485 -55.369968)
		(end 186.12485 -53.203856)
		(width 0.0889)
		(layer "In2.Cu")
		(net "BMC_I2C_CLK")
	)
	(segment
		(start 110.64875 -68.19265)
		(end 113.908586 -68.19265)
		(width 0.0889)
		(layer "In2.Cu")
		(net "BMC_I2C_CLK")
	)
	(segment
		(start 190.108078 -72.523604)
		(end 194.0941 -68.537582)
		(width 0.0889)
		(layer "In2.Cu")
		(net "BMC_I2C_CLK")
	)
	(segment
		(start 194.0941 -68.537582)
		(end 194.0941 -63.339218)
		(width 0.0889)
		(layer "In2.Cu")
		(net "BMC_I2C_CLK")
	)
	(segment
		(start 123.1392 -67.559682)
		(end 123.1392 -68.2752)
		(width 0.0889)
		(layer "In2.Cu")
		(net "BMC_I2C_CLK")
	)
	(segment
		(start 86.317582 -62.9793)
		(end 81.81213 -62.9793)
		(width 0.0889)
		(layer "In7.Cu")
		(net "BMC_I2C_CLK")
	)
	(segment
		(start 81.81213 -62.9793)
		(end 81.32953 -62.4967)
		(width 0.0889)
		(layer "In7.Cu")
		(net "BMC_I2C_CLK")
	)
	(segment
		(start 73.101708 -59.284108)
		(end 73.101708 -57.2008)
		(width 0.0889)
		(layer "In7.Cu")
		(net "BMC_I2C_CLK")
	)
	(segment
		(start 81.32953 -62.4967)
		(end 76.3143 -62.4967)
		(width 0.0889)
		(layer "In7.Cu")
		(net "BMC_I2C_CLK")
	)
	(segment
		(start 109.1946 -69.83476)
		(end 108.07446 -70.9549)
		(width 0.0889)
		(layer "In7.Cu")
		(net "BMC_I2C_CLK")
	)
	(segment
		(start 108.07446 -70.9549)
		(end 94.293182 -70.9549)
		(width 0.0889)
		(layer "In7.Cu")
		(net "BMC_I2C_CLK")
	)
	(segment
		(start 94.293182 -70.9549)
		(end 86.317582 -62.9793)
		(width 0.0889)
		(layer "In7.Cu")
		(net "BMC_I2C_CLK")
	)
	(segment
		(start 76.3143 -62.4967)
		(end 73.101708 -59.284108)
		(width 0.0889)
		(layer "In7.Cu")
		(net "BMC_I2C_CLK")
	)
	(segment
		(start 61.5696 -50.95748)
		(end 63.25997 -52.64785)
		(width 0.0889)
		(layer "In9.Cu")
		(net "BMC_I2C_CLK")
	)
	(segment
		(start 66.878962 -52.8701)
		(end 69.166994 -52.8701)
		(width 0.0889)
		(layer "In9.Cu")
		(net "BMC_I2C_CLK")
	)
	(segment
		(start 57.39765 -46.866556)
		(end 60.035694 -49.5046)
		(width 0.0889)
		(layer "In9.Cu")
		(net "BMC_I2C_CLK")
	)
	(segment
		(start 63.25997 -52.64785)
		(end 66.656712 -52.64785)
		(width 0.0889)
		(layer "In9.Cu")
		(net "BMC_I2C_CLK")
	)
	(segment
		(start 41.783 -26.960068)
		(end 51.284632 -36.4617)
		(width 0.0889)
		(layer "In9.Cu")
		(net "BMC_I2C_CLK")
	)
	(segment
		(start 32.67075 -15.579344)
		(end 32.941006 -15.8496)
		(width 0.0889)
		(layer "In9.Cu")
		(net "BMC_I2C_CLK")
	)
	(segment
		(start 57.39765 -45.420788)
		(end 57.39765 -46.866556)
		(width 0.0889)
		(layer "In9.Cu")
		(net "BMC_I2C_CLK")
	)
	(segment
		(start 34.6964 -11.3792)
		(end 33.655 -11.3792)
		(width 0.0889)
		(layer "In9.Cu")
		(net "BMC_I2C_CLK")
	)
	(segment
		(start 41.783 -22.873208)
		(end 41.783 -26.960068)
		(width 0.0889)
		(layer "In9.Cu")
		(net "BMC_I2C_CLK")
	)
	(segment
		(start 69.166994 -52.8701)
		(end 73.101708 -56.804814)
		(width 0.0889)
		(layer "In9.Cu")
		(net "BMC_I2C_CLK")
	)
	(segment
		(start 73.101708 -56.804814)
		(end 73.101708 -57.2008)
		(width 0.0889)
		(layer "In9.Cu")
		(net "BMC_I2C_CLK")
	)
	(segment
		(start 37.811964 -20.353274)
		(end 39.263066 -20.353274)
		(width 0.0889)
		(layer "In9.Cu")
		(net "BMC_I2C_CLK")
	)
	(segment
		(start 55.753508 -43.776646)
		(end 57.39765 -45.420788)
		(width 0.0889)
		(layer "In9.Cu")
		(net "BMC_I2C_CLK")
	)
	(segment
		(start 52.766722 -36.4617)
		(end 55.753508 -39.448486)
		(width 0.0889)
		(layer "In9.Cu")
		(net "BMC_I2C_CLK")
	)
	(segment
		(start 55.753508 -39.448486)
		(end 55.753508 -43.776646)
		(width 0.0889)
		(layer "In9.Cu")
		(net "BMC_I2C_CLK")
	)
	(segment
		(start 33.30829 -15.8496)
		(end 37.811964 -20.353274)
		(width 0.0889)
		(layer "In9.Cu")
		(net "BMC_I2C_CLK")
	)
	(segment
		(start 33.655 -11.3792)
		(end 32.67075 -12.36345)
		(width 0.0889)
		(layer "In9.Cu")
		(net "BMC_I2C_CLK")
	)
	(segment
		(start 32.67075 -12.36345)
		(end 32.67075 -15.579344)
		(width 0.0889)
		(layer "In9.Cu")
		(net "BMC_I2C_CLK")
	)
	(segment
		(start 66.656712 -52.64785)
		(end 66.878962 -52.8701)
		(width 0.0889)
		(layer "In9.Cu")
		(net "BMC_I2C_CLK")
	)
	(segment
		(start 39.263066 -20.353274)
		(end 41.783 -22.873208)
		(width 0.0889)
		(layer "In9.Cu")
		(net "BMC_I2C_CLK")
	)
	(segment
		(start 51.284632 -36.4617)
		(end 52.766722 -36.4617)
		(width 0.0889)
		(layer "In9.Cu")
		(net "BMC_I2C_CLK")
	)
	(segment
		(start 32.941006 -15.8496)
		(end 33.30829 -15.8496)
		(width 0.0889)
		(layer "In9.Cu")
		(net "BMC_I2C_CLK")
	)
	(segment
		(start 61.5696 -49.6824)
		(end 61.5696 -50.95748)
		(width 0.0889)
		(layer "In9.Cu")
		(net "BMC_I2C_CLK")
	)
	(segment
		(start 60.035694 -49.5046)
		(end 61.3918 -49.5046)
		(width 0.0889)
		(layer "In9.Cu")
		(net "BMC_I2C_CLK")
	)
	(segment
		(start 61.3918 -49.5046)
		(end 61.5696 -49.6824)
		(width 0.0889)
		(layer "In9.Cu")
		(net "BMC_I2C_CLK")
	)
	(segment
		(start 153.3652 -33.79343)
		(end 155.25877 -33.79343)
		(width 0.1143)
		(layer "F.Cu")
		(net "READY_R#")
	)
	(segment
		(start 156.7942 -32.639)
		(end 156.4132 -32.639)
		(width 0.1143)
		(layer "F.Cu")
		(net "READY_R#")
	)
	(segment
		(start 156.4132 -32.639)
		(end 155.25877 -33.79343)
		(width 0.1143)
		(layer "F.Cu")
		(net "READY_R#")
	)
	(via
		(at 155.25877 -33.79343)
		(size 0.7112)
		(drill 0.3556)
		(layers "F.Cu" "B.Cu")
		(net "READY_R#")
	)
	(segment
		(start 114.938556 -8.4836)
		(end 113.185956 -6.731)
		(width 0.1143)
		(layer "F.Cu")
		(net "PVCCP_PVNN_VRHOT#")
	)
	(segment
		(start 119.4308 -12.065)
		(end 119.4308 -9.906)
		(width 0.1143)
		(layer "F.Cu")
		(net "PVCCP_PVNN_VRHOT#")
	)
	(segment
		(start 109.30255 -4.78155)
		(end 108.92155 -4.78155)
		(width 0.1143)
		(layer "F.Cu")
		(net "PVCCP_PVNN_VRHOT#")
	)
	(segment
		(start 15.4178 -53.700172)
		(end 15.4178 -53.7972)
		(width 0.1143)
		(layer "F.Cu")
		(net "PVCCP_PVNN_VRHOT#")
	)
	(segment
		(start 15.4686 -49.541684)
		(end 14.859 -50.151284)
		(width 0.1143)
		(layer "F.Cu")
		(net "PVCCP_PVNN_VRHOT#")
	)
	(segment
		(start 182.372 -33.0708)
		(end 183.2102 -33.0708)
		(width 0.1143)
		(layer "F.Cu")
		(net "PVCCP_PVNN_VRHOT#")
	)
	(segment
		(start 182.1942 -32.893)
		(end 182.372 -33.0708)
		(width 0.1143)
		(layer "F.Cu")
		(net "PVCCP_PVNN_VRHOT#")
	)
	(segment
		(start 16.41475 -47.69485)
		(end 15.4686 -48.641)
		(width 0.1143)
		(layer "F.Cu")
		(net "PVCCP_PVNN_VRHOT#")
	)
	(segment
		(start 130.860038 -25.7937)
		(end 130.790188 -25.72385)
		(width 0.1143)
		(layer "F.Cu")
		(net "PVCCP_PVNN_VRHOT#")
	)
	(segment
		(start 113.185956 -6.731)
		(end 112.259872 -6.731)
		(width 0.1143)
		(layer "F.Cu")
		(net "PVCCP_PVNN_VRHOT#")
	)
	(segment
		(start 129.136648 -20.469352)
		(end 129.136648 -15.415514)
		(width 0.1143)
		(layer "F.Cu")
		(net "PVCCP_PVNN_VRHOT#")
	)
	(segment
		(start 132.1308 -25.7937)
		(end 130.860038 -25.7937)
		(width 0.1143)
		(layer "F.Cu")
		(net "PVCCP_PVNN_VRHOT#")
	)
	(segment
		(start 110.03915 -5.51815)
		(end 109.30255 -4.78155)
		(width 0.1143)
		(layer "F.Cu")
		(net "PVCCP_PVNN_VRHOT#")
	)
	(segment
		(start 119.4308 -9.906)
		(end 118.0084 -8.4836)
		(width 0.1143)
		(layer "F.Cu")
		(net "PVCCP_PVNN_VRHOT#")
	)
	(segment
		(start 132.1308 -25.7937)
		(end 132.7277 -25.7937)
		(width 0.1143)
		(layer "F.Cu")
		(net "PVCCP_PVNN_VRHOT#")
	)
	(segment
		(start 136.2456 -29.3116)
		(end 136.2456 -30.353)
		(width 0.1143)
		(layer "F.Cu")
		(net "PVCCP_PVNN_VRHOT#")
	)
	(segment
		(start 14.9352 -44.958)
		(end 16.41475 -46.43755)
		(width 0.1143)
		(layer "F.Cu")
		(net "PVCCP_PVNN_VRHOT#")
	)
	(segment
		(start 14.859 -50.151284)
		(end 14.859 -53.141372)
		(width 0.1143)
		(layer "F.Cu")
		(net "PVCCP_PVNN_VRHOT#")
	)
	(segment
		(start 128.66751 -20.93849)
		(end 129.136648 -20.469352)
		(width 0.1143)
		(layer "F.Cu")
		(net "PVCCP_PVNN_VRHOT#")
	)
	(segment
		(start 16.41475 -46.43755)
		(end 16.41475 -47.69485)
		(width 0.1143)
		(layer "F.Cu")
		(net "PVCCP_PVNN_VRHOT#")
	)
	(segment
		(start 132.7277 -25.7937)
		(end 136.2456 -29.3116)
		(width 0.1143)
		(layer "F.Cu")
		(net "PVCCP_PVNN_VRHOT#")
	)
	(segment
		(start 120.251474 -12.885674)
		(end 119.4308 -12.065)
		(width 0.1143)
		(layer "F.Cu")
		(net "PVCCP_PVNN_VRHOT#")
	)
	(segment
		(start 129.136648 -15.415514)
		(end 128.835912 -15.114778)
		(width 0.1143)
		(layer "F.Cu")
		(net "PVCCP_PVNN_VRHOT#")
	)
	(segment
		(start 108.92155 -4.78155)
		(end 108.458 -4.318)
		(width 0.1143)
		(layer "F.Cu")
		(net "PVCCP_PVNN_VRHOT#")
	)
	(segment
		(start 111.047022 -5.51815)
		(end 110.03915 -5.51815)
		(width 0.1143)
		(layer "F.Cu")
		(net "PVCCP_PVNN_VRHOT#")
	)
	(segment
		(start 180.3146 -35.5346)
		(end 180.3146 -33.6804)
		(width 0.1143)
		(layer "F.Cu")
		(net "PVCCP_PVNN_VRHOT#")
	)
	(segment
		(start 14.859 -53.141372)
		(end 15.4178 -53.700172)
		(width 0.1143)
		(layer "F.Cu")
		(net "PVCCP_PVNN_VRHOT#")
	)
	(segment
		(start 181.102 -32.893)
		(end 182.1942 -32.893)
		(width 0.1143)
		(layer "F.Cu")
		(net "PVCCP_PVNN_VRHOT#")
	)
	(segment
		(start 118.0084 -8.4836)
		(end 114.938556 -8.4836)
		(width 0.1143)
		(layer "F.Cu")
		(net "PVCCP_PVNN_VRHOT#")
	)
	(segment
		(start 126.687834 -15.114778)
		(end 124.45873 -12.885674)
		(width 0.1143)
		(layer "F.Cu")
		(net "PVCCP_PVNN_VRHOT#")
	)
	(segment
		(start 180.3146 -33.6804)
		(end 181.102 -32.893)
		(width 0.1143)
		(layer "F.Cu")
		(net "PVCCP_PVNN_VRHOT#")
	)
	(segment
		(start 112.259872 -6.731)
		(end 111.047022 -5.51815)
		(width 0.1143)
		(layer "F.Cu")
		(net "PVCCP_PVNN_VRHOT#")
	)
	(segment
		(start 124.45873 -12.885674)
		(end 120.251474 -12.885674)
		(width 0.1143)
		(layer "F.Cu")
		(net "PVCCP_PVNN_VRHOT#")
	)
	(segment
		(start 128.835912 -15.114778)
		(end 126.687834 -15.114778)
		(width 0.1143)
		(layer "F.Cu")
		(net "PVCCP_PVNN_VRHOT#")
	)
	(segment
		(start 130.75285 -25.72385)
		(end 128.66751 -23.63851)
		(width 0.1143)
		(layer "F.Cu")
		(net "PVCCP_PVNN_VRHOT#")
	)
	(segment
		(start 130.790188 -25.72385)
		(end 130.75285 -25.72385)
		(width 0.1143)
		(layer "F.Cu")
		(net "PVCCP_PVNN_VRHOT#")
	)
	(segment
		(start 128.66751 -23.63851)
		(end 128.66751 -20.93849)
		(width 0.1143)
		(layer "F.Cu")
		(net "PVCCP_PVNN_VRHOT#")
	)
	(segment
		(start 15.4686 -48.641)
		(end 15.4686 -49.541684)
		(width 0.1143)
		(layer "F.Cu")
		(net "PVCCP_PVNN_VRHOT#")
	)
	(via
		(at 79.2353 -12.9032)
		(size 0.508)
		(drill 0.254)
		(layers "F.Cu" "B.Cu")
		(net "PVCCP_PVNN_VRHOT#")
	)
	(via
		(at 136.2456 -30.353)
		(size 0.508)
		(drill 0.254)
		(layers "F.Cu" "B.Cu")
		(net "PVCCP_PVNN_VRHOT#")
	)
	(via
		(at 180.3146 -35.5346)
		(size 0.508)
		(drill 0.254)
		(layers "F.Cu" "B.Cu")
		(net "PVCCP_PVNN_VRHOT#")
	)
	(via
		(at 108.458 -4.318)
		(size 0.508)
		(drill 0.254)
		(layers "F.Cu" "B.Cu")
		(net "PVCCP_PVNN_VRHOT#")
	)
	(via
		(at 178.562 -35.5346)
		(size 0.7112)
		(drill 0.3556)
		(layers "F.Cu" "B.Cu")
		(net "PVCCP_PVNN_VRHOT#")
	)
	(via
		(at 14.9352 -44.958)
		(size 0.508)
		(drill 0.254)
		(layers "F.Cu" "B.Cu")
		(net "PVCCP_PVNN_VRHOT#")
	)
	(segment
		(start 150.114 -33.909)
		(end 151.550878 -35.345878)
		(width 0.1143)
		(layer "B.Cu")
		(net "PVCCP_PVNN_VRHOT#")
	)
	(segment
		(start 180.3146 -35.5346)
		(end 178.562 -35.5346)
		(width 0.1143)
		(layer "B.Cu")
		(net "PVCCP_PVNN_VRHOT#")
	)
	(segment
		(start 136.2456 -30.799532)
		(end 139.355068 -33.909)
		(width 0.1143)
		(layer "B.Cu")
		(net "PVCCP_PVNN_VRHOT#")
	)
	(segment
		(start 151.550878 -35.345878)
		(end 178.373278 -35.345878)
		(width 0.1143)
		(layer "B.Cu")
		(net "PVCCP_PVNN_VRHOT#")
	)
	(segment
		(start 139.355068 -33.909)
		(end 150.114 -33.909)
		(width 0.1143)
		(layer "B.Cu")
		(net "PVCCP_PVNN_VRHOT#")
	)
	(segment
		(start 136.2456 -30.353)
		(end 136.2456 -30.799532)
		(width 0.1143)
		(layer "B.Cu")
		(net "PVCCP_PVNN_VRHOT#")
	)
	(segment
		(start 178.373278 -35.345878)
		(end 178.562 -35.5346)
		(width 0.1143)
		(layer "B.Cu")
		(net "PVCCP_PVNN_VRHOT#")
	)
	(segment
		(start 29.63545 -33.819592)
		(end 28.75915 -32.943292)
		(width 0.0889)
		(layer "In7.Cu")
		(net "PVCCP_PVNN_VRHOT#")
	)
	(segment
		(start 76.754482 -12.9032)
		(end 79.2353 -12.9032)
		(width 0.0889)
		(layer "In7.Cu")
		(net "PVCCP_PVNN_VRHOT#")
	)
	(segment
		(start 33.3502 -13.9446)
		(end 35.52825 -13.9446)
		(width 0.0889)
		(layer "In7.Cu")
		(net "PVCCP_PVNN_VRHOT#")
	)
	(segment
		(start 23.602696 -42.377106)
		(end 23.602696 -40.310308)
		(width 0.0889)
		(layer "In7.Cu")
		(net "PVCCP_PVNN_VRHOT#")
	)
	(segment
		(start 28.75915 -32.943292)
		(end 28.75915 -19.542252)
		(width 0.0889)
		(layer "In7.Cu")
		(net "PVCCP_PVNN_VRHOT#")
	)
	(segment
		(start 56.5404 -11.0744)
		(end 58.8518 -8.763)
		(width 0.0889)
		(layer "In7.Cu")
		(net "PVCCP_PVNN_VRHOT#")
	)
	(segment
		(start 32.2453 -16.056102)
		(end 32.2453 -15.0495)
		(width 0.0889)
		(layer "In7.Cu")
		(net "PVCCP_PVNN_VRHOT#")
	)
	(segment
		(start 37.94125 -11.5316)
		(end 55.3212 -11.5316)
		(width 0.0889)
		(layer "In7.Cu")
		(net "PVCCP_PVNN_VRHOT#")
	)
	(segment
		(start 23.602696 -40.310308)
		(end 29.63545 -34.277554)
		(width 0.0889)
		(layer "In7.Cu")
		(net "PVCCP_PVNN_VRHOT#")
	)
	(segment
		(start 58.8518 -8.763)
		(end 72.636126 -8.763)
		(width 0.0889)
		(layer "In7.Cu")
		(net "PVCCP_PVNN_VRHOT#")
	)
	(segment
		(start 32.2453 -15.0495)
		(end 33.3502 -13.9446)
		(width 0.0889)
		(layer "In7.Cu")
		(net "PVCCP_PVNN_VRHOT#")
	)
	(segment
		(start 28.75915 -19.542252)
		(end 32.2453 -16.056102)
		(width 0.0889)
		(layer "In7.Cu")
		(net "PVCCP_PVNN_VRHOT#")
	)
	(segment
		(start 55.7784 -11.0744)
		(end 56.5404 -11.0744)
		(width 0.0889)
		(layer "In7.Cu")
		(net "PVCCP_PVNN_VRHOT#")
	)
	(segment
		(start 72.636126 -8.763)
		(end 73.29805 -9.424924)
		(width 0.0889)
		(layer "In7.Cu")
		(net "PVCCP_PVNN_VRHOT#")
	)
	(segment
		(start 22.685502 -43.2943)
		(end 23.602696 -42.377106)
		(width 0.0889)
		(layer "In7.Cu")
		(net "PVCCP_PVNN_VRHOT#")
	)
	(segment
		(start 73.29805 -9.424924)
		(end 73.29805 -9.446768)
		(width 0.0889)
		(layer "In7.Cu")
		(net "PVCCP_PVNN_VRHOT#")
	)
	(segment
		(start 55.3212 -11.5316)
		(end 55.7784 -11.0744)
		(width 0.0889)
		(layer "In7.Cu")
		(net "PVCCP_PVNN_VRHOT#")
	)
	(segment
		(start 16.3957 -43.2943)
		(end 22.685502 -43.2943)
		(width 0.0889)
		(layer "In7.Cu")
		(net "PVCCP_PVNN_VRHOT#")
	)
	(segment
		(start 35.52825 -13.9446)
		(end 37.94125 -11.5316)
		(width 0.0889)
		(layer "In7.Cu")
		(net "PVCCP_PVNN_VRHOT#")
	)
	(segment
		(start 73.29805 -9.446768)
		(end 76.754482 -12.9032)
		(width 0.0889)
		(layer "In7.Cu")
		(net "PVCCP_PVNN_VRHOT#")
	)
	(segment
		(start 14.9352 -44.7548)
		(end 16.3957 -43.2943)
		(width 0.0889)
		(layer "In7.Cu")
		(net "PVCCP_PVNN_VRHOT#")
	)
	(segment
		(start 14.9352 -44.958)
		(end 14.9352 -44.7548)
		(width 0.0889)
		(layer "In7.Cu")
		(net "PVCCP_PVNN_VRHOT#")
	)
	(segment
		(start 29.63545 -34.277554)
		(end 29.63545 -33.819592)
		(width 0.0889)
		(layer "In7.Cu")
		(net "PVCCP_PVNN_VRHOT#")
	)
	(segment
		(start 83.36915 -13.516356)
		(end 82.118962 -13.516356)
		(width 0.0889)
		(layer "In9.Cu")
		(net "PVCCP_PVNN_VRHOT#")
	)
	(segment
		(start 79.6036 -14.575282)
		(end 79.6036 -13.2715)
		(width 0.0889)
		(layer "In9.Cu")
		(net "PVCCP_PVNN_VRHOT#")
	)
	(segment
		(start 80.036162 -15.007844)
		(end 79.6036 -14.575282)
		(width 0.0889)
		(layer "In9.Cu")
		(net "PVCCP_PVNN_VRHOT#")
	)
	(segment
		(start 95.794322 -14.945106)
		(end 95.397066 -14.54785)
		(width 0.0889)
		(layer "In9.Cu")
		(net "PVCCP_PVNN_VRHOT#")
	)
	(segment
		(start 84.203794 -14.351)
		(end 83.36915 -13.516356)
		(width 0.0889)
		(layer "In9.Cu")
		(net "PVCCP_PVNN_VRHOT#")
	)
	(segment
		(start 79.6036 -13.2715)
		(end 79.2353 -12.9032)
		(width 0.0889)
		(layer "In9.Cu")
		(net "PVCCP_PVNN_VRHOT#")
	)
	(segment
		(start 89.916508 -13.709904)
		(end 89.458292 -13.709904)
		(width 0.0889)
		(layer "In9.Cu")
		(net "PVCCP_PVNN_VRHOT#")
	)
	(segment
		(start 81.50479 -14.756892)
		(end 81.253838 -15.007844)
		(width 0.0889)
		(layer "In9.Cu")
		(net "PVCCP_PVNN_VRHOT#")
	)
	(segment
		(start 82.118962 -13.516356)
		(end 81.50479 -14.130528)
		(width 0.0889)
		(layer "In9.Cu")
		(net "PVCCP_PVNN_VRHOT#")
	)
	(segment
		(start 81.50479 -14.130528)
		(end 81.50479 -14.756892)
		(width 0.0889)
		(layer "In9.Cu")
		(net "PVCCP_PVNN_VRHOT#")
	)
	(segment
		(start 88.817196 -14.351)
		(end 84.203794 -14.351)
		(width 0.0889)
		(layer "In9.Cu")
		(net "PVCCP_PVNN_VRHOT#")
	)
	(segment
		(start 90.754454 -14.54785)
		(end 89.916508 -13.709904)
		(width 0.0889)
		(layer "In9.Cu")
		(net "PVCCP_PVNN_VRHOT#")
	)
	(segment
		(start 89.458292 -13.709904)
		(end 88.817196 -14.351)
		(width 0.0889)
		(layer "In9.Cu")
		(net "PVCCP_PVNN_VRHOT#")
	)
	(segment
		(start 95.397066 -14.54785)
		(end 90.754454 -14.54785)
		(width 0.0889)
		(layer "In9.Cu")
		(net "PVCCP_PVNN_VRHOT#")
	)
	(segment
		(start 108.76915 -11.93546)
		(end 105.759504 -14.945106)
		(width 0.0889)
		(layer "In9.Cu")
		(net "PVCCP_PVNN_VRHOT#")
	)
	(segment
		(start 105.759504 -14.945106)
		(end 95.794322 -14.945106)
		(width 0.0889)
		(layer "In9.Cu")
		(net "PVCCP_PVNN_VRHOT#")
	)
	(segment
		(start 108.458 -4.318)
		(end 108.76915 -4.62915)
		(width 0.0889)
		(layer "In9.Cu")
		(net "PVCCP_PVNN_VRHOT#")
	)
	(segment
		(start 81.253838 -15.007844)
		(end 80.036162 -15.007844)
		(width 0.0889)
		(layer "In9.Cu")
		(net "PVCCP_PVNN_VRHOT#")
	)
	(segment
		(start 108.76915 -4.62915)
		(end 108.76915 -11.93546)
		(width 0.0889)
		(layer "In9.Cu")
		(net "PVCCP_PVNN_VRHOT#")
	)
	(segment
		(start 183.2102 -33.9344)
		(end 184.1246 -33.9344)
		(width 0.2032)
		(layer "F.Cu")
		(net "VR_PVDDR_PNN_VRHOT#")
	)
	(segment
		(start 184.785 -33.2486)
		(end 185.499248 -33.2486)
		(width 0.2032)
		(layer "F.Cu")
		(net "VR_PVDDR_PNN_VRHOT#")
	)
	(segment
		(start 184.1246 -33.9344)
		(end 184.1246 -33.909)
		(width 0.2032)
		(layer "F.Cu")
		(net "VR_PVDDR_PNN_VRHOT#")
	)
	(segment
		(start 185.626502 -33.375854)
		(end 186.856116 -33.375854)
		(width 0.2032)
		(layer "F.Cu")
		(net "VR_PVDDR_PNN_VRHOT#")
	)
	(segment
		(start 184.1246 -33.909)
		(end 184.785 -33.2486)
		(width 0.2032)
		(layer "F.Cu")
		(net "VR_PVDDR_PNN_VRHOT#")
	)
	(segment
		(start 185.499248 -33.2486)
		(end 185.626502 -33.375854)
		(width 0.2032)
		(layer "F.Cu")
		(net "VR_PVDDR_PNN_VRHOT#")
	)
	(via
		(at 184.1246 -33.9344)
		(size 0.7112)
		(drill 0.3556)
		(layers "F.Cu" "B.Cu")
		(net "VR_PVDDR_PNN_VRHOT#")
	)
	(segment
		(start 181.44998 -68.19138)
		(end 181.8386 -68.58)
		(width 0.1143)
		(layer "F.Cu")
		(net "M_A_RESET#")
	)
	(segment
		(start 181.44998 -62.59322)
		(end 181.44998 -68.19138)
		(width 0.1143)
		(layer "F.Cu")
		(net "M_A_RESET#")
	)
	(via
		(at 109.2708 -63.0936)
		(size 0.7112)
		(drill 0.3556)
		(layers "F.Cu" "B.Cu")
		(net "M_A_RESET#")
	)
	(via
		(at 181.8386 -68.58)
		(size 0.4318)
		(drill 0.2032)
		(layers "F.Cu" "B.Cu")
		(net "M_A_RESET#")
	)
	(segment
		(start 100.8888 -58.6486)
		(end 100.0252 -57.785)
		(width 0.1143)
		(layer "B.Cu")
		(net "M_A_RESET#")
	)
	(segment
		(start 181.44998 -70.79996)
		(end 181.44998 -72.27824)
		(width 0.1143)
		(layer "B.Cu")
		(net "M_A_RESET#")
	)
	(segment
		(start 108.704126 -63.0936)
		(end 107.39755 -61.787024)
		(width 0.1143)
		(layer "B.Cu")
		(net "M_A_RESET#")
	)
	(segment
		(start 100.584 -51.7398)
		(end 100.0252 -52.2986)
		(width 0.1143)
		(layer "B.Cu")
		(net "M_A_RESET#")
	)
	(segment
		(start 118.61038 -68.510658)
		(end 118.61038 -68.14058)
		(width 0.1143)
		(layer "B.Cu")
		(net "M_A_RESET#")
	)
	(segment
		(start 104.264206 -58.6486)
		(end 100.8888 -58.6486)
		(width 0.1143)
		(layer "B.Cu")
		(net "M_A_RESET#")
	)
	(segment
		(start 118.941342 -68.84162)
		(end 118.61038 -68.510658)
		(width 0.1143)
		(layer "B.Cu")
		(net "M_A_RESET#")
	)
	(segment
		(start 181.44998 -69.788024)
		(end 181.44998 -70.79996)
		(width 0.1143)
		(layer "B.Cu")
		(net "M_A_RESET#")
	)
	(segment
		(start 100.0252 -52.2986)
		(end 100.0252 -57.785)
		(width 0.1143)
		(layer "B.Cu")
		(net "M_A_RESET#")
	)
	(segment
		(start 181.8386 -68.58)
		(end 181.638448 -68.780152)
		(width 0.1143)
		(layer "B.Cu")
		(net "M_A_RESET#")
	)
	(segment
		(start 116.359686 -63.0936)
		(end 109.2708 -63.0936)
		(width 0.1143)
		(layer "B.Cu")
		(net "M_A_RESET#")
	)
	(segment
		(start 119.64162 -68.84162)
		(end 118.941342 -68.84162)
		(width 0.1143)
		(layer "B.Cu")
		(net "M_A_RESET#")
	)
	(segment
		(start 109.2708 -63.0936)
		(end 108.704126 -63.0936)
		(width 0.1143)
		(layer "B.Cu")
		(net "M_A_RESET#")
	)
	(segment
		(start 107.39755 -61.787024)
		(end 107.39755 -61.781944)
		(width 0.1143)
		(layer "B.Cu")
		(net "M_A_RESET#")
	)
	(segment
		(start 117.1194 -66.6496)
		(end 117.1194 -63.853314)
		(width 0.1143)
		(layer "B.Cu")
		(net "M_A_RESET#")
	)
	(segment
		(start 181.44998 -72.27824)
		(end 180.82387 -72.90435)
		(width 0.1143)
		(layer "B.Cu")
		(net "M_A_RESET#")
	)
	(segment
		(start 118.61038 -68.14058)
		(end 117.1194 -66.6496)
		(width 0.1143)
		(layer "B.Cu")
		(net "M_A_RESET#")
	)
	(segment
		(start 123.70435 -72.90435)
		(end 119.64162 -68.84162)
		(width 0.1143)
		(layer "B.Cu")
		(net "M_A_RESET#")
	)
	(segment
		(start 180.82387 -72.90435)
		(end 123.70435 -72.90435)
		(width 0.1143)
		(layer "B.Cu")
		(net "M_A_RESET#")
	)
	(segment
		(start 117.1194 -63.853314)
		(end 116.359686 -63.0936)
		(width 0.1143)
		(layer "B.Cu")
		(net "M_A_RESET#")
	)
	(segment
		(start 181.638448 -68.780152)
		(end 181.638448 -69.599302)
		(width 0.1143)
		(layer "B.Cu")
		(net "M_A_RESET#")
	)
	(segment
		(start 181.638448 -69.599302)
		(end 181.44998 -69.788024)
		(width 0.1143)
		(layer "B.Cu")
		(net "M_A_RESET#")
	)
	(segment
		(start 107.39755 -61.781944)
		(end 104.264206 -58.6486)
		(width 0.1143)
		(layer "B.Cu")
		(net "M_A_RESET#")
	)
	(segment
		(start 100.838 -45.9486)
		(end 100.266754 -45.9486)
		(width 0.1143)
		(layer "F.Cu")
		(net "M_A_R_RESET#")
	)
	(segment
		(start 100.8634 -45.974)
		(end 100.838 -45.9486)
		(width 0.1143)
		(layer "F.Cu")
		(net "M_A_R_RESET#")
	)
	(segment
		(start 100.266754 -45.9486)
		(end 100.053648 -45.735494)
		(width 0.1143)
		(layer "F.Cu")
		(net "M_A_R_RESET#")
	)
	(via
		(at 100.8634 -45.974)
		(size 0.4318)
		(drill 0.2032)
		(layers "F.Cu" "B.Cu")
		(net "M_A_R_RESET#")
	)
	(via
		(at 100.5078 -54.2544)
		(size 0.4318)
		(drill 0.2032)
		(layers "F.Cu" "B.Cu")
		(net "M_A_R_RESET#")
	)
	(via
		(at 101.0412 -56.5404)
		(size 0.7112)
		(drill 0.3556)
		(layers "F.Cu" "B.Cu")
		(net "M_A_R_RESET#")
	)
	(segment
		(start 101.0412 -54.7878)
		(end 100.5078 -54.2544)
		(width 0.1143)
		(layer "B.Cu")
		(net "M_A_R_RESET#")
	)
	(segment
		(start 100.5078 -53.594)
		(end 100.5078 -54.2544)
		(width 0.1143)
		(layer "B.Cu")
		(net "M_A_R_RESET#")
	)
	(segment
		(start 101.0412 -57.6326)
		(end 101.0412 -56.5404)
		(width 0.1143)
		(layer "B.Cu")
		(net "M_A_R_RESET#")
	)
	(segment
		(start 101.0412 -56.5404)
		(end 101.0412 -54.7878)
		(width 0.1143)
		(layer "B.Cu")
		(net "M_A_R_RESET#")
	)
	(segment
		(start 100.8888 -57.785)
		(end 101.0412 -57.6326)
		(width 0.1143)
		(layer "B.Cu")
		(net "M_A_R_RESET#")
	)
	(segment
		(start 100.584 -53.5178)
		(end 100.5078 -53.594)
		(width 0.1143)
		(layer "B.Cu")
		(net "M_A_R_RESET#")
	)
	(segment
		(start 100.8634 -45.974)
		(end 100.8634 -46.1518)
		(width 0.0889)
		(layer "In2.Cu")
		(net "M_A_R_RESET#")
	)
	(segment
		(start 101.314504 -46.602904)
		(end 101.314504 -47.568104)
		(width 0.0889)
		(layer "In2.Cu")
		(net "M_A_R_RESET#")
	)
	(segment
		(start 100.8634 -46.1518)
		(end 101.314504 -46.602904)
		(width 0.0889)
		(layer "In2.Cu")
		(net "M_A_R_RESET#")
	)
	(segment
		(start 101.6254 -51.0286)
		(end 102.108 -51.5112)
		(width 0.0889)
		(layer "In2.Cu")
		(net "M_A_R_RESET#")
	)
	(segment
		(start 101.6254 -47.879)
		(end 101.6254 -51.0286)
		(width 0.0889)
		(layer "In2.Cu")
		(net "M_A_R_RESET#")
	)
	(segment
		(start 101.314504 -47.568104)
		(end 101.6254 -47.879)
		(width 0.0889)
		(layer "In2.Cu")
		(net "M_A_R_RESET#")
	)
	(segment
		(start 101.0158 -53.7464)
		(end 100.5078 -54.2544)
		(width 0.0889)
		(layer "In2.Cu")
		(net "M_A_R_RESET#")
	)
	(segment
		(start 102.108 -53.4162)
		(end 101.7778 -53.7464)
		(width 0.0889)
		(layer "In2.Cu")
		(net "M_A_R_RESET#")
	)
	(segment
		(start 101.7778 -53.7464)
		(end 101.0158 -53.7464)
		(width 0.0889)
		(layer "In2.Cu")
		(net "M_A_R_RESET#")
	)
	(segment
		(start 102.108 -51.5112)
		(end 102.108 -53.4162)
		(width 0.0889)
		(layer "In2.Cu")
		(net "M_A_R_RESET#")
	)
	(segment
		(start 110.602268 -29.619194)
		(end 110.47984 -29.496766)
		(width 0.2413)
		(layer "F.Cu")
		(net "M_B_CAS#")
	)
	(segment
		(start 168.395396 -5.26542)
		(end 168.4528 -5.322824)
		(width 0.2413)
		(layer "F.Cu")
		(net "M_B_CAS#")
	)
	(segment
		(start 167.714422 -3.621278)
		(end 167.714422 -4.0132)
		(width 0.2413)
		(layer "F.Cu")
		(net "M_B_CAS#")
	)
	(segment
		(start 167.94988 -2.777744)
		(end 167.74795 -2.979674)
		(width 0.2413)
		(layer "F.Cu")
		(net "M_B_CAS#")
	)
	(segment
		(start 167.74795 -2.979674)
		(end 167.74795 -3.58775)
		(width 0.2413)
		(layer "F.Cu")
		(net "M_B_CAS#")
	)
	(segment
		(start 167.94988 -1.68402)
		(end 167.94988 -2.777744)
		(width 0.2413)
		(layer "F.Cu")
		(net "M_B_CAS#")
	)
	(segment
		(start 168.395396 -4.694174)
		(end 168.395396 -5.26542)
		(width 0.2413)
		(layer "F.Cu")
		(net "M_B_CAS#")
	)
	(segment
		(start 167.714422 -4.0132)
		(end 168.395396 -4.694174)
		(width 0.2413)
		(layer "F.Cu")
		(net "M_B_CAS#")
	)
	(segment
		(start 110.47984 -29.496766)
		(end 110.47984 -29.090366)
		(width 0.2413)
		(layer "F.Cu")
		(net "M_B_CAS#")
	)
	(segment
		(start 167.74795 -3.58775)
		(end 167.714422 -3.621278)
		(width 0.2413)
		(layer "F.Cu")
		(net "M_B_CAS#")
	)
	(via
		(at 110.47984 -29.090366)
		(size 0.4318)
		(drill 0.2032)
		(layers "F.Cu" "B.Cu")
		(net "M_B_CAS#")
	)
	(via
		(at 168.4528 -5.322824)
		(size 0.4318)
		(drill 0.2032)
		(layers "F.Cu" "B.Cu")
		(net "M_B_CAS#")
	)
	(segment
		(start 167.609012 -8.55599)
		(end 167.609012 -8.222234)
		(width 0.2413)
		(layer "B.Cu")
		(net "M_B_CAS#")
	)
	(segment
		(start 168.389554 -5.322824)
		(end 168.4528 -5.322824)
		(width 0.2413)
		(layer "B.Cu")
		(net "M_B_CAS#")
	)
	(segment
		(start 167.95115 -5.761228)
		(end 168.389554 -5.322824)
		(width 0.2413)
		(layer "B.Cu")
		(net "M_B_CAS#")
	)
	(segment
		(start 167.60825 -8.221472)
		(end 167.60825 -7.374128)
		(width 0.2413)
		(layer "B.Cu")
		(net "M_B_CAS#")
	)
	(segment
		(start 167.60825 -7.374128)
		(end 167.95115 -7.031228)
		(width 0.2413)
		(layer "B.Cu")
		(net "M_B_CAS#")
	)
	(segment
		(start 167.95115 -7.031228)
		(end 167.95115 -5.761228)
		(width 0.2413)
		(layer "B.Cu")
		(net "M_B_CAS#")
	)
	(segment
		(start 167.94988 -9.89076)
		(end 167.94988 -8.896858)
		(width 0.2413)
		(layer "B.Cu")
		(net "M_B_CAS#")
	)
	(segment
		(start 167.94988 -8.896858)
		(end 167.609012 -8.55599)
		(width 0.2413)
		(layer "B.Cu")
		(net "M_B_CAS#")
	)
	(segment
		(start 167.609012 -8.222234)
		(end 167.60825 -8.221472)
		(width 0.2413)
		(layer "B.Cu")
		(net "M_B_CAS#")
	)
	(segment
		(start 168.0591 -13.535406)
		(end 167.8686 -13.344906)
		(width 0.1905)
		(layer "In7.Cu")
		(net "M_B_CAS#")
	)
	(segment
		(start 110.47984 -29.090366)
		(end 112.057434 -29.090366)
		(width 0.1905)
		(layer "In7.Cu")
		(net "M_B_CAS#")
	)
	(segment
		(start 168.7322 -13.725906)
		(end 168.5417 -13.535406)
		(width 0.1905)
		(layer "In7.Cu")
		(net "M_B_CAS#")
	)
	(segment
		(start 168.5417 -11.249406)
		(end 168.7322 -11.058906)
		(width 0.1905)
		(layer "In7.Cu")
		(net "M_B_CAS#")
	)
	(segment
		(start 112.057434 -29.090366)
		(end 112.1918 -28.956)
		(width 0.1905)
		(layer "In7.Cu")
		(net "M_B_CAS#")
	)
	(segment
		(start 169.266362 -8.152638)
		(end 169.266362 -6.04774)
		(width 0.1905)
		(layer "In7.Cu")
		(net "M_B_CAS#")
	)
	(segment
		(start 168.5417 -12.011406)
		(end 168.0591 -12.011406)
		(width 0.1905)
		(layer "In7.Cu")
		(net "M_B_CAS#")
	)
	(segment
		(start 168.0591 -12.011406)
		(end 167.8686 -11.820906)
		(width 0.1905)
		(layer "In7.Cu")
		(net "M_B_CAS#")
	)
	(segment
		(start 168.0591 -12.773406)
		(end 168.5417 -12.773406)
		(width 0.1905)
		(layer "In7.Cu")
		(net "M_B_CAS#")
	)
	(segment
		(start 118.3513 -27.7495)
		(end 155.330906 -27.7495)
		(width 0.1905)
		(layer "In7.Cu")
		(net "M_B_CAS#")
	)
	(segment
		(start 168.7322 -12.201906)
		(end 168.5417 -12.011406)
		(width 0.1905)
		(layer "In7.Cu")
		(net "M_B_CAS#")
	)
	(segment
		(start 155.330906 -27.7495)
		(end 168.7322 -14.348206)
		(width 0.1905)
		(layer "In7.Cu")
		(net "M_B_CAS#")
	)
	(segment
		(start 168.7322 -8.6868)
		(end 169.266362 -8.152638)
		(width 0.1905)
		(layer "In7.Cu")
		(net "M_B_CAS#")
	)
	(segment
		(start 168.0591 -11.249406)
		(end 168.5417 -11.249406)
		(width 0.1905)
		(layer "In7.Cu")
		(net "M_B_CAS#")
	)
	(segment
		(start 168.461944 -5.331968)
		(end 168.4528 -5.322824)
		(width 0.1905)
		(layer "In7.Cu")
		(net "M_B_CAS#")
	)
	(segment
		(start 168.7322 -12.582906)
		(end 168.7322 -12.201906)
		(width 0.1905)
		(layer "In7.Cu")
		(net "M_B_CAS#")
	)
	(segment
		(start 168.7322 -11.058906)
		(end 168.7322 -8.6868)
		(width 0.1905)
		(layer "In7.Cu")
		(net "M_B_CAS#")
	)
	(segment
		(start 167.8686 -12.963906)
		(end 168.0591 -12.773406)
		(width 0.1905)
		(layer "In7.Cu")
		(net "M_B_CAS#")
	)
	(segment
		(start 167.8686 -11.820906)
		(end 167.8686 -11.439906)
		(width 0.1905)
		(layer "In7.Cu")
		(net "M_B_CAS#")
	)
	(segment
		(start 117.1448 -28.956)
		(end 118.3513 -27.7495)
		(width 0.1905)
		(layer "In7.Cu")
		(net "M_B_CAS#")
	)
	(segment
		(start 168.5417 -13.535406)
		(end 168.0591 -13.535406)
		(width 0.1905)
		(layer "In7.Cu")
		(net "M_B_CAS#")
	)
	(segment
		(start 168.55059 -5.331968)
		(end 168.461944 -5.331968)
		(width 0.1905)
		(layer "In7.Cu")
		(net "M_B_CAS#")
	)
	(segment
		(start 168.5417 -12.773406)
		(end 168.7322 -12.582906)
		(width 0.1905)
		(layer "In7.Cu")
		(net "M_B_CAS#")
	)
	(segment
		(start 167.8686 -13.344906)
		(end 167.8686 -12.963906)
		(width 0.1905)
		(layer "In7.Cu")
		(net "M_B_CAS#")
	)
	(segment
		(start 168.7322 -14.348206)
		(end 168.7322 -13.725906)
		(width 0.1905)
		(layer "In7.Cu")
		(net "M_B_CAS#")
	)
	(segment
		(start 112.1918 -28.956)
		(end 117.1448 -28.956)
		(width 0.1905)
		(layer "In7.Cu")
		(net "M_B_CAS#")
	)
	(segment
		(start 169.266362 -6.04774)
		(end 168.55059 -5.331968)
		(width 0.1905)
		(layer "In7.Cu")
		(net "M_B_CAS#")
	)
	(segment
		(start 167.8686 -11.439906)
		(end 168.0591 -11.249406)
		(width 0.1905)
		(layer "In7.Cu")
		(net "M_B_CAS#")
	)
	(segment
		(start 166.2938 -8.485378)
		(end 166.2938 -7.302754)
		(width 0.2413)
		(layer "F.Cu")
		(net "M_B_RAS#")
	)
	(segment
		(start 166.651432 -8.74141)
		(end 166.549832 -8.74141)
		(width 0.2413)
		(layer "F.Cu")
		(net "M_B_RAS#")
	)
	(segment
		(start 167.049958 -9.139936)
		(end 166.651432 -8.74141)
		(width 0.2413)
		(layer "F.Cu")
		(net "M_B_RAS#")
	)
	(segment
		(start 166.99865 -5.6388)
		(end 167.437054 -5.200396)
		(width 0.2413)
		(layer "F.Cu")
		(net "M_B_RAS#")
	)
	(segment
		(start 167.049958 -9.897364)
		(end 167.049958 -9.139936)
		(width 0.2413)
		(layer "F.Cu")
		(net "M_B_RAS#")
	)
	(segment
		(start 166.99865 -6.597904)
		(end 166.99865 -5.6388)
		(width 0.2413)
		(layer "F.Cu")
		(net "M_B_RAS#")
	)
	(segment
		(start 108.160312 -31.023814)
		(end 108.433108 -31.023814)
		(width 0.1016)
		(layer "F.Cu")
		(net "M_B_RAS#")
	)
	(segment
		(start 107.9246 -30.788102)
		(end 108.160312 -31.023814)
		(width 0.1016)
		(layer "F.Cu")
		(net "M_B_RAS#")
	)
	(segment
		(start 166.2938 -7.302754)
		(end 166.99865 -6.597904)
		(width 0.2413)
		(layer "F.Cu")
		(net "M_B_RAS#")
	)
	(segment
		(start 166.549832 -8.74141)
		(end 166.2938 -8.485378)
		(width 0.2413)
		(layer "F.Cu")
		(net "M_B_RAS#")
	)
	(segment
		(start 167.437054 -5.200396)
		(end 167.4876 -5.200396)
		(width 0.2413)
		(layer "F.Cu")
		(net "M_B_RAS#")
	)
	(via
		(at 107.9246 -30.788102)
		(size 0.4318)
		(drill 0.2032)
		(layers "F.Cu" "B.Cu")
		(net "M_B_RAS#")
	)
	(via
		(at 167.4876 -5.200396)
		(size 0.4318)
		(drill 0.2032)
		(layers "F.Cu" "B.Cu")
		(net "M_B_RAS#")
	)
	(segment
		(start 167.479218 -5.200396)
		(end 167.4876 -5.200396)
		(width 0.2413)
		(layer "B.Cu")
		(net "M_B_RAS#")
	)
	(segment
		(start 166.604188 -4.325366)
		(end 167.479218 -5.200396)
		(width 0.2413)
		(layer "B.Cu")
		(net "M_B_RAS#")
	)
	(segment
		(start 167.049958 -2.52222)
		(end 166.604188 -2.96799)
		(width 0.2413)
		(layer "B.Cu")
		(net "M_B_RAS#")
	)
	(segment
		(start 167.049958 -1.690624)
		(end 167.049958 -2.52222)
		(width 0.2413)
		(layer "B.Cu")
		(net "M_B_RAS#")
	)
	(segment
		(start 166.604188 -2.96799)
		(end 166.604188 -4.325366)
		(width 0.2413)
		(layer "B.Cu")
		(net "M_B_RAS#")
	)
	(segment
		(start 169.374058 -8.857742)
		(end 169.6466 -8.5852)
		(width 0.1905)
		(layer "In7.Cu")
		(net "M_B_RAS#")
	)
	(segment
		(start 118.62689 -28.3718)
		(end 155.073096 -28.3718)
		(width 0.1905)
		(layer "In7.Cu")
		(net "M_B_RAS#")
	)
	(segment
		(start 110.7186 -30.1244)
		(end 111.9886 -30.1244)
		(width 0.1016)
		(layer "In7.Cu")
		(net "M_B_RAS#")
	)
	(segment
		(start 155.073096 -28.3718)
		(end 155.07335 -28.372054)
		(width 0.1905)
		(layer "In7.Cu")
		(net "M_B_RAS#")
	)
	(segment
		(start 108.073698 -30.9372)
		(end 109.9058 -30.9372)
		(width 0.1016)
		(layer "In7.Cu")
		(net "M_B_RAS#")
	)
	(segment
		(start 169.374058 -14.586458)
		(end 169.374058 -8.857742)
		(width 0.1905)
		(layer "In7.Cu")
		(net "M_B_RAS#")
	)
	(segment
		(start 169.6466 -8.5852)
		(end 169.6466 -5.742178)
		(width 0.1905)
		(layer "In7.Cu")
		(net "M_B_RAS#")
	)
	(segment
		(start 169.6466 -5.742178)
		(end 168.789096 -4.884674)
		(width 0.1905)
		(layer "In7.Cu")
		(net "M_B_RAS#")
	)
	(segment
		(start 155.588462 -28.372054)
		(end 169.374058 -14.586458)
		(width 0.1905)
		(layer "In7.Cu")
		(net "M_B_RAS#")
	)
	(segment
		(start 107.9246 -30.788102)
		(end 108.073698 -30.9372)
		(width 0.1016)
		(layer "In7.Cu")
		(net "M_B_RAS#")
	)
	(segment
		(start 112.7506 -29.3624)
		(end 117.63629 -29.3624)
		(width 0.1905)
		(layer "In7.Cu")
		(net "M_B_RAS#")
	)
	(segment
		(start 168.789096 -4.884674)
		(end 167.777922 -4.884674)
		(width 0.1905)
		(layer "In7.Cu")
		(net "M_B_RAS#")
	)
	(segment
		(start 109.9058 -30.9372)
		(end 110.7186 -30.1244)
		(width 0.1016)
		(layer "In7.Cu")
		(net "M_B_RAS#")
	)
	(segment
		(start 167.4876 -5.174996)
		(end 167.4876 -5.200396)
		(width 0.1905)
		(layer "In7.Cu")
		(net "M_B_RAS#")
	)
	(segment
		(start 155.07335 -28.372054)
		(end 155.588462 -28.372054)
		(width 0.1905)
		(layer "In7.Cu")
		(net "M_B_RAS#")
	)
	(segment
		(start 111.9886 -30.1244)
		(end 112.268 -29.845)
		(width 0.1016)
		(layer "In7.Cu")
		(net "M_B_RAS#")
	)
	(segment
		(start 112.268 -29.845)
		(end 112.7506 -29.3624)
		(width 0.1905)
		(layer "In7.Cu")
		(net "M_B_RAS#")
	)
	(segment
		(start 167.777922 -4.884674)
		(end 167.4876 -5.174996)
		(width 0.1905)
		(layer "In7.Cu")
		(net "M_B_RAS#")
	)
	(segment
		(start 117.63629 -29.3624)
		(end 118.62689 -28.3718)
		(width 0.1905)
		(layer "In7.Cu")
		(net "M_B_RAS#")
	)
	(segment
		(start 108.807758 -31.337504)
		(end 109.195108 -31.724854)
		(width 0.1016)
		(layer "F.Cu")
		(net "M_B_WE#")
	)
	(segment
		(start 167.98925 -5.03682)
		(end 167.98925 -6.078728)
		(width 0.2413)
		(layer "F.Cu")
		(net "M_B_WE#")
	)
	(segment
		(start 167.98925 -6.078728)
		(end 167.4876 -6.580378)
		(width 0.2413)
		(layer "F.Cu")
		(net "M_B_WE#")
	)
	(segment
		(start 108.807758 -30.550358)
		(end 108.807758 -31.337504)
		(width 0.1016)
		(layer "F.Cu")
		(net "M_B_WE#")
	)
	(segment
		(start 108.7374 -30.48)
		(end 108.807758 -30.550358)
		(width 0.1016)
		(layer "F.Cu")
		(net "M_B_WE#")
	)
	(segment
		(start 166.604188 -3.651758)
		(end 167.98925 -5.03682)
		(width 0.2413)
		(layer "F.Cu")
		(net "M_B_WE#")
	)
	(segment
		(start 166.604188 -2.717038)
		(end 166.604188 -3.651758)
		(width 0.2413)
		(layer "F.Cu")
		(net "M_B_WE#")
	)
	(segment
		(start 166.749984 -2.571242)
		(end 166.604188 -2.717038)
		(width 0.2413)
		(layer "F.Cu")
		(net "M_B_WE#")
	)
	(segment
		(start 166.749984 -1.68402)
		(end 166.749984 -2.571242)
		(width 0.2413)
		(layer "F.Cu")
		(net "M_B_WE#")
	)
	(via
		(at 108.7374 -30.48)
		(size 0.4318)
		(drill 0.2032)
		(layers "F.Cu" "B.Cu")
		(net "M_B_WE#")
	)
	(via
		(at 167.4876 -6.580378)
		(size 0.4318)
		(drill 0.2032)
		(layers "F.Cu" "B.Cu")
		(net "M_B_WE#")
	)
	(segment
		(start 166.492936 -8.759698)
		(end 166.492936 -7.753096)
		(width 0.2413)
		(layer "B.Cu")
		(net "M_B_WE#")
	)
	(segment
		(start 166.749984 -9.016746)
		(end 166.492936 -8.759698)
		(width 0.2413)
		(layer "B.Cu")
		(net "M_B_WE#")
	)
	(segment
		(start 166.492936 -7.753096)
		(end 167.4876 -6.758432)
		(width 0.2413)
		(layer "B.Cu")
		(net "M_B_WE#")
	)
	(segment
		(start 166.749984 -9.89076)
		(end 166.749984 -9.016746)
		(width 0.2413)
		(layer "B.Cu")
		(net "M_B_WE#")
	)
	(segment
		(start 167.4876 -6.758432)
		(end 167.4876 -6.580378)
		(width 0.2413)
		(layer "B.Cu")
		(net "M_B_WE#")
	)
	(segment
		(start 159.26308 -21.309076)
		(end 159.502094 -21.54809)
		(width 0.1905)
		(layer "In7.Cu")
		(net "M_B_WE#")
	)
	(segment
		(start 109.1184 -29.8958)
		(end 109.1184 -29.284168)
		(width 0.1016)
		(layer "In7.Cu")
		(net "M_B_WE#")
	)
	(segment
		(start 161.927286 -19.392138)
		(end 165.4048 -15.914624)
		(width 0.1905)
		(layer "In7.Cu")
		(net "M_B_WE#")
	)
	(segment
		(start 116.139214 -28.16733)
		(end 117.801644 -26.5049)
		(width 0.1905)
		(layer "In7.Cu")
		(net "M_B_WE#")
	)
	(segment
		(start 159.771334 -21.54809)
		(end 160.041082 -21.278342)
		(width 0.1905)
		(layer "In7.Cu")
		(net "M_B_WE#")
	)
	(segment
		(start 161.119058 -20.200366)
		(end 161.119058 -19.931126)
		(width 0.1905)
		(layer "In7.Cu")
		(net "M_B_WE#")
	)
	(segment
		(start 167.343074 -6.580378)
		(end 167.4876 -6.580378)
		(width 0.1905)
		(layer "In7.Cu")
		(net "M_B_WE#")
	)
	(segment
		(start 159.502094 -21.54809)
		(end 159.771334 -21.54809)
		(width 0.1905)
		(layer "In7.Cu")
		(net "M_B_WE#")
	)
	(segment
		(start 153.798016 -26.5049)
		(end 158.99384 -21.309076)
		(width 0.1905)
		(layer "In7.Cu")
		(net "M_B_WE#")
	)
	(segment
		(start 109.1184 -29.284168)
		(end 109.409484 -28.993084)
		(width 0.1016)
		(layer "In7.Cu")
		(net "M_B_WE#")
	)
	(segment
		(start 108.7374 -30.2768)
		(end 109.1184 -29.8958)
		(width 0.1016)
		(layer "In7.Cu")
		(net "M_B_WE#")
	)
	(segment
		(start 109.409484 -28.993084)
		(end 109.740446 -28.993084)
		(width 0.1016)
		(layer "In7.Cu")
		(net "M_B_WE#")
	)
	(segment
		(start 160.041082 -21.278342)
		(end 160.041082 -21.009102)
		(width 0.1905)
		(layer "In7.Cu")
		(net "M_B_WE#")
	)
	(segment
		(start 110.5662 -28.16733)
		(end 111.75873 -28.16733)
		(width 0.1016)
		(layer "In7.Cu")
		(net "M_B_WE#")
	)
	(segment
		(start 159.802068 -20.770088)
		(end 159.802068 -20.500848)
		(width 0.1905)
		(layer "In7.Cu")
		(net "M_B_WE#")
	)
	(segment
		(start 165.4048 -15.914624)
		(end 165.4048 -10.745978)
		(width 0.1905)
		(layer "In7.Cu")
		(net "M_B_WE#")
	)
	(segment
		(start 108.7374 -30.48)
		(end 108.7374 -30.2768)
		(width 0.1016)
		(layer "In7.Cu")
		(net "M_B_WE#")
	)
	(segment
		(start 161.419032 -19.153124)
		(end 161.658046 -19.392138)
		(width 0.1905)
		(layer "In7.Cu")
		(net "M_B_WE#")
	)
	(segment
		(start 161.658046 -19.392138)
		(end 161.927286 -19.392138)
		(width 0.1905)
		(layer "In7.Cu")
		(net "M_B_WE#")
	)
	(segment
		(start 161.149792 -19.153124)
		(end 161.419032 -19.153124)
		(width 0.1905)
		(layer "In7.Cu")
		(net "M_B_WE#")
	)
	(segment
		(start 160.880044 -19.692112)
		(end 160.880044 -19.422872)
		(width 0.1905)
		(layer "In7.Cu")
		(net "M_B_WE#")
	)
	(segment
		(start 160.880044 -19.422872)
		(end 161.149792 -19.153124)
		(width 0.1905)
		(layer "In7.Cu")
		(net "M_B_WE#")
	)
	(segment
		(start 166.624 -7.299452)
		(end 167.343074 -6.580378)
		(width 0.1905)
		(layer "In7.Cu")
		(net "M_B_WE#")
	)
	(segment
		(start 160.041082 -21.009102)
		(end 159.802068 -20.770088)
		(width 0.1905)
		(layer "In7.Cu")
		(net "M_B_WE#")
	)
	(segment
		(start 166.624 -9.526778)
		(end 166.624 -7.299452)
		(width 0.1905)
		(layer "In7.Cu")
		(net "M_B_WE#")
	)
	(segment
		(start 165.4048 -10.745978)
		(end 166.624 -9.526778)
		(width 0.1905)
		(layer "In7.Cu")
		(net "M_B_WE#")
	)
	(segment
		(start 117.801644 -26.5049)
		(end 153.798016 -26.5049)
		(width 0.1905)
		(layer "In7.Cu")
		(net "M_B_WE#")
	)
	(segment
		(start 111.75873 -28.16733)
		(end 116.139214 -28.16733)
		(width 0.1905)
		(layer "In7.Cu")
		(net "M_B_WE#")
	)
	(segment
		(start 160.071816 -20.2311)
		(end 160.341056 -20.2311)
		(width 0.1905)
		(layer "In7.Cu")
		(net "M_B_WE#")
	)
	(segment
		(start 159.802068 -20.500848)
		(end 160.071816 -20.2311)
		(width 0.1905)
		(layer "In7.Cu")
		(net "M_B_WE#")
	)
	(segment
		(start 158.99384 -21.309076)
		(end 159.26308 -21.309076)
		(width 0.1905)
		(layer "In7.Cu")
		(net "M_B_WE#")
	)
	(segment
		(start 160.341056 -20.2311)
		(end 160.58007 -20.470114)
		(width 0.1905)
		(layer "In7.Cu")
		(net "M_B_WE#")
	)
	(segment
		(start 161.119058 -19.931126)
		(end 160.880044 -19.692112)
		(width 0.1905)
		(layer "In7.Cu")
		(net "M_B_WE#")
	)
	(segment
		(start 109.740446 -28.993084)
		(end 110.5662 -28.16733)
		(width 0.1016)
		(layer "In7.Cu")
		(net "M_B_WE#")
	)
	(segment
		(start 160.84931 -20.470114)
		(end 161.119058 -20.200366)
		(width 0.1905)
		(layer "In7.Cu")
		(net "M_B_WE#")
	)
	(segment
		(start 160.58007 -20.470114)
		(end 160.84931 -20.470114)
		(width 0.1905)
		(layer "In7.Cu")
		(net "M_B_WE#")
	)
	(segment
		(start 106.3244 -20.701)
		(end 106.3244 -20.2438)
		(width 0.1143)
		(layer "F.Cu")
		(net "M_B_R_RESET#")
	)
	(segment
		(start 106.3244 -21.59)
		(end 107.9754 -23.241)
		(width 0.1143)
		(layer "F.Cu")
		(net "M_B_R_RESET#")
	)
	(segment
		(start 106.824018 -29.431234)
		(end 107.225338 -29.832554)
		(width 0.1143)
		(layer "F.Cu")
		(net "M_B_R_RESET#")
	)
	(segment
		(start 106.3244 -20.2438)
		(end 106.6292 -19.939)
		(width 0.1143)
		(layer "F.Cu")
		(net "M_B_R_RESET#")
	)
	(segment
		(start 107.9754 -23.241)
		(end 107.9754 -25.454102)
		(width 0.1143)
		(layer "F.Cu")
		(net "M_B_R_RESET#")
	)
	(segment
		(start 107.442 -28.543504)
		(end 107.392216 -28.543504)
		(width 0.1143)
		(layer "F.Cu")
		(net "M_B_R_RESET#")
	)
	(segment
		(start 107.984798 -26.439622)
		(end 107.984798 -26.785062)
		(width 0.1143)
		(layer "F.Cu")
		(net "M_B_R_RESET#")
	)
	(segment
		(start 107.225338 -30.9626)
		(end 106.909108 -31.27883)
		(width 0.1143)
		(layer "F.Cu")
		(net "M_B_R_RESET#")
	)
	(segment
		(start 106.3244 -21.59)
		(end 106.3244 -20.701)
		(width 0.1143)
		(layer "F.Cu")
		(net "M_B_R_RESET#")
	)
	(segment
		(start 107.941618 -27.086306)
		(end 107.954318 -27.099006)
		(width 0.1143)
		(layer "F.Cu")
		(net "M_B_R_RESET#")
	)
	(segment
		(start 108.309918 -26.114502)
		(end 107.984798 -26.439622)
		(width 0.1143)
		(layer "F.Cu")
		(net "M_B_R_RESET#")
	)
	(segment
		(start 107.933998 -27.991562)
		(end 107.933998 -28.051506)
		(width 0.1143)
		(layer "F.Cu")
		(net "M_B_R_RESET#")
	)
	(segment
		(start 107.941618 -26.828242)
		(end 107.941618 -27.086306)
		(width 0.1143)
		(layer "F.Cu")
		(net "M_B_R_RESET#")
	)
	(segment
		(start 107.9754 -25.454102)
		(end 108.309918 -25.78862)
		(width 0.1143)
		(layer "F.Cu")
		(net "M_B_R_RESET#")
	)
	(segment
		(start 107.954318 -27.099006)
		(end 107.954318 -27.971242)
		(width 0.1143)
		(layer "F.Cu")
		(net "M_B_R_RESET#")
	)
	(segment
		(start 107.954318 -27.971242)
		(end 107.933998 -27.991562)
		(width 0.1143)
		(layer "F.Cu")
		(net "M_B_R_RESET#")
	)
	(segment
		(start 107.933998 -28.051506)
		(end 107.442 -28.543504)
		(width 0.1143)
		(layer "F.Cu")
		(net "M_B_R_RESET#")
	)
	(segment
		(start 106.909108 -31.27883)
		(end 106.909108 -31.724854)
		(width 0.1143)
		(layer "F.Cu")
		(net "M_B_R_RESET#")
	)
	(segment
		(start 106.824018 -29.111702)
		(end 106.824018 -29.431234)
		(width 0.1143)
		(layer "F.Cu")
		(net "M_B_R_RESET#")
	)
	(segment
		(start 107.984798 -26.785062)
		(end 107.941618 -26.828242)
		(width 0.1143)
		(layer "F.Cu")
		(net "M_B_R_RESET#")
	)
	(segment
		(start 107.392216 -28.543504)
		(end 106.824018 -29.111702)
		(width 0.1143)
		(layer "F.Cu")
		(net "M_B_R_RESET#")
	)
	(segment
		(start 107.225338 -29.832554)
		(end 107.225338 -30.9626)
		(width 0.1143)
		(layer "F.Cu")
		(net "M_B_R_RESET#")
	)
	(segment
		(start 108.309918 -25.78862)
		(end 108.309918 -26.114502)
		(width 0.1143)
		(layer "F.Cu")
		(net "M_B_R_RESET#")
	)
	(via
		(at 106.3244 -21.59)
		(size 0.7112)
		(drill 0.3556)
		(layers "F.Cu" "B.Cu")
		(net "M_B_R_RESET#")
	)
	(segment
		(start 109.1692 -23.749)
		(end 109.1692 -22.0472)
		(width 0.1143)
		(layer "F.Cu")
		(net "M_B_RESET#")
	)
	(segment
		(start 108.0008 -20.701)
		(end 107.4928 -20.193)
		(width 0.1143)
		(layer "F.Cu")
		(net "M_B_RESET#")
	)
	(segment
		(start 108.0008 -20.8788)
		(end 108.0008 -20.701)
		(width 0.1143)
		(layer "F.Cu")
		(net "M_B_RESET#")
	)
	(segment
		(start 107.4928 -20.193)
		(end 107.4928 -19.939)
		(width 0.1143)
		(layer "F.Cu")
		(net "M_B_RESET#")
	)
	(segment
		(start 137.050018 -9.897364)
		(end 137.050018 -4.182618)
		(width 0.1143)
		(layer "F.Cu")
		(net "M_B_RESET#")
	)
	(segment
		(start 109.093 -23.8252)
		(end 109.1692 -23.749)
		(width 0.1143)
		(layer "F.Cu")
		(net "M_B_RESET#")
	)
	(segment
		(start 137.050018 -4.182618)
		(end 136.7282 -3.8608)
		(width 0.1143)
		(layer "F.Cu")
		(net "M_B_RESET#")
	)
	(segment
		(start 109.1692 -22.0472)
		(end 108.0008 -20.8788)
		(width 0.1143)
		(layer "F.Cu")
		(net "M_B_RESET#")
	)
	(via
		(at 127.635 -1.5748)
		(size 0.5588)
		(drill 0.3048)
		(layers "F.Cu" "B.Cu")
		(net "M_B_RESET#")
	)
	(via
		(at 136.7282 -3.8608)
		(size 0.5588)
		(drill 0.3048)
		(layers "F.Cu" "B.Cu")
		(net "M_B_RESET#")
	)
	(via
		(at 119.953024 -7.493)
		(size 0.7112)
		(drill 0.3556)
		(layers "F.Cu" "B.Cu")
		(net "M_B_RESET#")
	)
	(via
		(at 109.093 -23.8252)
		(size 0.4318)
		(drill 0.2032)
		(layers "F.Cu" "B.Cu")
		(net "M_B_RESET#")
	)
	(via
		(at 126.619 -22.60473)
		(size 0.508)
		(drill 0.254)
		(layers "F.Cu" "B.Cu")
		(net "M_B_RESET#")
	)
	(segment
		(start 127.635 -1.5748)
		(end 119.833136 -1.5748)
		(width 0.1143)
		(layer "B.Cu")
		(net "M_B_RESET#")
	)
	(segment
		(start 126.430532 -22.416262)
		(end 120.714262 -22.416262)
		(width 0.1143)
		(layer "B.Cu")
		(net "M_B_RESET#")
	)
	(segment
		(start 119.39905 -2.94005)
		(end 120.523 -4.064)
		(width 0.1143)
		(layer "B.Cu")
		(net "M_B_RESET#")
	)
	(segment
		(start 136.7282 -3.8608)
		(end 137.042906 -3.546094)
		(width 0.1143)
		(layer "B.Cu")
		(net "M_B_RESET#")
	)
	(segment
		(start 137.042906 -1.697736)
		(end 137.050018 -1.690624)
		(width 0.1143)
		(layer "B.Cu")
		(net "M_B_RESET#")
	)
	(segment
		(start 119.953024 -21.655024)
		(end 119.953024 -7.493)
		(width 0.1143)
		(layer "B.Cu")
		(net "M_B_RESET#")
	)
	(segment
		(start 137.042906 -3.546094)
		(end 137.042906 -1.697736)
		(width 0.1143)
		(layer "B.Cu")
		(net "M_B_RESET#")
	)
	(segment
		(start 120.523 -6.923024)
		(end 119.953024 -7.493)
		(width 0.1143)
		(layer "B.Cu")
		(net "M_B_RESET#")
	)
	(segment
		(start 119.39905 -2.008886)
		(end 119.39905 -2.94005)
		(width 0.1143)
		(layer "B.Cu")
		(net "M_B_RESET#")
	)
	(segment
		(start 120.714262 -22.416262)
		(end 119.953024 -21.655024)
		(width 0.1143)
		(layer "B.Cu")
		(net "M_B_RESET#")
	)
	(segment
		(start 119.833136 -1.5748)
		(end 119.39905 -2.008886)
		(width 0.1143)
		(layer "B.Cu")
		(net "M_B_RESET#")
	)
	(segment
		(start 120.523 -4.064)
		(end 120.523 -6.923024)
		(width 0.1143)
		(layer "B.Cu")
		(net "M_B_RESET#")
	)
	(segment
		(start 126.619 -22.60473)
		(end 126.430532 -22.416262)
		(width 0.1143)
		(layer "B.Cu")
		(net "M_B_RESET#")
	)
	(segment
		(start 123.429268 -25.794462)
		(end 126.619 -22.60473)
		(width 0.0889)
		(layer "In2.Cu")
		(net "M_B_RESET#")
	)
	(segment
		(start 109.093 -24.796242)
		(end 110.09122 -25.794462)
		(width 0.0889)
		(layer "In2.Cu")
		(net "M_B_RESET#")
	)
	(segment
		(start 136.7282 -3.8608)
		(end 134.4422 -1.5748)
		(width 0.0889)
		(layer "In2.Cu")
		(net "M_B_RESET#")
	)
	(segment
		(start 110.09122 -25.794462)
		(end 123.429268 -25.794462)
		(width 0.0889)
		(layer "In2.Cu")
		(net "M_B_RESET#")
	)
	(segment
		(start 134.4422 -1.5748)
		(end 127.635 -1.5748)
		(width 0.0889)
		(layer "In2.Cu")
		(net "M_B_RESET#")
	)
	(segment
		(start 109.093 -23.8252)
		(end 109.093 -24.796242)
		(width 0.0889)
		(layer "In2.Cu")
		(net "M_B_RESET#")
	)
	(segment
		(start 101.338888 -46.878494)
		(end 101.665278 -47.204884)
		(width 0.1016)
		(layer "F.Cu")
		(net "M_A_WE#")
	)
	(segment
		(start 150.510748 -67.579748)
		(end 150.510748 -66.541396)
		(width 0.2413)
		(layer "F.Cu")
		(net "M_A_WE#")
	)
	(segment
		(start 151.750014 -70.806564)
		(end 151.750014 -68.311014)
		(width 0.2413)
		(layer "F.Cu")
		(net "M_A_WE#")
	)
	(segment
		(start 151.750014 -68.311014)
		(end 151.3586 -67.9196)
		(width 0.2413)
		(layer "F.Cu")
		(net "M_A_WE#")
	)
	(segment
		(start 151.3586 -67.9196)
		(end 150.8506 -67.9196)
		(width 0.2413)
		(layer "F.Cu")
		(net "M_A_WE#")
	)
	(segment
		(start 150.8506 -67.9196)
		(end 150.510748 -67.579748)
		(width 0.2413)
		(layer "F.Cu")
		(net "M_A_WE#")
	)
	(segment
		(start 101.665278 -47.25797)
		(end 101.676454 -47.269146)
		(width 0.1016)
		(layer "F.Cu")
		(net "M_A_WE#")
	)
	(segment
		(start 150.510748 -66.541396)
		(end 151.012144 -66.04)
		(width 0.2413)
		(layer "F.Cu")
		(net "M_A_WE#")
	)
	(segment
		(start 101.665278 -47.204884)
		(end 101.665278 -47.25797)
		(width 0.1016)
		(layer "F.Cu")
		(net "M_A_WE#")
	)
	(segment
		(start 151.012144 -66.04)
		(end 151.0284 -66.04)
		(width 0.2413)
		(layer "F.Cu")
		(net "M_A_WE#")
	)
	(via
		(at 101.676454 -47.269146)
		(size 0.4318)
		(drill 0.2032)
		(layers "F.Cu" "B.Cu")
		(net "M_A_WE#")
	)
	(via
		(at 151.0284 -66.04)
		(size 0.4318)
		(drill 0.2032)
		(layers "F.Cu" "B.Cu")
		(net "M_A_WE#")
	)
	(segment
		(start 151.750014 -64.805052)
		(end 151.0284 -65.526666)
		(width 0.2413)
		(layer "B.Cu")
		(net "M_A_WE#")
	)
	(segment
		(start 151.0284 -65.526666)
		(end 151.0284 -66.04)
		(width 0.2413)
		(layer "B.Cu")
		(net "M_A_WE#")
	)
	(segment
		(start 151.750014 -62.599824)
		(end 151.750014 -64.805052)
		(width 0.2413)
		(layer "B.Cu")
		(net "M_A_WE#")
	)
	(segment
		(start 103.251 -49.5554)
		(end 102.9208 -49.5554)
		(width 0.1016)
		(layer "In9.Cu")
		(net "M_A_WE#")
	)
	(segment
		(start 149.958044 -61.979302)
		(end 148.240242 -60.2615)
		(width 0.1905)
		(layer "In9.Cu")
		(net "M_A_WE#")
	)
	(segment
		(start 104.7623 -51.0667)
		(end 103.251 -49.5554)
		(width 0.1016)
		(layer "In9.Cu")
		(net "M_A_WE#")
	)
	(segment
		(start 141.820138 -59.497214)
		(end 141.466824 -59.1439)
		(width 0.1905)
		(layer "In9.Cu")
		(net "M_A_WE#")
	)
	(segment
		(start 148.240242 -60.2615)
		(end 145.66519 -60.2615)
		(width 0.1905)
		(layer "In9.Cu")
		(net "M_A_WE#")
	)
	(segment
		(start 145.66519 -60.2615)
		(end 144.900904 -59.497214)
		(width 0.1905)
		(layer "In9.Cu")
		(net "M_A_WE#")
	)
	(segment
		(start 121.36374 -58.36285)
		(end 119.38635 -58.36285)
		(width 0.1905)
		(layer "In9.Cu")
		(net "M_A_WE#")
	)
	(segment
		(start 102.489 -49.9872)
		(end 101.9048 -49.9872)
		(width 0.1016)
		(layer "In9.Cu")
		(net "M_A_WE#")
	)
	(segment
		(start 101.676454 -49.758854)
		(end 101.676454 -47.269146)
		(width 0.1016)
		(layer "In9.Cu")
		(net "M_A_WE#")
	)
	(segment
		(start 106.1212 -54.483)
		(end 104.7623 -53.1241)
		(width 0.1016)
		(layer "In9.Cu")
		(net "M_A_WE#")
	)
	(segment
		(start 149.958044 -62.607444)
		(end 149.958044 -61.979302)
		(width 0.1905)
		(layer "In9.Cu")
		(net "M_A_WE#")
	)
	(segment
		(start 144.900904 -59.497214)
		(end 141.820138 -59.497214)
		(width 0.1905)
		(layer "In9.Cu")
		(net "M_A_WE#")
	)
	(segment
		(start 151.0284 -66.04)
		(end 151.0284 -65.8622)
		(width 0.1905)
		(layer "In9.Cu")
		(net "M_A_WE#")
	)
	(segment
		(start 150.818342 -62.8396)
		(end 150.1902 -62.8396)
		(width 0.1905)
		(layer "In9.Cu")
		(net "M_A_WE#")
	)
	(segment
		(start 129.20599 -59.0423)
		(end 122.04319 -59.0423)
		(width 0.1905)
		(layer "In9.Cu")
		(net "M_A_WE#")
	)
	(segment
		(start 106.7943 -58.6359)
		(end 106.1212 -57.9628)
		(width 0.1905)
		(layer "In9.Cu")
		(net "M_A_WE#")
	)
	(segment
		(start 151.384 -65.5066)
		(end 151.384 -63.405258)
		(width 0.1905)
		(layer "In9.Cu")
		(net "M_A_WE#")
	)
	(segment
		(start 150.1902 -62.8396)
		(end 149.958044 -62.607444)
		(width 0.1905)
		(layer "In9.Cu")
		(net "M_A_WE#")
	)
	(segment
		(start 132.406644 -58.43905)
		(end 129.80924 -58.43905)
		(width 0.1905)
		(layer "In9.Cu")
		(net "M_A_WE#")
	)
	(segment
		(start 119.1133 -58.6359)
		(end 106.7943 -58.6359)
		(width 0.1905)
		(layer "In9.Cu")
		(net "M_A_WE#")
	)
	(segment
		(start 101.9048 -49.9872)
		(end 101.676454 -49.758854)
		(width 0.1016)
		(layer "In9.Cu")
		(net "M_A_WE#")
	)
	(segment
		(start 141.466824 -59.1439)
		(end 133.111494 -59.1439)
		(width 0.1905)
		(layer "In9.Cu")
		(net "M_A_WE#")
	)
	(segment
		(start 151.0284 -65.8622)
		(end 151.384 -65.5066)
		(width 0.1905)
		(layer "In9.Cu")
		(net "M_A_WE#")
	)
	(segment
		(start 122.04319 -59.0423)
		(end 121.36374 -58.36285)
		(width 0.1905)
		(layer "In9.Cu")
		(net "M_A_WE#")
	)
	(segment
		(start 102.9208 -49.5554)
		(end 102.489 -49.9872)
		(width 0.1016)
		(layer "In9.Cu")
		(net "M_A_WE#")
	)
	(segment
		(start 104.7623 -53.1241)
		(end 104.7623 -51.0667)
		(width 0.1016)
		(layer "In9.Cu")
		(net "M_A_WE#")
	)
	(segment
		(start 106.1212 -55.2196)
		(end 106.1212 -54.483)
		(width 0.1016)
		(layer "In9.Cu")
		(net "M_A_WE#")
	)
	(segment
		(start 133.111494 -59.1439)
		(end 132.406644 -58.43905)
		(width 0.1905)
		(layer "In9.Cu")
		(net "M_A_WE#")
	)
	(segment
		(start 129.80924 -58.43905)
		(end 129.20599 -59.0423)
		(width 0.1905)
		(layer "In9.Cu")
		(net "M_A_WE#")
	)
	(segment
		(start 151.384 -63.405258)
		(end 150.818342 -62.8396)
		(width 0.1905)
		(layer "In9.Cu")
		(net "M_A_WE#")
	)
	(segment
		(start 119.38635 -58.36285)
		(end 119.1133 -58.6359)
		(width 0.1905)
		(layer "In9.Cu")
		(net "M_A_WE#")
	)
	(segment
		(start 106.1212 -57.9628)
		(end 106.1212 -55.2196)
		(width 0.1905)
		(layer "In9.Cu")
		(net "M_A_WE#")
	)
	(segment
		(start 150.726394 -68.284598)
		(end 150.0378 -67.596004)
		(width 0.2413)
		(layer "F.Cu")
		(net "M_A_CAS#")
	)
	(segment
		(start 150.550118 -70.806564)
		(end 150.550118 -69.71284)
		(width 0.2413)
		(layer "F.Cu")
		(net "M_A_CAS#")
	)
	(segment
		(start 150.0378 -67.596004)
		(end 150.0378 -67.267582)
		(width 0.2413)
		(layer "F.Cu")
		(net "M_A_CAS#")
	)
	(segment
		(start 150.550118 -69.71284)
		(end 150.726394 -69.536564)
		(width 0.2413)
		(layer "F.Cu")
		(net "M_A_CAS#")
	)
	(segment
		(start 150.726394 -69.536564)
		(end 150.726394 -68.284598)
		(width 0.2413)
		(layer "F.Cu")
		(net "M_A_CAS#")
	)
	(segment
		(start 99.7331 -49.165002)
		(end 99.7458 -49.165002)
		(width 0.2413)
		(layer "F.Cu")
		(net "M_A_CAS#")
	)
	(segment
		(start 99.352608 -49.545494)
		(end 99.7331 -49.165002)
		(width 0.2413)
		(layer "F.Cu")
		(net "M_A_CAS#")
	)
	(via
		(at 150.0378 -67.267582)
		(size 0.4318)
		(drill 0.2032)
		(layers "F.Cu" "B.Cu")
		(net "M_A_CAS#")
	)
	(via
		(at 99.7458 -49.165002)
		(size 0.4318)
		(drill 0.2032)
		(layers "F.Cu" "B.Cu")
		(net "M_A_CAS#")
	)
	(segment
		(start 150.702518 -63.852298)
		(end 150.702518 -65.1764)
		(width 0.2413)
		(layer "B.Cu")
		(net "M_A_CAS#")
	)
	(segment
		(start 150.548848 -66.77406)
		(end 150.055326 -67.267582)
		(width 0.2413)
		(layer "B.Cu")
		(net "M_A_CAS#")
	)
	(segment
		(start 150.055326 -67.267582)
		(end 150.0378 -67.267582)
		(width 0.2413)
		(layer "B.Cu")
		(net "M_A_CAS#")
	)
	(segment
		(start 150.702518 -65.1764)
		(end 150.548848 -65.33007)
		(width 0.2413)
		(layer "B.Cu")
		(net "M_A_CAS#")
	)
	(segment
		(start 150.548848 -65.33007)
		(end 150.548848 -66.77406)
		(width 0.2413)
		(layer "B.Cu")
		(net "M_A_CAS#")
	)
	(segment
		(start 150.550118 -63.699898)
		(end 150.702518 -63.852298)
		(width 0.2413)
		(layer "B.Cu")
		(net "M_A_CAS#")
	)
	(segment
		(start 150.550118 -62.599824)
		(end 150.550118 -63.699898)
		(width 0.2413)
		(layer "B.Cu")
		(net "M_A_CAS#")
	)
	(segment
		(start 121.57456 -61.214)
		(end 147.922742 -61.214)
		(width 0.1905)
		(layer "In9.Cu")
		(net "M_A_CAS#")
	)
	(segment
		(start 149.4536 -67.370706)
		(end 149.606 -67.218306)
		(width 0.1905)
		(layer "In9.Cu")
		(net "M_A_CAS#")
	)
	(segment
		(start 100.824284 -51.207924)
		(end 101.093524 -51.207924)
		(width 0.1905)
		(layer "In9.Cu")
		(net "M_A_CAS#")
	)
	(segment
		(start 120.86336 -60.5028)
		(end 121.57456 -61.214)
		(width 0.1905)
		(layer "In9.Cu")
		(net "M_A_CAS#")
	)
	(segment
		(start 100.150676 -50.265076)
		(end 100.150676 -50.534316)
		(width 0.1905)
		(layer "In9.Cu")
		(net "M_A_CAS#")
	)
	(segment
		(start 101.497892 -51.612292)
		(end 101.497892 -51.881532)
		(width 0.1905)
		(layer "In9.Cu")
		(net "M_A_CAS#")
	)
	(segment
		(start 148.784818 -63.862966)
		(end 148.784818 -67.8688)
		(width 0.1905)
		(layer "In9.Cu")
		(net "M_A_CAS#")
	)
	(segment
		(start 148.937218 -68.0212)
		(end 149.3012 -68.0212)
		(width 0.1905)
		(layer "In9.Cu")
		(net "M_A_CAS#")
	)
	(segment
		(start 101.093524 -51.207924)
		(end 101.497892 -51.612292)
		(width 0.1905)
		(layer "In9.Cu")
		(net "M_A_CAS#")
	)
	(segment
		(start 148.784818 -67.8688)
		(end 148.937218 -68.0212)
		(width 0.1905)
		(layer "In9.Cu")
		(net "M_A_CAS#")
	)
	(segment
		(start 149.971506 -67.218306)
		(end 150.020782 -67.267582)
		(width 0.1905)
		(layer "In9.Cu")
		(net "M_A_CAS#")
	)
	(segment
		(start 150.020782 -67.267582)
		(end 150.0378 -67.267582)
		(width 0.1905)
		(layer "In9.Cu")
		(net "M_A_CAS#")
	)
	(segment
		(start 147.922742 -61.214)
		(end 148.7932 -62.084458)
		(width 0.1905)
		(layer "In9.Cu")
		(net "M_A_CAS#")
	)
	(segment
		(start 148.7932 -63.854584)
		(end 148.784818 -63.862966)
		(width 0.1905)
		(layer "In9.Cu")
		(net "M_A_CAS#")
	)
	(segment
		(start 99.87026 -50.814732)
		(end 99.87026 -51.17846)
		(width 0.1905)
		(layer "In9.Cu")
		(net "M_A_CAS#")
	)
	(segment
		(start 100.18014 -51.48834)
		(end 100.543868 -51.48834)
		(width 0.1905)
		(layer "In9.Cu")
		(net "M_A_CAS#")
	)
	(segment
		(start 99.7458 -49.8602)
		(end 100.150676 -50.265076)
		(width 0.1905)
		(layer "In9.Cu")
		(net "M_A_CAS#")
	)
	(segment
		(start 149.4536 -67.8688)
		(end 149.4536 -67.370706)
		(width 0.1905)
		(layer "In9.Cu")
		(net "M_A_CAS#")
	)
	(segment
		(start 149.3012 -68.0212)
		(end 149.4536 -67.8688)
		(width 0.1905)
		(layer "In9.Cu")
		(net "M_A_CAS#")
	)
	(segment
		(start 100.150676 -50.534316)
		(end 99.87026 -50.814732)
		(width 0.1905)
		(layer "In9.Cu")
		(net "M_A_CAS#")
	)
	(segment
		(start 102.44074 -52.55514)
		(end 103.2002 -53.3146)
		(width 0.1905)
		(layer "In9.Cu")
		(net "M_A_CAS#")
	)
	(segment
		(start 103.2002 -53.3146)
		(end 103.2002 -58.6232)
		(width 0.1905)
		(layer "In9.Cu")
		(net "M_A_CAS#")
	)
	(segment
		(start 101.7397 -52.7177)
		(end 102.00894 -52.7177)
		(width 0.1905)
		(layer "In9.Cu")
		(net "M_A_CAS#")
	)
	(segment
		(start 99.7458 -49.165002)
		(end 99.7458 -49.8602)
		(width 0.1905)
		(layer "In9.Cu")
		(net "M_A_CAS#")
	)
	(segment
		(start 149.606 -67.218306)
		(end 149.971506 -67.218306)
		(width 0.1905)
		(layer "In9.Cu")
		(net "M_A_CAS#")
	)
	(segment
		(start 101.497892 -51.881532)
		(end 101.335332 -52.044092)
		(width 0.1905)
		(layer "In9.Cu")
		(net "M_A_CAS#")
	)
	(segment
		(start 101.335332 -52.044092)
		(end 101.335332 -52.313332)
		(width 0.1905)
		(layer "In9.Cu")
		(net "M_A_CAS#")
	)
	(segment
		(start 101.335332 -52.313332)
		(end 101.7397 -52.7177)
		(width 0.1905)
		(layer "In9.Cu")
		(net "M_A_CAS#")
	)
	(segment
		(start 102.00894 -52.7177)
		(end 102.1715 -52.55514)
		(width 0.1905)
		(layer "In9.Cu")
		(net "M_A_CAS#")
	)
	(segment
		(start 99.87026 -51.17846)
		(end 100.18014 -51.48834)
		(width 0.1905)
		(layer "In9.Cu")
		(net "M_A_CAS#")
	)
	(segment
		(start 148.7932 -62.084458)
		(end 148.7932 -63.854584)
		(width 0.1905)
		(layer "In9.Cu")
		(net "M_A_CAS#")
	)
	(segment
		(start 103.2002 -58.6232)
		(end 105.0798 -60.5028)
		(width 0.1905)
		(layer "In9.Cu")
		(net "M_A_CAS#")
	)
	(segment
		(start 102.1715 -52.55514)
		(end 102.44074 -52.55514)
		(width 0.1905)
		(layer "In9.Cu")
		(net "M_A_CAS#")
	)
	(segment
		(start 105.0798 -60.5028)
		(end 120.86336 -60.5028)
		(width 0.1905)
		(layer "In9.Cu")
		(net "M_A_CAS#")
	)
	(segment
		(start 100.543868 -51.48834)
		(end 100.824284 -51.207924)
		(width 0.1905)
		(layer "In9.Cu")
		(net "M_A_CAS#")
	)
	(segment
		(start 151.45004 -62.59322)
		(end 151.45004 -63.650622)
		(width 0.2413)
		(layer "F.Cu")
		(net "M_A_RAS#")
	)
	(segment
		(start 151.45004 -63.650622)
		(end 151.651716 -63.852298)
		(width 0.2413)
		(layer "F.Cu")
		(net "M_A_RAS#")
	)
	(segment
		(start 151.651716 -63.852298)
		(end 151.651716 -65.742312)
		(width 0.2413)
		(layer "F.Cu")
		(net "M_A_RAS#")
	)
	(segment
		(start 151.651716 -65.742312)
		(end 151.501348 -65.89268)
		(width 0.2413)
		(layer "F.Cu")
		(net "M_A_RAS#")
	)
	(segment
		(start 101.338888 -49.083976)
		(end 101.338888 -49.164494)
		(width 0.1016)
		(layer "F.Cu")
		(net "M_A_RAS#")
	)
	(segment
		(start 101.04882 -48.789844)
		(end 101.04882 -48.793908)
		(width 0.1016)
		(layer "F.Cu")
		(net "M_A_RAS#")
	)
	(segment
		(start 151.501348 -65.89268)
		(end 151.501348 -66.862452)
		(width 0.2413)
		(layer "F.Cu")
		(net "M_A_RAS#")
	)
	(segment
		(start 101.04247 -48.783494)
		(end 101.04882 -48.789844)
		(width 0.1016)
		(layer "F.Cu")
		(net "M_A_RAS#")
	)
	(segment
		(start 101.04882 -48.793908)
		(end 101.338888 -49.083976)
		(width 0.1016)
		(layer "F.Cu")
		(net "M_A_RAS#")
	)
	(segment
		(start 151.501348 -66.862452)
		(end 151.003 -67.3608)
		(width 0.2413)
		(layer "F.Cu")
		(net "M_A_RAS#")
	)
	(via
		(at 101.04247 -48.783494)
		(size 0.4318)
		(drill 0.2032)
		(layers "F.Cu" "B.Cu")
		(net "M_A_RAS#")
	)
	(via
		(at 151.003 -67.3608)
		(size 0.4318)
		(drill 0.2032)
		(layers "F.Cu" "B.Cu")
		(net "M_A_RAS#")
	)
	(segment
		(start 151.45004 -69.968364)
		(end 151.89581 -69.522594)
		(width 0.2413)
		(layer "B.Cu")
		(net "M_A_RAS#")
	)
	(segment
		(start 151.89581 -69.522594)
		(end 151.89581 -68.165218)
		(width 0.2413)
		(layer "B.Cu")
		(net "M_A_RAS#")
	)
	(segment
		(start 151.89581 -68.165218)
		(end 151.091392 -67.3608)
		(width 0.2413)
		(layer "B.Cu")
		(net "M_A_RAS#")
	)
	(segment
		(start 151.091392 -67.3608)
		(end 151.003 -67.3608)
		(width 0.2413)
		(layer "B.Cu")
		(net "M_A_RAS#")
	)
	(segment
		(start 151.45004 -70.79996)
		(end 151.45004 -69.968364)
		(width 0.2413)
		(layer "B.Cu")
		(net "M_A_RAS#")
	)
	(segment
		(start 150.574248 -66.41338)
		(end 150.485348 -66.50228)
		(width 0.1905)
		(layer "In9.Cu")
		(net "M_A_RAS#")
	)
	(segment
		(start 129.4638 -59.6646)
		(end 130.06705 -59.06135)
		(width 0.1905)
		(layer "In9.Cu")
		(net "M_A_RAS#")
	)
	(segment
		(start 107.2134 -59.2582)
		(end 119.37111 -59.2582)
		(width 0.1905)
		(layer "In9.Cu")
		(net "M_A_RAS#")
	)
	(segment
		(start 151.0284 -65.368424)
		(end 150.574248 -65.822576)
		(width 0.1905)
		(layer "In9.Cu")
		(net "M_A_RAS#")
	)
	(segment
		(start 105.4862 -57.531)
		(end 105.4862 -57.8612)
		(width 0.1905)
		(layer "In9.Cu")
		(net "M_A_RAS#")
	)
	(segment
		(start 137.738358 -60.14085)
		(end 137.909808 -59.9694)
		(width 0.1905)
		(layer "In9.Cu")
		(net "M_A_RAS#")
	)
	(segment
		(start 105.1052 -57.15)
		(end 105.4862 -57.531)
		(width 0.1905)
		(layer "In9.Cu")
		(net "M_A_RAS#")
	)
	(segment
		(start 141.200886 -59.9694)
		(end 141.351 -60.119514)
		(width 0.1905)
		(layer "In9.Cu")
		(net "M_A_RAS#")
	)
	(segment
		(start 105.4862 -57.8612)
		(end 105.1052 -58.2422)
		(width 0.1905)
		(layer "In9.Cu")
		(net "M_A_RAS#")
	)
	(segment
		(start 105.4862 -59.2582)
		(end 105.9688 -59.2582)
		(width 0.1905)
		(layer "In9.Cu")
		(net "M_A_RAS#")
	)
	(segment
		(start 150.6474 -63.246)
		(end 151.0284 -63.627)
		(width 0.1905)
		(layer "In9.Cu")
		(net "M_A_RAS#")
	)
	(segment
		(start 105.1052 -56.2102)
		(end 105.1052 -57.15)
		(width 0.1905)
		(layer "In9.Cu")
		(net "M_A_RAS#")
	)
	(segment
		(start 137.343642 -60.14085)
		(end 137.738358 -60.14085)
		(width 0.1905)
		(layer "In9.Cu")
		(net "M_A_RAS#")
	)
	(segment
		(start 150.485348 -66.50228)
		(end 150.485348 -66.962528)
		(width 0.1905)
		(layer "In9.Cu")
		(net "M_A_RAS#")
	)
	(segment
		(start 137.172192 -59.9694)
		(end 137.343642 -60.14085)
		(width 0.1905)
		(layer "In9.Cu")
		(net "M_A_RAS#")
	)
	(segment
		(start 150.88362 -67.3608)
		(end 151.003 -67.3608)
		(width 0.1905)
		(layer "In9.Cu")
		(net "M_A_RAS#")
	)
	(segment
		(start 121.10593 -58.98515)
		(end 121.78538 -59.6646)
		(width 0.1905)
		(layer "In9.Cu")
		(net "M_A_RAS#")
	)
	(segment
		(start 149.637242 -62.071758)
		(end 149.637242 -62.794642)
		(width 0.1905)
		(layer "In9.Cu")
		(net "M_A_RAS#")
	)
	(segment
		(start 101.04247 -48.783494)
		(end 101.04247 -48.79721)
		(width 0.1016)
		(layer "In9.Cu")
		(net "M_A_RAS#")
	)
	(segment
		(start 137.909808 -59.9694)
		(end 141.200886 -59.9694)
		(width 0.1905)
		(layer "In9.Cu")
		(net "M_A_RAS#")
	)
	(segment
		(start 133.056884 -59.9694)
		(end 137.172192 -59.9694)
		(width 0.1905)
		(layer "In9.Cu")
		(net "M_A_RAS#")
	)
	(segment
		(start 101.01834 -48.82134)
		(end 101.01834 -49.76114)
		(width 0.1016)
		(layer "In9.Cu")
		(net "M_A_RAS#")
	)
	(segment
		(start 148.144484 -60.579)
		(end 149.637242 -62.071758)
		(width 0.1905)
		(layer "In9.Cu")
		(net "M_A_RAS#")
	)
	(segment
		(start 150.485348 -66.962528)
		(end 150.88362 -67.3608)
		(width 0.1905)
		(layer "In9.Cu")
		(net "M_A_RAS#")
	)
	(segment
		(start 119.64416 -58.98515)
		(end 121.10593 -58.98515)
		(width 0.1905)
		(layer "In9.Cu")
		(net "M_A_RAS#")
	)
	(segment
		(start 104.2924 -53.2384)
		(end 105.1052 -54.0512)
		(width 0.1016)
		(layer "In9.Cu")
		(net "M_A_RAS#")
	)
	(segment
		(start 119.37111 -59.2582)
		(end 119.64416 -58.98515)
		(width 0.1905)
		(layer "In9.Cu")
		(net "M_A_RAS#")
	)
	(segment
		(start 101.727 -50.4698)
		(end 103.4034 -50.4698)
		(width 0.1016)
		(layer "In9.Cu")
		(net "M_A_RAS#")
	)
	(segment
		(start 105.1052 -58.8772)
		(end 105.4862 -59.2582)
		(width 0.1905)
		(layer "In9.Cu")
		(net "M_A_RAS#")
	)
	(segment
		(start 103.4034 -50.4698)
		(end 104.2924 -51.3588)
		(width 0.1016)
		(layer "In9.Cu")
		(net "M_A_RAS#")
	)
	(segment
		(start 149.637242 -62.794642)
		(end 150.0886 -63.246)
		(width 0.1905)
		(layer "In9.Cu")
		(net "M_A_RAS#")
	)
	(segment
		(start 121.78538 -59.6646)
		(end 129.4638 -59.6646)
		(width 0.1905)
		(layer "In9.Cu")
		(net "M_A_RAS#")
	)
	(segment
		(start 101.04247 -48.79721)
		(end 101.01834 -48.82134)
		(width 0.1016)
		(layer "In9.Cu")
		(net "M_A_RAS#")
	)
	(segment
		(start 105.1052 -58.2422)
		(end 105.1052 -58.8772)
		(width 0.1905)
		(layer "In9.Cu")
		(net "M_A_RAS#")
	)
	(segment
		(start 105.9688 -59.2582)
		(end 106.299 -58.928)
		(width 0.1905)
		(layer "In9.Cu")
		(net "M_A_RAS#")
	)
	(segment
		(start 141.351 -60.119514)
		(end 144.643094 -60.119514)
		(width 0.1905)
		(layer "In9.Cu")
		(net "M_A_RAS#")
	)
	(segment
		(start 151.0284 -63.627)
		(end 151.0284 -65.368424)
		(width 0.1905)
		(layer "In9.Cu")
		(net "M_A_RAS#")
	)
	(segment
		(start 150.574248 -65.822576)
		(end 150.574248 -66.41338)
		(width 0.1905)
		(layer "In9.Cu")
		(net "M_A_RAS#")
	)
	(segment
		(start 106.299 -58.928)
		(end 106.8832 -58.928)
		(width 0.1905)
		(layer "In9.Cu")
		(net "M_A_RAS#")
	)
	(segment
		(start 105.1052 -54.0512)
		(end 105.1052 -56.2102)
		(width 0.1016)
		(layer "In9.Cu")
		(net "M_A_RAS#")
	)
	(segment
		(start 106.8832 -58.928)
		(end 107.2134 -59.2582)
		(width 0.1905)
		(layer "In9.Cu")
		(net "M_A_RAS#")
	)
	(segment
		(start 104.2924 -51.3588)
		(end 104.2924 -53.2384)
		(width 0.1016)
		(layer "In9.Cu")
		(net "M_A_RAS#")
	)
	(segment
		(start 101.01834 -49.76114)
		(end 101.727 -50.4698)
		(width 0.1016)
		(layer "In9.Cu")
		(net "M_A_RAS#")
	)
	(segment
		(start 130.06705 -59.06135)
		(end 132.148834 -59.06135)
		(width 0.1905)
		(layer "In9.Cu")
		(net "M_A_RAS#")
	)
	(segment
		(start 144.643094 -60.119514)
		(end 145.10258 -60.579)
		(width 0.1905)
		(layer "In9.Cu")
		(net "M_A_RAS#")
	)
	(segment
		(start 145.10258 -60.579)
		(end 148.144484 -60.579)
		(width 0.1905)
		(layer "In9.Cu")
		(net "M_A_RAS#")
	)
	(segment
		(start 132.148834 -59.06135)
		(end 133.056884 -59.9694)
		(width 0.1905)
		(layer "In9.Cu")
		(net "M_A_RAS#")
	)
	(segment
		(start 150.0886 -63.246)
		(end 150.6474 -63.246)
		(width 0.1905)
		(layer "In9.Cu")
		(net "M_A_RAS#")
	)
	(segment
		(start 51.035712 -29.115512)
		(end 50.081434 -28.161234)
		(width 0.1143)
		(layer "F.Cu")
		(net "SPI_HOLD#")
	)
	(segment
		(start 50.1142 -34.4932)
		(end 50.1142 -33.288732)
		(width 0.1143)
		(layer "F.Cu")
		(net "SPI_HOLD#")
	)
	(segment
		(start 50.1142 -33.288732)
		(end 51.035712 -32.36722)
		(width 0.1143)
		(layer "F.Cu")
		(net "SPI_HOLD#")
	)
	(segment
		(start 51.035712 -32.36722)
		(end 51.035712 -29.115512)
		(width 0.1143)
		(layer "F.Cu")
		(net "SPI_HOLD#")
	)
	(segment
		(start 50.081434 -28.161234)
		(end 49.429162 -28.161234)
		(width 0.1143)
		(layer "F.Cu")
		(net "SPI_HOLD#")
	)
	(segment
		(start 140.79855 -43.35145)
		(end 139.99845 -44.15155)
		(width 0.1143)
		(layer "F.Cu")
		(net "FPGA_CLK_DP")
	)
	(segment
		(start 152.818846 -43.79595)
		(end 152.374346 -43.35145)
		(width 0.1143)
		(layer "F.Cu")
		(net "FPGA_CLK_DP")
	)
	(segment
		(start 163.16325 -43.9674)
		(end 162.4584 -43.26255)
		(width 0.1143)
		(layer "F.Cu")
		(net "FPGA_CLK_DP")
	)
	(segment
		(start 162.4584 -43.26255)
		(end 159.126682 -43.26255)
		(width 0.1143)
		(layer "F.Cu")
		(net "FPGA_CLK_DP")
	)
	(segment
		(start 158.789116 -43.600116)
		(end 158.593536 -43.79595)
		(width 0.1143)
		(layer "F.Cu")
		(net "FPGA_CLK_DP")
	)
	(segment
		(start 163.16325 -43.9674)
		(end 164.3888 -43.9674)
		(width 0.1143)
		(layer "F.Cu")
		(net "FPGA_CLK_DP")
	)
	(segment
		(start 158.593536 -43.79595)
		(end 152.818846 -43.79595)
		(width 0.1143)
		(layer "F.Cu")
		(net "FPGA_CLK_DP")
	)
	(segment
		(start 152.374346 -43.35145)
		(end 140.79855 -43.35145)
		(width 0.1143)
		(layer "F.Cu")
		(net "FPGA_CLK_DP")
	)
	(segment
		(start 164.3888 -43.9674)
		(end 164.4142 -43.942)
		(width 0.1143)
		(layer "F.Cu")
		(net "FPGA_CLK_DP")
	)
	(segment
		(start 139.99845 -44.15155)
		(end 139.99845 -45.1612)
		(width 0.1143)
		(layer "F.Cu")
		(net "FPGA_CLK_DP")
	)
	(segment
		(start 159.126682 -43.26255)
		(end 158.789116 -43.600116)
		(width 0.1143)
		(layer "F.Cu")
		(net "FPGA_CLK_DP")
	)
	(via
		(at 163.16325 -43.9674)
		(size 0.7112)
		(drill 0.3556)
		(layers "F.Cu" "B.Cu")
		(net "FPGA_CLK_DP")
	)
	(segment
		(start 43.52036 -29.55544)
		(end 42.10177 -29.55544)
		(width 0.1143)
		(layer "F.Cu")
		(net "XDP_RSMRST_R#")
	)
	(segment
		(start 43.7642 -27.226006)
		(end 44.376594 -27.8384)
		(width 0.1143)
		(layer "F.Cu")
		(net "XDP_RSMRST_R#")
	)
	(segment
		(start 44.3992 -28.6766)
		(end 43.52036 -29.55544)
		(width 0.1143)
		(layer "F.Cu")
		(net "XDP_RSMRST_R#")
	)
	(segment
		(start 44.3992 -27.8384)
		(end 44.3992 -28.6766)
		(width 0.1143)
		(layer "F.Cu")
		(net "XDP_RSMRST_R#")
	)
	(segment
		(start 44.376594 -27.8384)
		(end 44.3992 -27.8384)
		(width 0.1143)
		(layer "F.Cu")
		(net "XDP_RSMRST_R#")
	)
	(via
		(at 36.82873 -14.73073)
		(size 0.508)
		(drill 0.254)
		(layers "F.Cu" "B.Cu")
		(net "XDP_RSMRST_R#")
	)
	(via
		(at 43.7642 -27.226006)
		(size 0.508)
		(drill 0.254)
		(layers "F.Cu" "B.Cu")
		(net "XDP_RSMRST_R#")
	)
	(via
		(at 35.489388 -13.792454)
		(size 0.7112)
		(drill 0.3556)
		(layers "F.Cu" "B.Cu")
		(net "XDP_RSMRST_R#")
	)
	(segment
		(start 36.82873 -14.73073)
		(end 36.427664 -14.73073)
		(width 0.1143)
		(layer "B.Cu")
		(net "XDP_RSMRST_R#")
	)
	(segment
		(start 36.427664 -14.73073)
		(end 35.489388 -13.792454)
		(width 0.1143)
		(layer "B.Cu")
		(net "XDP_RSMRST_R#")
	)
	(segment
		(start 43.8658 -25.864312)
		(end 43.8658 -27.124406)
		(width 0.0889)
		(layer "In2.Cu")
		(net "XDP_RSMRST_R#")
	)
	(segment
		(start 36.82873 -14.73073)
		(end 36.82873 -15.97533)
		(width 0.0889)
		(layer "In2.Cu")
		(net "XDP_RSMRST_R#")
	)
	(segment
		(start 36.82873 -15.97533)
		(end 42.817796 -21.964396)
		(width 0.0889)
		(layer "In2.Cu")
		(net "XDP_RSMRST_R#")
	)
	(segment
		(start 42.817796 -21.964396)
		(end 42.817796 -24.816308)
		(width 0.0889)
		(layer "In2.Cu")
		(net "XDP_RSMRST_R#")
	)
	(segment
		(start 42.817796 -24.816308)
		(end 43.8658 -25.864312)
		(width 0.0889)
		(layer "In2.Cu")
		(net "XDP_RSMRST_R#")
	)
	(segment
		(start 43.8658 -27.124406)
		(end 43.7642 -27.226006)
		(width 0.0889)
		(layer "In2.Cu")
		(net "XDP_RSMRST_R#")
	)
	(segment
		(start 30.8864 -32.5882)
		(end 30.861 -32.5628)
		(width 0.1143)
		(layer "F.Cu")
		(net "XDP_RST_BTN_R#")
	)
	(segment
		(start 33.1216 -31.8008)
		(end 32.639 -32.2834)
		(width 0.1143)
		(layer "F.Cu")
		(net "XDP_RST_BTN_R#")
	)
	(segment
		(start 68.39204 -11.51636)
		(end 68.5292 -11.3792)
		(width 0.1143)
		(layer "F.Cu")
		(net "XDP_RST_BTN_R#")
	)
	(segment
		(start 31.623 -32.5882)
		(end 30.8864 -32.5882)
		(width 0.1143)
		(layer "F.Cu")
		(net "XDP_RST_BTN_R#")
	)
	(segment
		(start 68.39204 -12.17676)
		(end 68.39204 -11.51636)
		(width 0.1143)
		(layer "F.Cu")
		(net "XDP_RST_BTN_R#")
	)
	(segment
		(start 32.639 -32.2834)
		(end 31.9278 -32.2834)
		(width 0.1143)
		(layer "F.Cu")
		(net "XDP_RST_BTN_R#")
	)
	(segment
		(start 31.9278 -32.2834)
		(end 31.623 -32.5882)
		(width 0.1143)
		(layer "F.Cu")
		(net "XDP_RST_BTN_R#")
	)
	(segment
		(start 33.681416 -31.55442)
		(end 33.435036 -31.8008)
		(width 0.1143)
		(layer "F.Cu")
		(net "XDP_RST_BTN_R#")
	)
	(segment
		(start 33.163002 -31.8008)
		(end 33.1216 -31.8008)
		(width 0.1143)
		(layer "F.Cu")
		(net "XDP_RST_BTN_R#")
	)
	(segment
		(start 36.37788 -31.55442)
		(end 33.681416 -31.55442)
		(width 0.1143)
		(layer "F.Cu")
		(net "XDP_RST_BTN_R#")
	)
	(segment
		(start 33.435036 -31.8008)
		(end 33.163002 -31.8008)
		(width 0.1143)
		(layer "F.Cu")
		(net "XDP_RST_BTN_R#")
	)
	(via
		(at 57.531 -23.9903)
		(size 0.508)
		(drill 0.254)
		(layers "F.Cu" "B.Cu")
		(net "XDP_RST_BTN_R#")
	)
	(via
		(at 67.6148 -12.377674)
		(size 0.7112)
		(drill 0.3556)
		(layers "F.Cu" "B.Cu")
		(net "XDP_RST_BTN_R#")
	)
	(via
		(at 68.5292 -11.3792)
		(size 0.508)
		(drill 0.254)
		(layers "F.Cu" "B.Cu")
		(net "XDP_RST_BTN_R#")
	)
	(via
		(at 33.163002 -31.8008)
		(size 0.508)
		(drill 0.254)
		(layers "F.Cu" "B.Cu")
		(net "XDP_RST_BTN_R#")
	)
	(via
		(at 58.2422 -10.9093)
		(size 0.508)
		(drill 0.254)
		(layers "F.Cu" "B.Cu")
		(net "XDP_RST_BTN_R#")
	)
	(segment
		(start 67.6148 -12.377674)
		(end 67.6148 -12.192)
		(width 0.1143)
		(layer "B.Cu")
		(net "XDP_RST_BTN_R#")
	)
	(segment
		(start 68.4276 -11.3792)
		(end 68.5292 -11.3792)
		(width 0.1143)
		(layer "B.Cu")
		(net "XDP_RST_BTN_R#")
	)
	(segment
		(start 67.6148 -12.192)
		(end 68.4276 -11.3792)
		(width 0.1143)
		(layer "B.Cu")
		(net "XDP_RST_BTN_R#")
	)
	(segment
		(start 34.28365 -31.62935)
		(end 35.367722 -31.62935)
		(width 0.0889)
		(layer "In4.Cu")
		(net "XDP_RST_BTN_R#")
	)
	(segment
		(start 36.449 -32.710628)
		(end 39.726616 -32.710628)
		(width 0.0889)
		(layer "In4.Cu")
		(net "XDP_RST_BTN_R#")
	)
	(segment
		(start 57.09285 -24.42845)
		(end 57.531 -23.9903)
		(width 0.0889)
		(layer "In4.Cu")
		(net "XDP_RST_BTN_R#")
	)
	(segment
		(start 49.752758 -25.708864)
		(end 50.372772 -25.08885)
		(width 0.0889)
		(layer "In4.Cu")
		(net "XDP_RST_BTN_R#")
	)
	(segment
		(start 53.29555 -24.42845)
		(end 57.09285 -24.42845)
		(width 0.0889)
		(layer "In4.Cu")
		(net "XDP_RST_BTN_R#")
	)
	(segment
		(start 33.163002 -31.8008)
		(end 34.1122 -31.8008)
		(width 0.0889)
		(layer "In4.Cu")
		(net "XDP_RST_BTN_R#")
	)
	(segment
		(start 52.63515 -25.08885)
		(end 53.29555 -24.42845)
		(width 0.0889)
		(layer "In4.Cu")
		(net "XDP_RST_BTN_R#")
	)
	(segment
		(start 46.860206 -24.80056)
		(end 46.860206 -25.054814)
		(width 0.0889)
		(layer "In4.Cu")
		(net "XDP_RST_BTN_R#")
	)
	(segment
		(start 45.66285 -24.59736)
		(end 45.94606 -24.31415)
		(width 0.0889)
		(layer "In4.Cu")
		(net "XDP_RST_BTN_R#")
	)
	(segment
		(start 35.367722 -31.62935)
		(end 36.449 -32.710628)
		(width 0.0889)
		(layer "In4.Cu")
		(net "XDP_RST_BTN_R#")
	)
	(segment
		(start 46.860206 -25.054814)
		(end 47.514256 -25.708864)
		(width 0.0889)
		(layer "In4.Cu")
		(net "XDP_RST_BTN_R#")
	)
	(segment
		(start 39.726616 -32.710628)
		(end 45.5422 -26.895044)
		(width 0.0889)
		(layer "In4.Cu")
		(net "XDP_RST_BTN_R#")
	)
	(segment
		(start 45.5422 -26.895044)
		(end 45.5422 -25.021794)
		(width 0.0889)
		(layer "In4.Cu")
		(net "XDP_RST_BTN_R#")
	)
	(segment
		(start 45.94606 -24.31415)
		(end 46.373796 -24.31415)
		(width 0.0889)
		(layer "In4.Cu")
		(net "XDP_RST_BTN_R#")
	)
	(segment
		(start 46.373796 -24.31415)
		(end 46.860206 -24.80056)
		(width 0.0889)
		(layer "In4.Cu")
		(net "XDP_RST_BTN_R#")
	)
	(segment
		(start 47.514256 -25.708864)
		(end 49.752758 -25.708864)
		(width 0.0889)
		(layer "In4.Cu")
		(net "XDP_RST_BTN_R#")
	)
	(segment
		(start 50.372772 -25.08885)
		(end 52.63515 -25.08885)
		(width 0.0889)
		(layer "In4.Cu")
		(net "XDP_RST_BTN_R#")
	)
	(segment
		(start 45.66285 -24.901144)
		(end 45.66285 -24.59736)
		(width 0.0889)
		(layer "In4.Cu")
		(net "XDP_RST_BTN_R#")
	)
	(segment
		(start 45.5422 -25.021794)
		(end 45.66285 -24.901144)
		(width 0.0889)
		(layer "In4.Cu")
		(net "XDP_RST_BTN_R#")
	)
	(segment
		(start 34.1122 -31.8008)
		(end 34.28365 -31.62935)
		(width 0.0889)
		(layer "In4.Cu")
		(net "XDP_RST_BTN_R#")
	)
	(segment
		(start 58.2422 -10.9093)
		(end 58.643266 -10.508234)
		(width 0.0889)
		(layer "In7.Cu")
		(net "XDP_RST_BTN_R#")
	)
	(segment
		(start 60.160408 -10.508234)
		(end 60.160916 -10.508488)
		(width 0.0889)
		(layer "In7.Cu")
		(net "XDP_RST_BTN_R#")
	)
	(segment
		(start 60.17387 -10.511028)
		(end 60.184792 -10.518394)
		(width 0.0889)
		(layer "In7.Cu")
		(net "XDP_RST_BTN_R#")
	)
	(segment
		(start 60.160916 -10.508488)
		(end 60.17387 -10.511028)
		(width 0.0889)
		(layer "In7.Cu")
		(net "XDP_RST_BTN_R#")
	)
	(segment
		(start 67.3608 -11.3792)
		(end 68.5292 -11.3792)
		(width 0.0889)
		(layer "In7.Cu")
		(net "XDP_RST_BTN_R#")
	)
	(segment
		(start 66.84645 -10.86485)
		(end 67.3608 -11.3792)
		(width 0.0889)
		(layer "In7.Cu")
		(net "XDP_RST_BTN_R#")
	)
	(segment
		(start 60.531248 -10.86485)
		(end 66.84645 -10.86485)
		(width 0.0889)
		(layer "In7.Cu")
		(net "XDP_RST_BTN_R#")
	)
	(segment
		(start 58.643266 -10.508234)
		(end 60.160408 -10.508234)
		(width 0.0889)
		(layer "In7.Cu")
		(net "XDP_RST_BTN_R#")
	)
	(segment
		(start 60.184792 -10.518394)
		(end 60.531248 -10.86485)
		(width 0.0889)
		(layer "In7.Cu")
		(net "XDP_RST_BTN_R#")
	)
	(segment
		(start 57.57545 -11.57605)
		(end 58.2422 -10.9093)
		(width 0.0889)
		(layer "In9.Cu")
		(net "XDP_RST_BTN_R#")
	)
	(segment
		(start 57.6326 -23.8887)
		(end 57.6326 -17.312386)
		(width 0.0889)
		(layer "In9.Cu")
		(net "XDP_RST_BTN_R#")
	)
	(segment
		(start 57.57545 -17.255236)
		(end 57.57545 -11.57605)
		(width 0.0889)
		(layer "In9.Cu")
		(net "XDP_RST_BTN_R#")
	)
	(segment
		(start 57.531 -23.9903)
		(end 57.6326 -23.8887)
		(width 0.0889)
		(layer "In9.Cu")
		(net "XDP_RST_BTN_R#")
	)
	(segment
		(start 57.6326 -17.312386)
		(end 57.57545 -17.255236)
		(width 0.0889)
		(layer "In9.Cu")
		(net "XDP_RST_BTN_R#")
	)
	(segment
		(start 44.4246 -33.7312)
		(end 44.4246 -32.778192)
		(width 0.1143)
		(layer "F.Cu")
		(net "XDP_PWRBTN_R#")
	)
	(segment
		(start 44.4246 -32.778192)
		(end 44.649898 -32.552894)
		(width 0.1143)
		(layer "F.Cu")
		(net "XDP_PWRBTN_R#")
	)
	(segment
		(start 43.691556 -30.908244)
		(end 44.649898 -31.866586)
		(width 0.1143)
		(layer "F.Cu")
		(net "XDP_PWRBTN_R#")
	)
	(segment
		(start 44.649898 -32.552894)
		(end 44.649898 -32.258)
		(width 0.1143)
		(layer "F.Cu")
		(net "XDP_PWRBTN_R#")
	)
	(segment
		(start 42.10177 -30.05455)
		(end 43.44035 -30.05455)
		(width 0.1143)
		(layer "F.Cu")
		(net "XDP_PWRBTN_R#")
	)
	(segment
		(start 44.958 -34.2646)
		(end 44.4246 -33.7312)
		(width 0.1143)
		(layer "F.Cu")
		(net "XDP_PWRBTN_R#")
	)
	(segment
		(start 43.691556 -30.305756)
		(end 43.691556 -30.908244)
		(width 0.1143)
		(layer "F.Cu")
		(net "XDP_PWRBTN_R#")
	)
	(segment
		(start 43.44035 -30.05455)
		(end 43.691556 -30.305756)
		(width 0.1143)
		(layer "F.Cu")
		(net "XDP_PWRBTN_R#")
	)
	(segment
		(start 44.649898 -31.866586)
		(end 44.649898 -32.258)
		(width 0.1143)
		(layer "F.Cu")
		(net "XDP_PWRBTN_R#")
	)
	(via
		(at 31.5214 -13.5382)
		(size 0.7112)
		(drill 0.3556)
		(layers "F.Cu" "B.Cu")
		(net "XDP_PWRBTN_R#")
	)
	(via
		(at 44.649898 -32.258)
		(size 0.508)
		(drill 0.254)
		(layers "F.Cu" "B.Cu")
		(net "XDP_PWRBTN_R#")
	)
	(via
		(at 30.48 -10.3378)
		(size 0.508)
		(drill 0.254)
		(layers "F.Cu" "B.Cu")
		(net "XDP_PWRBTN_R#")
	)
	(segment
		(start 31.5214 -13.5382)
		(end 31.5214 -11.3792)
		(width 0.1143)
		(layer "B.Cu")
		(net "XDP_PWRBTN_R#")
	)
	(segment
		(start 31.5214 -11.3792)
		(end 30.48 -10.3378)
		(width 0.1143)
		(layer "B.Cu")
		(net "XDP_PWRBTN_R#")
	)
	(segment
		(start 38.306502 -23.545292)
		(end 30.38475 -15.62354)
		(width 0.0889)
		(layer "In9.Cu")
		(net "XDP_PWRBTN_R#")
	)
	(segment
		(start 30.38475 -15.62354)
		(end 30.38475 -15.078456)
		(width 0.0889)
		(layer "In9.Cu")
		(net "XDP_PWRBTN_R#")
	)
	(segment
		(start 30.38475 -15.078456)
		(end 30.95625 -14.506956)
		(width 0.0889)
		(layer "In9.Cu")
		(net "XDP_PWRBTN_R#")
	)
	(segment
		(start 39.70782 -27.076654)
		(end 39.70782 -25.66162)
		(width 0.0889)
		(layer "In9.Cu")
		(net "XDP_PWRBTN_R#")
	)
	(segment
		(start 38.306502 -24.260302)
		(end 38.306502 -23.545292)
		(width 0.0889)
		(layer "In9.Cu")
		(net "XDP_PWRBTN_R#")
	)
	(segment
		(start 44.649898 -32.258)
		(end 44.649898 -32.018732)
		(width 0.0889)
		(layer "In9.Cu")
		(net "XDP_PWRBTN_R#")
	)
	(segment
		(start 44.649898 -32.018732)
		(end 39.70782 -27.076654)
		(width 0.0889)
		(layer "In9.Cu")
		(net "XDP_PWRBTN_R#")
	)
	(segment
		(start 39.70782 -25.66162)
		(end 38.306502 -24.260302)
		(width 0.0889)
		(layer "In9.Cu")
		(net "XDP_PWRBTN_R#")
	)
	(segment
		(start 30.95625 -10.81405)
		(end 30.48 -10.3378)
		(width 0.0889)
		(layer "In9.Cu")
		(net "XDP_PWRBTN_R#")
	)
	(segment
		(start 30.95625 -14.506956)
		(end 30.95625 -10.81405)
		(width 0.0889)
		(layer "In9.Cu")
		(net "XDP_PWRBTN_R#")
	)
	(segment
		(start 129.631948 -15.620746)
		(end 129.632202 -15.620492)
		(width 0.1143)
		(layer "F.Cu")
		(net "SLOT_ID0")
	)
	(segment
		(start 129.16281 -23.433278)
		(end 129.16281 -21.143722)
		(width 0.1143)
		(layer "F.Cu")
		(net "SLOT_ID0")
	)
	(segment
		(start 130.99542 -25.22855)
		(end 130.958082 -25.22855)
		(width 0.1143)
		(layer "F.Cu")
		(net "SLOT_ID0")
	)
	(segment
		(start 129.632202 -20.67433)
		(end 129.632202 -20.264374)
		(width 0.1143)
		(layer "F.Cu")
		(net "SLOT_ID0")
	)
	(segment
		(start 129.16281 -21.143722)
		(end 129.632202 -20.67433)
		(width 0.1143)
		(layer "F.Cu")
		(net "SLOT_ID0")
	)
	(segment
		(start 108.419138 -3.5433)
		(end 109.227874 -3.5433)
		(width 0.1143)
		(layer "F.Cu")
		(net "SLOT_ID0")
	)
	(segment
		(start 136.7409 -29.106368)
		(end 132.932932 -25.2984)
		(width 0.1143)
		(layer "F.Cu")
		(net "SLOT_ID0")
	)
	(segment
		(start 129.632202 -15.210536)
		(end 129.041144 -14.619478)
		(width 0.1143)
		(layer "F.Cu")
		(net "SLOT_ID0")
	)
	(segment
		(start 93.78823 -9.467088)
		(end 93.78823 -9.980676)
		(width 0.1143)
		(layer "F.Cu")
		(net "SLOT_ID0")
	)
	(segment
		(start 113.391188 -6.2357)
		(end 112.465104 -6.2357)
		(width 0.1143)
		(layer "F.Cu")
		(net "SLOT_ID0")
	)
	(segment
		(start 130.958082 -25.22855)
		(end 129.16281 -23.433278)
		(width 0.1143)
		(layer "F.Cu")
		(net "SLOT_ID0")
	)
	(segment
		(start 110.236 -4.551426)
		(end 110.236 -4.699)
		(width 0.1143)
		(layer "F.Cu")
		(net "SLOT_ID0")
	)
	(segment
		(start 110.55985 -5.02285)
		(end 110.236 -4.699)
		(width 0.1143)
		(layer "F.Cu")
		(net "SLOT_ID0")
	)
	(segment
		(start 129.041144 -14.619478)
		(end 126.893066 -14.619478)
		(width 0.1143)
		(layer "F.Cu")
		(net "SLOT_ID0")
	)
	(segment
		(start 132.932932 -25.2984)
		(end 131.06527 -25.2984)
		(width 0.1143)
		(layer "F.Cu")
		(net "SLOT_ID0")
	)
	(segment
		(start 120.261888 -7.9883)
		(end 115.143788 -7.9883)
		(width 0.1143)
		(layer "F.Cu")
		(net "SLOT_ID0")
	)
	(segment
		(start 94.350078 -6.195568)
		(end 94.350078 -8.90524)
		(width 0.1143)
		(layer "F.Cu")
		(net "SLOT_ID0")
	)
	(segment
		(start 134.99846 -45.1612)
		(end 134.99846 -43.30954)
		(width 0.1143)
		(layer "F.Cu")
		(net "SLOT_ID0")
	)
	(segment
		(start 107.188 -2.312162)
		(end 108.419138 -3.5433)
		(width 0.1143)
		(layer "F.Cu")
		(net "SLOT_ID0")
	)
	(segment
		(start 134.99846 -43.30954)
		(end 136.7409 -41.5671)
		(width 0.1143)
		(layer "F.Cu")
		(net "SLOT_ID0")
	)
	(segment
		(start 93.550486 -10.630916)
		(end 93.344238 -10.424668)
		(width 0.1143)
		(layer "F.Cu")
		(net "SLOT_ID0")
	)
	(segment
		(start 129.632202 -20.264374)
		(end 129.631948 -20.26412)
		(width 0.1143)
		(layer "F.Cu")
		(net "SLOT_ID0")
	)
	(segment
		(start 112.465104 -6.2357)
		(end 111.252254 -5.02285)
		(width 0.1143)
		(layer "F.Cu")
		(net "SLOT_ID0")
	)
	(segment
		(start 109.227874 -3.5433)
		(end 110.236 -4.551426)
		(width 0.1143)
		(layer "F.Cu")
		(net "SLOT_ID0")
	)
	(segment
		(start 93.550486 -12.163044)
		(end 93.550486 -10.630916)
		(width 0.1143)
		(layer "F.Cu")
		(net "SLOT_ID0")
	)
	(segment
		(start 94.350078 -8.90524)
		(end 93.78823 -9.467088)
		(width 0.1143)
		(layer "F.Cu")
		(net "SLOT_ID0")
	)
	(segment
		(start 115.143788 -7.9883)
		(end 113.391188 -6.2357)
		(width 0.1143)
		(layer "F.Cu")
		(net "SLOT_ID0")
	)
	(segment
		(start 111.252254 -5.02285)
		(end 110.55985 -5.02285)
		(width 0.1143)
		(layer "F.Cu")
		(net "SLOT_ID0")
	)
	(segment
		(start 93.472 -12.7762)
		(end 93.472 -12.24153)
		(width 0.1143)
		(layer "F.Cu")
		(net "SLOT_ID0")
	)
	(segment
		(start 136.7409 -41.5671)
		(end 136.7409 -29.106368)
		(width 0.1143)
		(layer "F.Cu")
		(net "SLOT_ID0")
	)
	(segment
		(start 129.632202 -15.620492)
		(end 129.632202 -15.210536)
		(width 0.1143)
		(layer "F.Cu")
		(net "SLOT_ID0")
	)
	(segment
		(start 93.472 -12.24153)
		(end 93.550486 -12.163044)
		(width 0.1143)
		(layer "F.Cu")
		(net "SLOT_ID0")
	)
	(segment
		(start 93.78823 -9.980676)
		(end 93.344238 -10.424668)
		(width 0.1143)
		(layer "F.Cu")
		(net "SLOT_ID0")
	)
	(segment
		(start 131.06527 -25.2984)
		(end 130.99542 -25.22855)
		(width 0.1143)
		(layer "F.Cu")
		(net "SLOT_ID0")
	)
	(segment
		(start 126.893066 -14.619478)
		(end 120.261888 -7.9883)
		(width 0.1143)
		(layer "F.Cu")
		(net "SLOT_ID0")
	)
	(segment
		(start 129.631948 -20.26412)
		(end 129.631948 -15.620746)
		(width 0.1143)
		(layer "F.Cu")
		(net "SLOT_ID0")
	)
	(via
		(at 107.188 -2.312162)
		(size 0.508)
		(drill 0.254)
		(layers "F.Cu" "B.Cu")
		(net "SLOT_ID0")
	)
	(via
		(at 110.236 -4.699)
		(size 0.7112)
		(drill 0.3556)
		(layers "F.Cu" "B.Cu")
		(net "SLOT_ID0")
	)
	(via
		(at 93.344238 -10.424668)
		(size 0.508)
		(drill 0.254)
		(layers "F.Cu" "B.Cu")
		(net "SLOT_ID0")
	)
	(segment
		(start 107.188 -2.312162)
		(end 105.816146 -3.684016)
		(width 0.0889)
		(layer "In7.Cu")
		(net "SLOT_ID0")
	)
	(segment
		(start 105.816146 -3.684016)
		(end 105.816146 -11.438636)
		(width 0.0889)
		(layer "In7.Cu")
		(net "SLOT_ID0")
	)
	(segment
		(start 104.732582 -12.5222)
		(end 94.0562 -12.5222)
		(width 0.0889)
		(layer "In7.Cu")
		(net "SLOT_ID0")
	)
	(segment
		(start 94.0562 -12.5222)
		(end 93.537786 -12.003786)
		(width 0.0889)
		(layer "In7.Cu")
		(net "SLOT_ID0")
	)
	(segment
		(start 105.816146 -11.438636)
		(end 104.732582 -12.5222)
		(width 0.0889)
		(layer "In7.Cu")
		(net "SLOT_ID0")
	)
	(segment
		(start 93.537786 -12.003786)
		(end 93.537786 -10.618216)
		(width 0.0889)
		(layer "In7.Cu")
		(net "SLOT_ID0")
	)
	(segment
		(start 93.537786 -10.618216)
		(end 93.344238 -10.424668)
		(width 0.0889)
		(layer "In7.Cu")
		(net "SLOT_ID0")
	)
	(segment
		(start 111.13516 -6.96595)
		(end 111.09071 -6.96595)
		(width 0.1143)
		(layer "F.Cu")
		(net "PROCESSOR_HOT_LVC#")
	)
	(segment
		(start 118.4402 -10.346436)
		(end 117.491764 -9.398)
		(width 0.1143)
		(layer "F.Cu")
		(net "PROCESSOR_HOT_LVC#")
	)
	(segment
		(start 118.4402 -13.5128)
		(end 118.4402 -10.346436)
		(width 0.1143)
		(layer "F.Cu")
		(net "PROCESSOR_HOT_LVC#")
	)
	(segment
		(start 111.09071 -6.96595)
		(end 110.80496 -6.6802)
		(width 0.1143)
		(layer "F.Cu")
		(net "PROCESSOR_HOT_LVC#")
	)
	(segment
		(start 128.25857 -27.29357)
		(end 126.3523 -25.3873)
		(width 0.1143)
		(layer "F.Cu")
		(net "PROCESSOR_HOT_LVC#")
	)
	(segment
		(start 113.56721 -9.398)
		(end 111.13516 -6.96595)
		(width 0.1143)
		(layer "F.Cu")
		(net "PROCESSOR_HOT_LVC#")
	)
	(segment
		(start 117.491764 -9.398)
		(end 113.56721 -9.398)
		(width 0.1143)
		(layer "F.Cu")
		(net "PROCESSOR_HOT_LVC#")
	)
	(segment
		(start 119.697246 -21.504656)
		(end 119.697246 -14.769846)
		(width 0.1143)
		(layer "F.Cu")
		(net "PROCESSOR_HOT_LVC#")
	)
	(segment
		(start 119.697246 -14.769846)
		(end 118.4402 -13.5128)
		(width 0.1143)
		(layer "F.Cu")
		(net "PROCESSOR_HOT_LVC#")
	)
	(segment
		(start 132.1308 -27.29357)
		(end 128.25857 -27.29357)
		(width 0.1143)
		(layer "F.Cu")
		(net "PROCESSOR_HOT_LVC#")
	)
	(segment
		(start 126.3523 -25.3873)
		(end 123.57989 -25.3873)
		(width 0.1143)
		(layer "F.Cu")
		(net "PROCESSOR_HOT_LVC#")
	)
	(segment
		(start 123.57989 -25.3873)
		(end 119.697246 -21.504656)
		(width 0.1143)
		(layer "F.Cu")
		(net "PROCESSOR_HOT_LVC#")
	)
	(via
		(at 110.80496 -6.6802)
		(size 0.508)
		(drill 0.254)
		(layers "F.Cu" "B.Cu")
		(net "PROCESSOR_HOT_LVC#")
	)
	(via
		(at 84.963 -52.705)
		(size 0.7112)
		(drill 0.3556)
		(layers "F.Cu" "B.Cu")
		(net "PROCESSOR_HOT_LVC#")
	)
	(via
		(at 90.6526 -47.2694)
		(size 0.4318)
		(drill 0.2032)
		(layers "F.Cu" "B.Cu")
		(net "PROCESSOR_HOT_LVC#")
	)
	(via
		(at 85.471 -51.9684)
		(size 0.4318)
		(drill 0.2032)
		(layers "F.Cu" "B.Cu")
		(net "PROCESSOR_HOT_LVC#")
	)
	(segment
		(start 86.233 -62.8142)
		(end 86.233 -62.299596)
		(width 0.1143)
		(layer "B.Cu")
		(net "PROCESSOR_HOT_LVC#")
	)
	(segment
		(start 85.5218 -63.5254)
		(end 86.233 -62.8142)
		(width 0.1143)
		(layer "B.Cu")
		(net "PROCESSOR_HOT_LVC#")
	)
	(segment
		(start 85.258402 -56.528208)
		(end 84.686394 -55.9562)
		(width 0.1143)
		(layer "B.Cu")
		(net "PROCESSOR_HOT_LVC#")
	)
	(segment
		(start 85.258402 -61.324998)
		(end 85.258402 -56.528208)
		(width 0.1143)
		(layer "B.Cu")
		(net "PROCESSOR_HOT_LVC#")
	)
	(segment
		(start 84.963 -53.8226)
		(end 84.963 -52.705)
		(width 0.1143)
		(layer "B.Cu")
		(net "PROCESSOR_HOT_LVC#")
	)
	(segment
		(start 84.963 -52.4764)
		(end 85.471 -51.9684)
		(width 0.1143)
		(layer "B.Cu")
		(net "PROCESSOR_HOT_LVC#")
	)
	(segment
		(start 84.963 -52.705)
		(end 84.963 -52.4764)
		(width 0.1143)
		(layer "B.Cu")
		(net "PROCESSOR_HOT_LVC#")
	)
	(segment
		(start 84.686394 -54.099206)
		(end 84.963 -53.8226)
		(width 0.1143)
		(layer "B.Cu")
		(net "PROCESSOR_HOT_LVC#")
	)
	(segment
		(start 86.233 -62.299596)
		(end 85.258402 -61.324998)
		(width 0.1143)
		(layer "B.Cu")
		(net "PROCESSOR_HOT_LVC#")
	)
	(segment
		(start 84.709 -63.5254)
		(end 85.5218 -63.5254)
		(width 0.1143)
		(layer "B.Cu")
		(net "PROCESSOR_HOT_LVC#")
	)
	(segment
		(start 84.686394 -55.9562)
		(end 84.686394 -54.099206)
		(width 0.1143)
		(layer "B.Cu")
		(net "PROCESSOR_HOT_LVC#")
	)
	(segment
		(start 89.4588 -49.66716)
		(end 89.4588 -48.4632)
		(width 0.0889)
		(layer "In2.Cu")
		(net "PROCESSOR_HOT_LVC#")
	)
	(segment
		(start 89.4588 -48.4632)
		(end 90.6526 -47.2694)
		(width 0.0889)
		(layer "In2.Cu")
		(net "PROCESSOR_HOT_LVC#")
	)
	(segment
		(start 85.471 -51.9684)
		(end 87.15756 -51.9684)
		(width 0.0889)
		(layer "In2.Cu")
		(net "PROCESSOR_HOT_LVC#")
	)
	(segment
		(start 87.15756 -51.9684)
		(end 89.4588 -49.66716)
		(width 0.0889)
		(layer "In2.Cu")
		(net "PROCESSOR_HOT_LVC#")
	)
	(segment
		(start 106.71302 -17.243806)
		(end 111.221774 -12.735052)
		(width 0.0889)
		(layer "In9.Cu")
		(net "PROCESSOR_HOT_LVC#")
	)
	(segment
		(start 87.938864 -35.268154)
		(end 87.938864 -34.014664)
		(width 0.0889)
		(layer "In9.Cu")
		(net "PROCESSOR_HOT_LVC#")
	)
	(segment
		(start 86.6394 -32.7152)
		(end 86.6394 -32.304736)
		(width 0.0889)
		(layer "In9.Cu")
		(net "PROCESSOR_HOT_LVC#")
	)
	(segment
		(start 90.6526 -43.2308)
		(end 89.88425 -42.46245)
		(width 0.0889)
		(layer "In9.Cu")
		(net "PROCESSOR_HOT_LVC#")
	)
	(segment
		(start 94.44355 -16.84655)
		(end 94.840806 -17.243806)
		(width 0.0889)
		(layer "In9.Cu")
		(net "PROCESSOR_HOT_LVC#")
	)
	(segment
		(start 87.938864 -34.014664)
		(end 86.6394 -32.7152)
		(width 0.0889)
		(layer "In9.Cu")
		(net "PROCESSOR_HOT_LVC#")
	)
	(segment
		(start 84.68995 -24.92375)
		(end 84.68995 -20.745958)
		(width 0.0889)
		(layer "In9.Cu")
		(net "PROCESSOR_HOT_LVC#")
	)
	(segment
		(start 89.88425 -37.21354)
		(end 87.938864 -35.268154)
		(width 0.0889)
		(layer "In9.Cu")
		(net "PROCESSOR_HOT_LVC#")
	)
	(segment
		(start 111.221774 -12.735052)
		(end 111.221774 -7.097014)
		(width 0.0889)
		(layer "In9.Cu")
		(net "PROCESSOR_HOT_LVC#")
	)
	(segment
		(start 86.6394 -32.304736)
		(end 85.12175 -30.787086)
		(width 0.0889)
		(layer "In9.Cu")
		(net "PROCESSOR_HOT_LVC#")
	)
	(segment
		(start 88.589358 -16.84655)
		(end 94.44355 -16.84655)
		(width 0.0889)
		(layer "In9.Cu")
		(net "PROCESSOR_HOT_LVC#")
	)
	(segment
		(start 90.6526 -47.2694)
		(end 90.6526 -43.2308)
		(width 0.0889)
		(layer "In9.Cu")
		(net "PROCESSOR_HOT_LVC#")
	)
	(segment
		(start 89.88425 -42.46245)
		(end 89.88425 -37.21354)
		(width 0.0889)
		(layer "In9.Cu")
		(net "PROCESSOR_HOT_LVC#")
	)
	(segment
		(start 84.68995 -20.745958)
		(end 88.589358 -16.84655)
		(width 0.0889)
		(layer "In9.Cu")
		(net "PROCESSOR_HOT_LVC#")
	)
	(segment
		(start 85.12175 -25.35555)
		(end 84.68995 -24.92375)
		(width 0.0889)
		(layer "In9.Cu")
		(net "PROCESSOR_HOT_LVC#")
	)
	(segment
		(start 85.12175 -30.787086)
		(end 85.12175 -25.35555)
		(width 0.0889)
		(layer "In9.Cu")
		(net "PROCESSOR_HOT_LVC#")
	)
	(segment
		(start 94.840806 -17.243806)
		(end 106.71302 -17.243806)
		(width 0.0889)
		(layer "In9.Cu")
		(net "PROCESSOR_HOT_LVC#")
	)
	(segment
		(start 111.221774 -7.097014)
		(end 110.80496 -6.6802)
		(width 0.0889)
		(layer "In9.Cu")
		(net "PROCESSOR_HOT_LVC#")
	)
	(segment
		(start 128.44145 -67.368674)
		(end 128.78816 -67.715384)
		(width 0.1143)
		(layer "F.Cu")
		(net "MEMORY_HOT_LV_R#")
	)
	(segment
		(start 128.649984 -63.75527)
		(end 128.44145 -63.963804)
		(width 0.1143)
		(layer "F.Cu")
		(net "MEMORY_HOT_LV_R#")
	)
	(segment
		(start 127.648462 -52.996338)
		(end 127.648462 -59.322462)
		(width 0.1143)
		(layer "F.Cu")
		(net "MEMORY_HOT_LV_R#")
	)
	(segment
		(start 128.78816 -67.715384)
		(end 128.78816 -69.076824)
		(width 0.1143)
		(layer "F.Cu")
		(net "MEMORY_HOT_LV_R#")
	)
	(segment
		(start 127.648462 -59.322462)
		(end 128.649984 -60.323984)
		(width 0.1143)
		(layer "F.Cu")
		(net "MEMORY_HOT_LV_R#")
	)
	(segment
		(start 128.524 -52.1208)
		(end 127.648462 -52.996338)
		(width 0.1143)
		(layer "F.Cu")
		(net "MEMORY_HOT_LV_R#")
	)
	(segment
		(start 131.699 -52.1208)
		(end 130.556 -52.1208)
		(width 0.1143)
		(layer "F.Cu")
		(net "MEMORY_HOT_LV_R#")
	)
	(segment
		(start 130.556 -52.1208)
		(end 128.524 -52.1208)
		(width 0.1143)
		(layer "F.Cu")
		(net "MEMORY_HOT_LV_R#")
	)
	(segment
		(start 128.78816 -69.076824)
		(end 128.649984 -69.215)
		(width 0.1143)
		(layer "F.Cu")
		(net "MEMORY_HOT_LV_R#")
	)
	(segment
		(start 128.649984 -60.323984)
		(end 128.649984 -62.59322)
		(width 0.1143)
		(layer "F.Cu")
		(net "MEMORY_HOT_LV_R#")
	)
	(segment
		(start 189.850014 -9.897364)
		(end 189.850014 -8.383778)
		(width 0.1143)
		(layer "F.Cu")
		(net "MEMORY_HOT_LV_R#")
	)
	(segment
		(start 128.44145 -63.963804)
		(end 128.44145 -67.368674)
		(width 0.1143)
		(layer "F.Cu")
		(net "MEMORY_HOT_LV_R#")
	)
	(segment
		(start 128.649984 -62.59322)
		(end 128.649984 -63.75527)
		(width 0.1143)
		(layer "F.Cu")
		(net "MEMORY_HOT_LV_R#")
	)
	(via
		(at 189.850014 -8.383778)
		(size 0.4318)
		(drill 0.2032)
		(layers "F.Cu" "B.Cu")
		(net "MEMORY_HOT_LV_R#")
	)
	(via
		(at 128.649984 -69.215)
		(size 0.4318)
		(drill 0.2032)
		(layers "F.Cu" "B.Cu")
		(net "MEMORY_HOT_LV_R#")
	)
	(via
		(at 130.556 -52.1208)
		(size 0.7112)
		(drill 0.3556)
		(layers "F.Cu" "B.Cu")
		(net "MEMORY_HOT_LV_R#")
	)
	(via
		(at 122.5296 -67.6148)
		(size 0.508)
		(drill 0.254)
		(layers "F.Cu" "B.Cu")
		(net "MEMORY_HOT_LV_R#")
	)
	(via
		(at 78.486 -67.7418)
		(size 0.508)
		(drill 0.254)
		(layers "F.Cu" "B.Cu")
		(net "MEMORY_HOT_LV_R#")
	)
	(segment
		(start 66.90995 -54.839108)
		(end 66.90995 -55.67934)
		(width 0.1143)
		(layer "B.Cu")
		(net "MEMORY_HOT_LV_R#")
	)
	(segment
		(start 189.850014 -1.690624)
		(end 189.850014 -3.183636)
		(width 0.1143)
		(layer "B.Cu")
		(net "MEMORY_HOT_LV_R#")
	)
	(segment
		(start 72.9996 -63.7794)
		(end 72.52335 -64.25565)
		(width 0.1143)
		(layer "B.Cu")
		(net "MEMORY_HOT_LV_R#")
	)
	(segment
		(start 127.3937 -67.9577)
		(end 128.649984 -69.213984)
		(width 0.1143)
		(layer "B.Cu")
		(net "MEMORY_HOT_LV_R#")
	)
	(segment
		(start 189.850014 -7.528814)
		(end 189.850014 -8.383778)
		(width 0.1143)
		(layer "B.Cu")
		(net "MEMORY_HOT_LV_R#")
	)
	(segment
		(start 74.980038 -68.367148)
		(end 77.860652 -68.367148)
		(width 0.1143)
		(layer "B.Cu")
		(net "MEMORY_HOT_LV_R#")
	)
	(segment
		(start 70.485 -53.0352)
		(end 68.713858 -53.0352)
		(width 0.1143)
		(layer "B.Cu")
		(net "MEMORY_HOT_LV_R#")
	)
	(segment
		(start 73.00595 -66.39306)
		(end 74.980038 -68.367148)
		(width 0.1143)
		(layer "B.Cu")
		(net "MEMORY_HOT_LV_R#")
	)
	(segment
		(start 66.90995 -55.67934)
		(end 72.9996 -61.76899)
		(width 0.1143)
		(layer "B.Cu")
		(net "MEMORY_HOT_LV_R#")
	)
	(segment
		(start 73.00595 -65.3288)
		(end 73.00595 -66.39306)
		(width 0.1143)
		(layer "B.Cu")
		(net "MEMORY_HOT_LV_R#")
	)
	(segment
		(start 71.247 -53.0352)
		(end 70.485 -53.0352)
		(width 0.1143)
		(layer "B.Cu")
		(net "MEMORY_HOT_LV_R#")
	)
	(segment
		(start 77.860652 -68.367148)
		(end 78.486 -67.7418)
		(width 0.1143)
		(layer "B.Cu")
		(net "MEMORY_HOT_LV_R#")
	)
	(segment
		(start 188.80455 -4.2291)
		(end 188.80455 -6.48335)
		(width 0.1143)
		(layer "B.Cu")
		(net "MEMORY_HOT_LV_R#")
	)
	(segment
		(start 72.9996 -61.76899)
		(end 72.9996 -63.7794)
		(width 0.1143)
		(layer "B.Cu")
		(net "MEMORY_HOT_LV_R#")
	)
	(segment
		(start 189.850014 -3.183636)
		(end 188.80455 -4.2291)
		(width 0.1143)
		(layer "B.Cu")
		(net "MEMORY_HOT_LV_R#")
	)
	(segment
		(start 128.649984 -69.213984)
		(end 128.649984 -69.215)
		(width 0.1143)
		(layer "B.Cu")
		(net "MEMORY_HOT_LV_R#")
	)
	(segment
		(start 122.8725 -67.9577)
		(end 127.3937 -67.9577)
		(width 0.1143)
		(layer "B.Cu")
		(net "MEMORY_HOT_LV_R#")
	)
	(segment
		(start 72.52335 -64.8462)
		(end 73.00595 -65.3288)
		(width 0.1143)
		(layer "B.Cu")
		(net "MEMORY_HOT_LV_R#")
	)
	(segment
		(start 72.52335 -64.25565)
		(end 72.52335 -64.8462)
		(width 0.1143)
		(layer "B.Cu")
		(net "MEMORY_HOT_LV_R#")
	)
	(segment
		(start 68.713858 -53.0352)
		(end 66.90995 -54.839108)
		(width 0.1143)
		(layer "B.Cu")
		(net "MEMORY_HOT_LV_R#")
	)
	(segment
		(start 188.80455 -6.48335)
		(end 189.850014 -7.528814)
		(width 0.1143)
		(layer "B.Cu")
		(net "MEMORY_HOT_LV_R#")
	)
	(segment
		(start 122.5296 -67.6148)
		(end 122.8725 -67.9577)
		(width 0.1143)
		(layer "B.Cu")
		(net "MEMORY_HOT_LV_R#")
	)
	(segment
		(start 128.649984 -70.79996)
		(end 128.649984 -69.215)
		(width 0.1143)
		(layer "B.Cu")
		(net "MEMORY_HOT_LV_R#")
	)
	(segment
		(start 189.850014 -11.839956)
		(end 189.76975 -11.92022)
		(width 0.0889)
		(layer "In2.Cu")
		(net "MEMORY_HOT_LV_R#")
	)
	(segment
		(start 100.27285 -69.663056)
		(end 100.27285 -71.204328)
		(width 0.0889)
		(layer "In2.Cu")
		(net "MEMORY_HOT_LV_R#")
	)
	(segment
		(start 79.087726 -69.562726)
		(end 87.917274 -69.562726)
		(width 0.0889)
		(layer "In2.Cu")
		(net "MEMORY_HOT_LV_R#")
	)
	(segment
		(start 113.603278 -72.4789)
		(end 115.44935 -70.632828)
		(width 0.0889)
		(layer "In2.Cu")
		(net "MEMORY_HOT_LV_R#")
	)
	(segment
		(start 118.100856 -67.08775)
		(end 122.00255 -67.08775)
		(width 0.0889)
		(layer "In2.Cu")
		(net "MEMORY_HOT_LV_R#")
	)
	(segment
		(start 194.564 -63.1444)
		(end 194.564 -68.7324)
		(width 0.0889)
		(layer "In2.Cu")
		(net "MEMORY_HOT_LV_R#")
	)
	(segment
		(start 183.41975 -44.91355)
		(end 185.7502 -47.244)
		(width 0.0889)
		(layer "In2.Cu")
		(net "MEMORY_HOT_LV_R#")
	)
	(segment
		(start 122.00255 -67.08775)
		(end 122.5296 -67.6148)
		(width 0.0889)
		(layer "In2.Cu")
		(net "MEMORY_HOT_LV_R#")
	)
	(segment
		(start 78.486 -68.961)
		(end 79.087726 -69.562726)
		(width 0.0889)
		(layer "In2.Cu")
		(net "MEMORY_HOT_LV_R#")
	)
	(segment
		(start 115.44935 -69.739256)
		(end 118.100856 -67.08775)
		(width 0.0889)
		(layer "In2.Cu")
		(net "MEMORY_HOT_LV_R#")
	)
	(segment
		(start 78.486 -67.7418)
		(end 78.486 -68.961)
		(width 0.0889)
		(layer "In2.Cu")
		(net "MEMORY_HOT_LV_R#")
	)
	(segment
		(start 189.76975 -18.14322)
		(end 183.41975 -24.49322)
		(width 0.0889)
		(layer "In2.Cu")
		(net "MEMORY_HOT_LV_R#")
	)
	(segment
		(start 185.7502 -47.244)
		(end 185.7502 -52.164488)
		(width 0.0889)
		(layer "In2.Cu")
		(net "MEMORY_HOT_LV_R#")
	)
	(segment
		(start 194.564 -68.7324)
		(end 190.302896 -72.993504)
		(width 0.0889)
		(layer "In2.Cu")
		(net "MEMORY_HOT_LV_R#")
	)
	(segment
		(start 185.7502 -52.164488)
		(end 186.59475 -53.009038)
		(width 0.0889)
		(layer "In2.Cu")
		(net "MEMORY_HOT_LV_R#")
	)
	(segment
		(start 189.76975 -11.92022)
		(end 189.76975 -18.14322)
		(width 0.0889)
		(layer "In2.Cu")
		(net "MEMORY_HOT_LV_R#")
	)
	(segment
		(start 186.59475 -55.17515)
		(end 194.564 -63.1444)
		(width 0.0889)
		(layer "In2.Cu")
		(net "MEMORY_HOT_LV_R#")
	)
	(segment
		(start 122.5296 -68.5546)
		(end 122.5296 -67.6148)
		(width 0.0889)
		(layer "In2.Cu")
		(net "MEMORY_HOT_LV_R#")
	)
	(segment
		(start 190.302896 -72.993504)
		(end 126.968504 -72.993504)
		(width 0.0889)
		(layer "In2.Cu")
		(net "MEMORY_HOT_LV_R#")
	)
	(segment
		(start 100.27285 -71.204328)
		(end 101.547422 -72.4789)
		(width 0.0889)
		(layer "In2.Cu")
		(net "MEMORY_HOT_LV_R#")
	)
	(segment
		(start 88.14435 -69.33565)
		(end 99.945444 -69.33565)
		(width 0.0889)
		(layer "In2.Cu")
		(net "MEMORY_HOT_LV_R#")
	)
	(segment
		(start 99.945444 -69.33565)
		(end 100.27285 -69.663056)
		(width 0.0889)
		(layer "In2.Cu")
		(net "MEMORY_HOT_LV_R#")
	)
	(segment
		(start 183.41975 -24.49322)
		(end 183.41975 -44.91355)
		(width 0.0889)
		(layer "In2.Cu")
		(net "MEMORY_HOT_LV_R#")
	)
	(segment
		(start 115.44935 -70.632828)
		(end 115.44935 -69.739256)
		(width 0.0889)
		(layer "In2.Cu")
		(net "MEMORY_HOT_LV_R#")
	)
	(segment
		(start 101.547422 -72.4789)
		(end 113.603278 -72.4789)
		(width 0.0889)
		(layer "In2.Cu")
		(net "MEMORY_HOT_LV_R#")
	)
	(segment
		(start 126.968504 -72.993504)
		(end 122.5296 -68.5546)
		(width 0.0889)
		(layer "In2.Cu")
		(net "MEMORY_HOT_LV_R#")
	)
	(segment
		(start 87.917274 -69.562726)
		(end 88.14435 -69.33565)
		(width 0.0889)
		(layer "In2.Cu")
		(net "MEMORY_HOT_LV_R#")
	)
	(segment
		(start 189.850014 -8.383778)
		(end 189.850014 -11.839956)
		(width 0.0889)
		(layer "In2.Cu")
		(net "MEMORY_HOT_LV_R#")
	)
	(segment
		(start 186.59475 -53.009038)
		(end 186.59475 -55.17515)
		(width 0.0889)
		(layer "In2.Cu")
		(net "MEMORY_HOT_LV_R#")
	)
	(segment
		(start 131.560824 -23.2918)
		(end 130.937508 -22.668738)
		(width 0.1143)
		(layer "F.Cu")
		(net "CPU_THERMTRIP_LVC#")
	)
	(segment
		(start 133.9977 -23.50516)
		(end 133.78434 -23.2918)
		(width 0.1143)
		(layer "F.Cu")
		(net "CPU_THERMTRIP_LVC#")
	)
	(segment
		(start 133.78434 -23.2918)
		(end 131.560824 -23.2918)
		(width 0.1143)
		(layer "F.Cu")
		(net "CPU_THERMTRIP_LVC#")
	)
	(segment
		(start 130.937508 -22.668738)
		(end 130.937508 -22.605492)
		(width 0.1143)
		(layer "F.Cu")
		(net "CPU_THERMTRIP_LVC#")
	)
	(segment
		(start 133.9977 -23.9268)
		(end 133.9977 -23.50516)
		(width 0.1143)
		(layer "F.Cu")
		(net "CPU_THERMTRIP_LVC#")
	)
	(via
		(at 130.937508 -22.605492)
		(size 0.508)
		(drill 0.254)
		(layers "F.Cu" "B.Cu")
		(net "CPU_THERMTRIP_LVC#")
	)
	(via
		(at 131.191 -23.5204)
		(size 0.7112)
		(drill 0.3556)
		(layers "F.Cu" "B.Cu")
		(net "CPU_THERMTRIP_LVC#")
	)
	(segment
		(start 130.4798 -24.9428)
		(end 130.81 -24.6126)
		(width 0.1143)
		(layer "B.Cu")
		(net "CPU_THERMTRIP_LVC#")
	)
	(segment
		(start 131.191 -23.5204)
		(end 131.191 -22.858984)
		(width 0.1143)
		(layer "B.Cu")
		(net "CPU_THERMTRIP_LVC#")
	)
	(segment
		(start 129.286 -25.7048)
		(end 129.6162 -25.7048)
		(width 0.1143)
		(layer "B.Cu")
		(net "CPU_THERMTRIP_LVC#")
	)
	(segment
		(start 129.6162 -25.7048)
		(end 130.3782 -24.9428)
		(width 0.1143)
		(layer "B.Cu")
		(net "CPU_THERMTRIP_LVC#")
	)
	(segment
		(start 130.3782 -24.9428)
		(end 130.4798 -24.9428)
		(width 0.1143)
		(layer "B.Cu")
		(net "CPU_THERMTRIP_LVC#")
	)
	(segment
		(start 130.81 -24.6126)
		(end 131.191 -24.2316)
		(width 0.1143)
		(layer "B.Cu")
		(net "CPU_THERMTRIP_LVC#")
	)
	(segment
		(start 131.191 -22.858984)
		(end 130.937508 -22.605492)
		(width 0.1143)
		(layer "B.Cu")
		(net "CPU_THERMTRIP_LVC#")
	)
	(segment
		(start 131.191 -24.2316)
		(end 131.191 -23.5204)
		(width 0.1143)
		(layer "B.Cu")
		(net "CPU_THERMTRIP_LVC#")
	)
	(segment
		(start 82.2706 -32.9946)
		(end 82.289142 -32.9946)
		(width 0.1143)
		(layer "F.Cu")
		(net "GBE_SMBDATA")
	)
	(segment
		(start 75.7682 -25.273)
		(end 75.057 -25.273)
		(width 0.1143)
		(layer "F.Cu")
		(net "GBE_SMBDATA")
	)
	(segment
		(start 58.74004 -15.78356)
		(end 58.74004 -14.5923)
		(width 0.1143)
		(layer "F.Cu")
		(net "GBE_SMBDATA")
	)
	(segment
		(start 74.3458 -24.6888)
		(end 74.1172 -24.6888)
		(width 0.1143)
		(layer "F.Cu")
		(net "GBE_SMBDATA")
	)
	(segment
		(start 75.057 -25.273)
		(end 74.93 -25.273)
		(width 0.1143)
		(layer "F.Cu")
		(net "GBE_SMBDATA")
	)
	(segment
		(start 82.766916 -33.472374)
		(end 82.885788 -33.472374)
		(width 0.1143)
		(layer "F.Cu")
		(net "GBE_SMBDATA")
	)
	(segment
		(start 82.289142 -32.9946)
		(end 82.766916 -33.472374)
		(width 0.1143)
		(layer "F.Cu")
		(net "GBE_SMBDATA")
	)
	(segment
		(start 76.0222 -25.019)
		(end 75.7682 -25.273)
		(width 0.1143)
		(layer "F.Cu")
		(net "GBE_SMBDATA")
	)
	(segment
		(start 58.5216 -16.002)
		(end 58.74004 -15.78356)
		(width 0.1143)
		(layer "F.Cu")
		(net "GBE_SMBDATA")
	)
	(segment
		(start 74.93 -25.273)
		(end 74.3458 -24.6888)
		(width 0.1143)
		(layer "F.Cu")
		(net "GBE_SMBDATA")
	)
	(via
		(at 76.0222 -25.019)
		(size 0.508)
		(drill 0.254)
		(layers "F.Cu" "B.Cu")
		(net "GBE_SMBDATA")
	)
	(via
		(at 75.057 -25.273)
		(size 0.7112)
		(drill 0.3556)
		(layers "F.Cu" "B.Cu")
		(net "GBE_SMBDATA")
	)
	(via
		(at 58.5216 -16.002)
		(size 0.508)
		(drill 0.254)
		(layers "F.Cu" "B.Cu")
		(net "GBE_SMBDATA")
	)
	(via
		(at 82.2706 -32.9946)
		(size 0.4318)
		(drill 0.2032)
		(layers "F.Cu" "B.Cu")
		(net "GBE_SMBDATA")
	)
	(segment
		(start 82.62239 -31.8008)
		(end 83.018122 -32.196532)
		(width 0.0889)
		(layer "In7.Cu")
		(net "GBE_SMBDATA")
	)
	(segment
		(start 77.47889 -29.237432)
		(end 77.737208 -29.49575)
		(width 0.0889)
		(layer "In7.Cu")
		(net "GBE_SMBDATA")
	)
	(segment
		(start 80.672432 -31.062168)
		(end 80.672432 -31.523432)
		(width 0.0889)
		(layer "In7.Cu")
		(net "GBE_SMBDATA")
	)
	(segment
		(start 78.908148 -29.627068)
		(end 79.237332 -29.627068)
		(width 0.0889)
		(layer "In7.Cu")
		(net "GBE_SMBDATA")
	)
	(segment
		(start 71.120762 -21.012404)
		(end 73.7616 -23.653242)
		(width 0.0889)
		(layer "In7.Cu")
		(net "GBE_SMBDATA")
	)
	(segment
		(start 82.578956 -32.935926)
		(end 82.329274 -32.935926)
		(width 0.0889)
		(layer "In7.Cu")
		(net "GBE_SMBDATA")
	)
	(segment
		(start 80.9498 -31.8008)
		(end 82.62239 -31.8008)
		(width 0.0889)
		(layer "In7.Cu")
		(net "GBE_SMBDATA")
	)
	(segment
		(start 58.9661 -15.5575)
		(end 61.3791 -15.5575)
		(width 0.0889)
		(layer "In7.Cu")
		(net "GBE_SMBDATA")
	)
	(segment
		(start 77.47889 -26.47569)
		(end 77.47889 -29.237432)
		(width 0.0889)
		(layer "In7.Cu")
		(net "GBE_SMBDATA")
	)
	(segment
		(start 83.018122 -32.49676)
		(end 82.578956 -32.935926)
		(width 0.0889)
		(layer "In7.Cu")
		(net "GBE_SMBDATA")
	)
	(segment
		(start 69.477382 -21.012404)
		(end 71.120762 -21.012404)
		(width 0.0889)
		(layer "In7.Cu")
		(net "GBE_SMBDATA")
	)
	(segment
		(start 77.737208 -29.49575)
		(end 78.77683 -29.49575)
		(width 0.0889)
		(layer "In7.Cu")
		(net "GBE_SMBDATA")
	)
	(segment
		(start 58.5216 -16.002)
		(end 58.9661 -15.5575)
		(width 0.0889)
		(layer "In7.Cu")
		(net "GBE_SMBDATA")
	)
	(segment
		(start 76.004674 -25.001474)
		(end 76.0222 -25.019)
		(width 0.0889)
		(layer "In7.Cu")
		(net "GBE_SMBDATA")
	)
	(segment
		(start 79.237332 -29.627068)
		(end 80.672432 -31.062168)
		(width 0.0889)
		(layer "In7.Cu")
		(net "GBE_SMBDATA")
	)
	(segment
		(start 83.018122 -32.196532)
		(end 83.018122 -32.49676)
		(width 0.0889)
		(layer "In7.Cu")
		(net "GBE_SMBDATA")
	)
	(segment
		(start 78.77683 -29.49575)
		(end 78.908148 -29.627068)
		(width 0.0889)
		(layer "In7.Cu")
		(net "GBE_SMBDATA")
	)
	(segment
		(start 68.080128 -19.61515)
		(end 69.477382 -21.012404)
		(width 0.0889)
		(layer "In7.Cu")
		(net "GBE_SMBDATA")
	)
	(segment
		(start 61.3791 -15.5575)
		(end 65.43675 -19.61515)
		(width 0.0889)
		(layer "In7.Cu")
		(net "GBE_SMBDATA")
	)
	(segment
		(start 76.0222 -25.019)
		(end 77.47889 -26.47569)
		(width 0.0889)
		(layer "In7.Cu")
		(net "GBE_SMBDATA")
	)
	(segment
		(start 74.353674 -25.001474)
		(end 76.004674 -25.001474)
		(width 0.0889)
		(layer "In7.Cu")
		(net "GBE_SMBDATA")
	)
	(segment
		(start 73.7616 -23.653242)
		(end 73.7616 -24.4094)
		(width 0.0889)
		(layer "In7.Cu")
		(net "GBE_SMBDATA")
	)
	(segment
		(start 80.672432 -31.523432)
		(end 80.9498 -31.8008)
		(width 0.0889)
		(layer "In7.Cu")
		(net "GBE_SMBDATA")
	)
	(segment
		(start 82.329274 -32.935926)
		(end 82.2706 -32.9946)
		(width 0.0889)
		(layer "In7.Cu")
		(net "GBE_SMBDATA")
	)
	(segment
		(start 65.43675 -19.61515)
		(end 68.080128 -19.61515)
		(width 0.0889)
		(layer "In7.Cu")
		(net "GBE_SMBDATA")
	)
	(segment
		(start 73.7616 -24.4094)
		(end 74.353674 -25.001474)
		(width 0.0889)
		(layer "In7.Cu")
		(net "GBE_SMBDATA")
	)
	(segment
		(start 51.7779 -21.5646)
		(end 53.0352 -21.5646)
		(width 0.1143)
		(layer "F.Cu")
		(net "SPI_CS_GBE#")
	)
	(segment
		(start 53.0352 -21.5646)
		(end 53.7464 -20.8534)
		(width 0.1143)
		(layer "F.Cu")
		(net "SPI_CS_GBE#")
	)
	(segment
		(start 82.885788 -32.576262)
		(end 82.656172 -32.346646)
		(width 0.1143)
		(layer "F.Cu")
		(net "SPI_CS_GBE#")
	)
	(segment
		(start 82.885788 -32.771334)
		(end 82.885788 -32.576262)
		(width 0.1143)
		(layer "F.Cu")
		(net "SPI_CS_GBE#")
	)
	(via
		(at 81.4324 -32.0294)
		(size 0.7112)
		(drill 0.3556)
		(layers "F.Cu" "B.Cu")
		(net "SPI_CS_GBE#")
	)
	(via
		(at 82.656172 -32.346646)
		(size 0.4318)
		(drill 0.2032)
		(layers "F.Cu" "B.Cu")
		(net "SPI_CS_GBE#")
	)
	(via
		(at 53.7464 -20.8534)
		(size 0.508)
		(drill 0.254)
		(layers "F.Cu" "B.Cu")
		(net "SPI_CS_GBE#")
	)
	(segment
		(start 82.338926 -32.0294)
		(end 82.656172 -32.346646)
		(width 0.1143)
		(layer "B.Cu")
		(net "SPI_CS_GBE#")
	)
	(segment
		(start 81.4324 -32.0294)
		(end 82.338926 -32.0294)
		(width 0.1143)
		(layer "B.Cu")
		(net "SPI_CS_GBE#")
	)
	(segment
		(start 71.64324 -26.07945)
		(end 66.97599 -21.4122)
		(width 0.0889)
		(layer "In7.Cu")
		(net "SPI_CS_GBE#")
	)
	(segment
		(start 82.656172 -32.346646)
		(end 82.4738 -32.346646)
		(width 0.0889)
		(layer "In7.Cu")
		(net "SPI_CS_GBE#")
	)
	(segment
		(start 77.527404 -30.410404)
		(end 76.910946 -29.793946)
		(width 0.0889)
		(layer "In7.Cu")
		(net "SPI_CS_GBE#")
	)
	(segment
		(start 61.711332 -16.55445)
		(end 60.071 -16.55445)
		(width 0.0889)
		(layer "In7.Cu")
		(net "SPI_CS_GBE#")
	)
	(segment
		(start 74.87285 -26.07945)
		(end 71.64324 -26.07945)
		(width 0.0889)
		(layer "In7.Cu")
		(net "SPI_CS_GBE#")
	)
	(segment
		(start 77.859636 -30.421326)
		(end 77.859128 -30.421072)
		(width 0.0889)
		(layer "In7.Cu")
		(net "SPI_CS_GBE#")
	)
	(segment
		(start 78.01991 -30.5816)
		(end 77.859636 -30.421326)
		(width 0.0889)
		(layer "In7.Cu")
		(net "SPI_CS_GBE#")
	)
	(segment
		(start 82.4738 -32.346646)
		(end 82.193892 -32.066738)
		(width 0.0889)
		(layer "In7.Cu")
		(net "SPI_CS_GBE#")
	)
	(segment
		(start 54.3687 -17.9705)
		(end 53.7464 -18.5928)
		(width 0.0889)
		(layer "In7.Cu")
		(net "SPI_CS_GBE#")
	)
	(segment
		(start 79.3496 -30.5816)
		(end 78.01991 -30.5816)
		(width 0.0889)
		(layer "In7.Cu")
		(net "SPI_CS_GBE#")
	)
	(segment
		(start 77.830426 -30.410404)
		(end 77.527404 -30.410404)
		(width 0.0889)
		(layer "In7.Cu")
		(net "SPI_CS_GBE#")
	)
	(segment
		(start 66.97599 -21.4122)
		(end 65.605406 -21.4122)
		(width 0.0889)
		(layer "In7.Cu")
		(net "SPI_CS_GBE#")
	)
	(segment
		(start 53.7464 -18.5928)
		(end 53.7464 -20.8534)
		(width 0.0889)
		(layer "In7.Cu")
		(net "SPI_CS_GBE#")
	)
	(segment
		(start 65.605406 -21.4122)
		(end 63.12535 -18.932144)
		(width 0.0889)
		(layer "In7.Cu")
		(net "SPI_CS_GBE#")
	)
	(segment
		(start 58.65495 -17.9705)
		(end 54.3687 -17.9705)
		(width 0.0889)
		(layer "In7.Cu")
		(net "SPI_CS_GBE#")
	)
	(segment
		(start 76.910946 -28.44927)
		(end 76.75499 -28.293314)
		(width 0.0889)
		(layer "In7.Cu")
		(net "SPI_CS_GBE#")
	)
	(segment
		(start 60.071 -16.55445)
		(end 58.65495 -17.9705)
		(width 0.0889)
		(layer "In7.Cu")
		(net "SPI_CS_GBE#")
	)
	(segment
		(start 63.12535 -18.932144)
		(end 63.12535 -17.968468)
		(width 0.0889)
		(layer "In7.Cu")
		(net "SPI_CS_GBE#")
	)
	(segment
		(start 80.199738 -32.066738)
		(end 79.68996 -31.55696)
		(width 0.0889)
		(layer "In7.Cu")
		(net "SPI_CS_GBE#")
	)
	(segment
		(start 82.193892 -32.066738)
		(end 80.199738 -32.066738)
		(width 0.0889)
		(layer "In7.Cu")
		(net "SPI_CS_GBE#")
	)
	(segment
		(start 77.859128 -30.421072)
		(end 77.830426 -30.410404)
		(width 0.0889)
		(layer "In7.Cu")
		(net "SPI_CS_GBE#")
	)
	(segment
		(start 79.68996 -30.92196)
		(end 79.3496 -30.5816)
		(width 0.0889)
		(layer "In7.Cu")
		(net "SPI_CS_GBE#")
	)
	(segment
		(start 76.75499 -28.293314)
		(end 76.75499 -27.96159)
		(width 0.0889)
		(layer "In7.Cu")
		(net "SPI_CS_GBE#")
	)
	(segment
		(start 63.12535 -17.968468)
		(end 61.711332 -16.55445)
		(width 0.0889)
		(layer "In7.Cu")
		(net "SPI_CS_GBE#")
	)
	(segment
		(start 76.75499 -27.96159)
		(end 74.87285 -26.07945)
		(width 0.0889)
		(layer "In7.Cu")
		(net "SPI_CS_GBE#")
	)
	(segment
		(start 79.68996 -31.55696)
		(end 79.68996 -30.92196)
		(width 0.0889)
		(layer "In7.Cu")
		(net "SPI_CS_GBE#")
	)
	(segment
		(start 76.910946 -29.793946)
		(end 76.910946 -28.44927)
		(width 0.0889)
		(layer "In7.Cu")
		(net "SPI_CS_GBE#")
	)
	(segment
		(start 55.499 -21.0566)
		(end 56.261 -20.2946)
		(width 0.1143)
		(layer "F.Cu")
		(net "SPI_GBE_HOLD#")
	)
	(segment
		(start 54.9402 -23.495)
		(end 55.499 -22.9362)
		(width 0.1143)
		(layer "F.Cu")
		(net "SPI_GBE_HOLD#")
	)
	(segment
		(start 55.7784 -18.5166)
		(end 55.4736 -18.2118)
		(width 0.1143)
		(layer "F.Cu")
		(net "SPI_GBE_HOLD#")
	)
	(segment
		(start 47.625 -19.3294)
		(end 47.625 -19.304)
		(width 0.1143)
		(layer "F.Cu")
		(net "SPI_GBE_HOLD#")
	)
	(segment
		(start 52.959 -19.0246)
		(end 51.7779 -19.0246)
		(width 0.1143)
		(layer "F.Cu")
		(net "SPI_GBE_HOLD#")
	)
	(segment
		(start 56.261 -20.2946)
		(end 56.2864 -20.2946)
		(width 0.1143)
		(layer "F.Cu")
		(net "SPI_GBE_HOLD#")
	)
	(segment
		(start 47.9044 -19.0246)
		(end 51.7779 -19.0246)
		(width 0.1143)
		(layer "F.Cu")
		(net "SPI_GBE_HOLD#")
	)
	(segment
		(start 56.7309 -20.2946)
		(end 56.2864 -20.2946)
		(width 0.1143)
		(layer "F.Cu")
		(net "SPI_GBE_HOLD#")
	)
	(segment
		(start 55.4736 -18.2118)
		(end 53.7718 -18.2118)
		(width 0.1143)
		(layer "F.Cu")
		(net "SPI_GBE_HOLD#")
	)
	(segment
		(start 56.2864 -20.2946)
		(end 55.7784 -19.7866)
		(width 0.1143)
		(layer "F.Cu")
		(net "SPI_GBE_HOLD#")
	)
	(segment
		(start 53.7718 -18.2118)
		(end 52.959 -19.0246)
		(width 0.1143)
		(layer "F.Cu")
		(net "SPI_GBE_HOLD#")
	)
	(segment
		(start 55.7784 -19.7866)
		(end 55.7784 -18.5166)
		(width 0.1143)
		(layer "F.Cu")
		(net "SPI_GBE_HOLD#")
	)
	(segment
		(start 47.625 -19.304)
		(end 47.9044 -19.0246)
		(width 0.1143)
		(layer "F.Cu")
		(net "SPI_GBE_HOLD#")
	)
	(segment
		(start 55.499 -22.9362)
		(end 55.499 -21.0566)
		(width 0.1143)
		(layer "F.Cu")
		(net "SPI_GBE_HOLD#")
	)
	(via
		(at 47.625 -19.3294)
		(size 0.7112)
		(drill 0.3556)
		(layers "F.Cu" "B.Cu")
		(net "SPI_GBE_HOLD#")
	)
	(segment
		(start 83.591146 -40.716454)
		(end 83.2866 -41.021)
		(width 0.1143)
		(layer "F.Cu")
		(net "SMBUS_HOST_ALRT#")
	)
	(segment
		(start 83.2866 -41.021)
		(end 83.2612 -41.021)
		(width 0.1143)
		(layer "F.Cu")
		(net "SMBUS_HOST_ALRT#")
	)
	(segment
		(start 83.647788 -40.716454)
		(end 83.591146 -40.716454)
		(width 0.1143)
		(layer "F.Cu")
		(net "SMBUS_HOST_ALRT#")
	)
	(via
		(at 77.124306 -43.485054)
		(size 0.7112)
		(drill 0.3556)
		(layers "F.Cu" "B.Cu")
		(net "SMBUS_HOST_ALRT#")
	)
	(via
		(at 83.2612 -41.021)
		(size 0.4318)
		(drill 0.2032)
		(layers "F.Cu" "B.Cu")
		(net "SMBUS_HOST_ALRT#")
	)
	(segment
		(start 76.74991 -43.485054)
		(end 77.124306 -43.485054)
		(width 0.1143)
		(layer "B.Cu")
		(net "SMBUS_HOST_ALRT#")
	)
	(segment
		(start 76.2 -44.034964)
		(end 76.74991 -43.485054)
		(width 0.1143)
		(layer "B.Cu")
		(net "SMBUS_HOST_ALRT#")
	)
	(segment
		(start 74.949812 -44.734988)
		(end 75.864212 -44.734988)
		(width 0.1143)
		(layer "B.Cu")
		(net "SMBUS_HOST_ALRT#")
	)
	(segment
		(start 82.830162 -41.452038)
		(end 83.2612 -41.021)
		(width 0.1143)
		(layer "B.Cu")
		(net "SMBUS_HOST_ALRT#")
	)
	(segment
		(start 77.139546 -43.485054)
		(end 77.5208 -43.1038)
		(width 0.1143)
		(layer "B.Cu")
		(net "SMBUS_HOST_ALRT#")
	)
	(segment
		(start 77.5208 -43.1038)
		(end 80.288638 -43.1038)
		(width 0.1143)
		(layer "B.Cu")
		(net "SMBUS_HOST_ALRT#")
	)
	(segment
		(start 81.9404 -41.452038)
		(end 82.830162 -41.452038)
		(width 0.1143)
		(layer "B.Cu")
		(net "SMBUS_HOST_ALRT#")
	)
	(segment
		(start 74.5998 -45.085)
		(end 74.949812 -44.734988)
		(width 0.1143)
		(layer "B.Cu")
		(net "SMBUS_HOST_ALRT#")
	)
	(segment
		(start 77.124306 -43.485054)
		(end 77.139546 -43.485054)
		(width 0.1143)
		(layer "B.Cu")
		(net "SMBUS_HOST_ALRT#")
	)
	(segment
		(start 75.864212 -44.734988)
		(end 76.2 -44.3992)
		(width 0.1143)
		(layer "B.Cu")
		(net "SMBUS_HOST_ALRT#")
	)
	(segment
		(start 80.288638 -43.1038)
		(end 81.9404 -41.452038)
		(width 0.1143)
		(layer "B.Cu")
		(net "SMBUS_HOST_ALRT#")
	)
	(segment
		(start 76.2 -44.3992)
		(end 76.2 -44.034964)
		(width 0.1143)
		(layer "B.Cu")
		(net "SMBUS_HOST_ALRT#")
	)
	(segment
		(start 83.645502 -47.054008)
		(end 83.645502 -47.752)
		(width 0.1143)
		(layer "F.Cu")
		(net "PROCESSOR_HOT#")
	)
	(segment
		(start 83.266788 -46.675294)
		(end 83.645502 -47.054008)
		(width 0.1143)
		(layer "F.Cu")
		(net "PROCESSOR_HOT#")
	)
	(via
		(at 81.836768 -59.470544)
		(size 0.7112)
		(drill 0.3556)
		(layers "F.Cu" "B.Cu")
		(net "PROCESSOR_HOT#")
	)
	(via
		(at 83.645502 -47.752)
		(size 0.4318)
		(drill 0.2032)
		(layers "F.Cu" "B.Cu")
		(net "PROCESSOR_HOT#")
	)
	(segment
		(start 82.931 -62.2046)
		(end 84.201 -62.2046)
		(width 0.1143)
		(layer "B.Cu")
		(net "PROCESSOR_HOT#")
	)
	(segment
		(start 81.836768 -59.470544)
		(end 81.836768 -58.809382)
		(width 0.1143)
		(layer "B.Cu")
		(net "PROCESSOR_HOT#")
	)
	(segment
		(start 83.998562 -53.458364)
		(end 83.998562 -50.57648)
		(width 0.1143)
		(layer "B.Cu")
		(net "PROCESSOR_HOT#")
	)
	(segment
		(start 83.645502 -48.801274)
		(end 83.645502 -47.752)
		(width 0.1143)
		(layer "B.Cu")
		(net "PROCESSOR_HOT#")
	)
	(segment
		(start 82.22615 -58.42)
		(end 82.22615 -55.235094)
		(width 0.1143)
		(layer "B.Cu")
		(net "PROCESSOR_HOT#")
	)
	(segment
		(start 83.998562 -50.57648)
		(end 83.722718 -50.300636)
		(width 0.1143)
		(layer "B.Cu")
		(net "PROCESSOR_HOT#")
	)
	(segment
		(start 82.22615 -55.235094)
		(end 83.867244 -53.594)
		(width 0.1143)
		(layer "B.Cu")
		(net "PROCESSOR_HOT#")
	)
	(segment
		(start 82.3722 -60.005976)
		(end 82.3722 -61.6458)
		(width 0.1143)
		(layer "B.Cu")
		(net "PROCESSOR_HOT#")
	)
	(segment
		(start 83.438238 -50.08118)
		(end 83.438238 -49.008538)
		(width 0.1143)
		(layer "B.Cu")
		(net "PROCESSOR_HOT#")
	)
	(segment
		(start 83.657694 -50.300636)
		(end 83.438238 -50.08118)
		(width 0.1143)
		(layer "B.Cu")
		(net "PROCESSOR_HOT#")
	)
	(segment
		(start 83.867244 -53.594)
		(end 83.998562 -53.458364)
		(width 0.1143)
		(layer "B.Cu")
		(net "PROCESSOR_HOT#")
	)
	(segment
		(start 81.836768 -58.809382)
		(end 82.22615 -58.42)
		(width 0.1143)
		(layer "B.Cu")
		(net "PROCESSOR_HOT#")
	)
	(segment
		(start 82.3722 -61.6458)
		(end 82.931 -62.2046)
		(width 0.1143)
		(layer "B.Cu")
		(net "PROCESSOR_HOT#")
	)
	(segment
		(start 83.722718 -50.300636)
		(end 83.657694 -50.300636)
		(width 0.1143)
		(layer "B.Cu")
		(net "PROCESSOR_HOT#")
	)
	(segment
		(start 81.836768 -59.470544)
		(end 82.3722 -60.005976)
		(width 0.1143)
		(layer "B.Cu")
		(net "PROCESSOR_HOT#")
	)
	(segment
		(start 83.438238 -49.008538)
		(end 83.645502 -48.801274)
		(width 0.1143)
		(layer "B.Cu")
		(net "PROCESSOR_HOT#")
	)
	(via
		(at 70.2564 -32.6898)
		(size 0.7112)
		(drill 0.3556)
		(layers "F.Cu" "B.Cu")
		(net "SRTCRST#")
	)
	(segment
		(start 69.05244 -33.66516)
		(end 68.20408 -33.66516)
		(width 0.1143)
		(layer "B.Cu")
		(net "SRTCRST#")
	)
	(segment
		(start 70.2564 -32.6898)
		(end 70.0278 -32.6898)
		(width 0.1143)
		(layer "B.Cu")
		(net "SRTCRST#")
	)
	(segment
		(start 70.2564 -32.6898)
		(end 70.4088 -32.6898)
		(width 0.1143)
		(layer "B.Cu")
		(net "SRTCRST#")
	)
	(segment
		(start 70.4088 -32.6898)
		(end 71.374 -33.655)
		(width 0.1143)
		(layer "B.Cu")
		(net "SRTCRST#")
	)
	(segment
		(start 71.374 -33.655)
		(end 71.882 -33.655)
		(width 0.1143)
		(layer "B.Cu")
		(net "SRTCRST#")
	)
	(segment
		(start 70.0278 -32.6898)
		(end 69.05244 -33.66516)
		(width 0.1143)
		(layer "B.Cu")
		(net "SRTCRST#")
	)
	(via
		(at 110.770924 -8.764524)
		(size 0.508)
		(drill 0.254)
		(layers "F.Cu" "B.Cu")
		(net "IRQ_MCERR#")
	)
	(via
		(at 88.123776 -39.82085)
		(size 0.4318)
		(drill 0.2032)
		(layers "F.Cu" "B.Cu")
		(net "IRQ_MCERR#")
	)
	(via
		(at 111.5822 -10.0584)
		(size 0.7112)
		(drill 0.3556)
		(layers "F.Cu" "B.Cu")
		(net "IRQ_MCERR#")
	)
	(segment
		(start 112.141 -8.8392)
		(end 112.141 -8.17372)
		(width 0.1143)
		(layer "B.Cu")
		(net "IRQ_MCERR#")
	)
	(segment
		(start 87.9221 -40.022526)
		(end 88.123776 -39.82085)
		(width 0.1143)
		(layer "B.Cu")
		(net "IRQ_MCERR#")
	)
	(segment
		(start 110.770924 -9.779)
		(end 110.770924 -8.764524)
		(width 0.1143)
		(layer "B.Cu")
		(net "IRQ_MCERR#")
	)
	(segment
		(start 111.8362 -9.8044)
		(end 111.8362 -9.144)
		(width 0.1143)
		(layer "B.Cu")
		(net "IRQ_MCERR#")
	)
	(segment
		(start 111.8362 -9.144)
		(end 112.141 -8.8392)
		(width 0.1143)
		(layer "B.Cu")
		(net "IRQ_MCERR#")
	)
	(segment
		(start 111.5822 -10.0584)
		(end 111.050324 -10.0584)
		(width 0.1143)
		(layer "B.Cu")
		(net "IRQ_MCERR#")
	)
	(segment
		(start 111.050324 -10.0584)
		(end 110.770924 -9.779)
		(width 0.1143)
		(layer "B.Cu")
		(net "IRQ_MCERR#")
	)
	(segment
		(start 87.9221 -40.4368)
		(end 87.9221 -40.022526)
		(width 0.1143)
		(layer "B.Cu")
		(net "IRQ_MCERR#")
	)
	(segment
		(start 111.5822 -10.0584)
		(end 111.8362 -9.8044)
		(width 0.1143)
		(layer "B.Cu")
		(net "IRQ_MCERR#")
	)
	(segment
		(start 85.7631 -36.4871)
		(end 84.84362 -36.4871)
		(width 0.0889)
		(layer "In9.Cu")
		(net "IRQ_MCERR#")
	)
	(segment
		(start 82.11185 -21.695664)
		(end 86.202012 -17.605502)
		(width 0.0889)
		(layer "In9.Cu")
		(net "IRQ_MCERR#")
	)
	(segment
		(start 88.123776 -39.82085)
		(end 88.123776 -39.224712)
		(width 0.0889)
		(layer "In9.Cu")
		(net "IRQ_MCERR#")
	)
	(segment
		(start 110.7694 -8.8138)
		(end 110.770924 -8.812276)
		(width 0.0889)
		(layer "In9.Cu")
		(net "IRQ_MCERR#")
	)
	(segment
		(start 88.123776 -39.224712)
		(end 86.36 -37.460936)
		(width 0.0889)
		(layer "In9.Cu")
		(net "IRQ_MCERR#")
	)
	(segment
		(start 82.91957 -35.708082)
		(end 82.377534 -35.166046)
		(width 0.0889)
		(layer "In9.Cu")
		(net "IRQ_MCERR#")
	)
	(segment
		(start 106.549698 -16.850106)
		(end 110.7694 -12.630404)
		(width 0.0889)
		(layer "In9.Cu")
		(net "IRQ_MCERR#")
	)
	(segment
		(start 82.377534 -33.658048)
		(end 81.681828 -32.962342)
		(width 0.0889)
		(layer "In9.Cu")
		(net "IRQ_MCERR#")
	)
	(segment
		(start 86.36 -37.460936)
		(end 86.36 -37.084)
		(width 0.0889)
		(layer "In9.Cu")
		(net "IRQ_MCERR#")
	)
	(segment
		(start 82.169 -31.791402)
		(end 82.169 -25.414986)
		(width 0.0889)
		(layer "In9.Cu")
		(net "IRQ_MCERR#")
	)
	(segment
		(start 82.11185 -22.737826)
		(end 82.11185 -21.695664)
		(width 0.0889)
		(layer "In9.Cu")
		(net "IRQ_MCERR#")
	)
	(segment
		(start 88.426036 -16.45285)
		(end 94.606872 -16.45285)
		(width 0.0889)
		(layer "In9.Cu")
		(net "IRQ_MCERR#")
	)
	(segment
		(start 95.004128 -16.850106)
		(end 106.549698 -16.850106)
		(width 0.0889)
		(layer "In9.Cu")
		(net "IRQ_MCERR#")
	)
	(segment
		(start 87.27313 -17.605502)
		(end 88.426036 -16.45285)
		(width 0.0889)
		(layer "In9.Cu")
		(net "IRQ_MCERR#")
	)
	(segment
		(start 82.377534 -35.166046)
		(end 82.377534 -33.658048)
		(width 0.0889)
		(layer "In9.Cu")
		(net "IRQ_MCERR#")
	)
	(segment
		(start 86.36 -37.084)
		(end 85.7631 -36.4871)
		(width 0.0889)
		(layer "In9.Cu")
		(net "IRQ_MCERR#")
	)
	(segment
		(start 110.7694 -12.630404)
		(end 110.7694 -8.8138)
		(width 0.0889)
		(layer "In9.Cu")
		(net "IRQ_MCERR#")
	)
	(segment
		(start 84.84362 -36.4871)
		(end 84.62264 -36.26612)
		(width 0.0889)
		(layer "In9.Cu")
		(net "IRQ_MCERR#")
	)
	(segment
		(start 81.71053 -23.139146)
		(end 82.11185 -22.737826)
		(width 0.0889)
		(layer "In9.Cu")
		(net "IRQ_MCERR#")
	)
	(segment
		(start 94.606872 -16.45285)
		(end 95.004128 -16.850106)
		(width 0.0889)
		(layer "In9.Cu")
		(net "IRQ_MCERR#")
	)
	(segment
		(start 84.62264 -36.26612)
		(end 84.62264 -35.86988)
		(width 0.0889)
		(layer "In9.Cu")
		(net "IRQ_MCERR#")
	)
	(segment
		(start 81.681828 -32.278574)
		(end 82.169 -31.791402)
		(width 0.0889)
		(layer "In9.Cu")
		(net "IRQ_MCERR#")
	)
	(segment
		(start 81.681828 -32.962342)
		(end 81.681828 -32.278574)
		(width 0.0889)
		(layer "In9.Cu")
		(net "IRQ_MCERR#")
	)
	(segment
		(start 110.770924 -8.812276)
		(end 110.770924 -8.764524)
		(width 0.0889)
		(layer "In9.Cu")
		(net "IRQ_MCERR#")
	)
	(segment
		(start 86.202012 -17.605502)
		(end 87.27313 -17.605502)
		(width 0.0889)
		(layer "In9.Cu")
		(net "IRQ_MCERR#")
	)
	(segment
		(start 84.460842 -35.708082)
		(end 82.91957 -35.708082)
		(width 0.0889)
		(layer "In9.Cu")
		(net "IRQ_MCERR#")
	)
	(segment
		(start 81.71053 -24.956516)
		(end 81.71053 -23.139146)
		(width 0.0889)
		(layer "In9.Cu")
		(net "IRQ_MCERR#")
	)
	(segment
		(start 84.62264 -35.86988)
		(end 84.460842 -35.708082)
		(width 0.0889)
		(layer "In9.Cu")
		(net "IRQ_MCERR#")
	)
	(segment
		(start 82.169 -25.414986)
		(end 81.71053 -24.956516)
		(width 0.0889)
		(layer "In9.Cu")
		(net "IRQ_MCERR#")
	)
	(segment
		(start 92.71 -12.347702)
		(end 93.086936 -11.970766)
		(width 0.1143)
		(layer "F.Cu")
		(net "SLOT_ID1")
	)
	(segment
		(start 129.873502 -20.774406)
		(end 129.40411 -21.243798)
		(width 0.1143)
		(layer "F.Cu")
		(net "SLOT_ID1")
	)
	(segment
		(start 129.873248 -20.164044)
		(end 129.873502 -20.164298)
		(width 0.1143)
		(layer "F.Cu")
		(net "SLOT_ID1")
	)
	(segment
		(start 112.381792 -5.647182)
		(end 112.685576 -5.647182)
		(width 0.1143)
		(layer "F.Cu")
		(net "SLOT_ID1")
	)
	(segment
		(start 129.14122 -14.378178)
		(end 129.873502 -15.11046)
		(width 0.1143)
		(layer "F.Cu")
		(net "SLOT_ID1")
	)
	(segment
		(start 136.9822 -29.006292)
		(end 136.9822 -42.0878)
		(width 0.1143)
		(layer "F.Cu")
		(net "SLOT_ID1")
	)
	(segment
		(start 129.873502 -15.11046)
		(end 129.873502 -15.720568)
		(width 0.1143)
		(layer "F.Cu")
		(net "SLOT_ID1")
	)
	(segment
		(start 136.9822 -42.0878)
		(end 135.49757 -43.57243)
		(width 0.1143)
		(layer "F.Cu")
		(net "SLOT_ID1")
	)
	(segment
		(start 93.35008 -8.90524)
		(end 92.906088 -9.349232)
		(width 0.1143)
		(layer "F.Cu")
		(net "SLOT_ID1")
	)
	(segment
		(start 92.71 -12.7762)
		(end 92.71 -12.347702)
		(width 0.1143)
		(layer "F.Cu")
		(net "SLOT_ID1")
	)
	(segment
		(start 112.685576 -5.647182)
		(end 113.144046 -5.647182)
		(width 0.1143)
		(layer "F.Cu")
		(net "SLOT_ID1")
	)
	(segment
		(start 115.015264 -7.5184)
		(end 120.133364 -7.5184)
		(width 0.1143)
		(layer "F.Cu")
		(net "SLOT_ID1")
	)
	(segment
		(start 131.095496 -24.98725)
		(end 131.165346 -25.0571)
		(width 0.1143)
		(layer "F.Cu")
		(net "SLOT_ID1")
	)
	(segment
		(start 133.033008 -25.0571)
		(end 136.9822 -29.006292)
		(width 0.1143)
		(layer "F.Cu")
		(net "SLOT_ID1")
	)
	(segment
		(start 129.873248 -15.720822)
		(end 129.873248 -20.164044)
		(width 0.1143)
		(layer "F.Cu")
		(net "SLOT_ID1")
	)
	(segment
		(start 126.993142 -14.378178)
		(end 129.14122 -14.378178)
		(width 0.1143)
		(layer "F.Cu")
		(net "SLOT_ID1")
	)
	(segment
		(start 135.49757 -43.57243)
		(end 135.49757 -45.1612)
		(width 0.1143)
		(layer "F.Cu")
		(net "SLOT_ID1")
	)
	(segment
		(start 92.906088 -9.349232)
		(end 92.906088 -10.92962)
		(width 0.1143)
		(layer "F.Cu")
		(net "SLOT_ID1")
	)
	(segment
		(start 131.165346 -25.0571)
		(end 133.033008 -25.0571)
		(width 0.1143)
		(layer "F.Cu")
		(net "SLOT_ID1")
	)
	(segment
		(start 129.873502 -20.164298)
		(end 129.873502 -20.774406)
		(width 0.1143)
		(layer "F.Cu")
		(net "SLOT_ID1")
	)
	(segment
		(start 109.041438 -3.302)
		(end 110.03661 -3.302)
		(width 0.1143)
		(layer "F.Cu")
		(net "SLOT_ID1")
	)
	(segment
		(start 129.40411 -23.333202)
		(end 131.058158 -24.98725)
		(width 0.1143)
		(layer "F.Cu")
		(net "SLOT_ID1")
	)
	(segment
		(start 129.873502 -15.720568)
		(end 129.873248 -15.720822)
		(width 0.1143)
		(layer "F.Cu")
		(net "SLOT_ID1")
	)
	(segment
		(start 113.144046 -5.647182)
		(end 115.015264 -7.5184)
		(width 0.1143)
		(layer "F.Cu")
		(net "SLOT_ID1")
	)
	(segment
		(start 120.133364 -7.5184)
		(end 126.993142 -14.378178)
		(width 0.1143)
		(layer "F.Cu")
		(net "SLOT_ID1")
	)
	(segment
		(start 108.0516 -2.312162)
		(end 109.041438 -3.302)
		(width 0.1143)
		(layer "F.Cu")
		(net "SLOT_ID1")
	)
	(segment
		(start 129.40411 -21.243798)
		(end 129.40411 -23.333202)
		(width 0.1143)
		(layer "F.Cu")
		(net "SLOT_ID1")
	)
	(segment
		(start 92.906088 -10.92962)
		(end 93.04655 -11.070082)
		(width 0.1143)
		(layer "F.Cu")
		(net "SLOT_ID1")
	)
	(segment
		(start 93.35008 -6.195568)
		(end 93.35008 -8.90524)
		(width 0.1143)
		(layer "F.Cu")
		(net "SLOT_ID1")
	)
	(segment
		(start 93.04655 -11.93038)
		(end 93.086936 -11.970766)
		(width 0.1143)
		(layer "F.Cu")
		(net "SLOT_ID1")
	)
	(segment
		(start 93.04655 -11.070082)
		(end 93.04655 -11.93038)
		(width 0.1143)
		(layer "F.Cu")
		(net "SLOT_ID1")
	)
	(segment
		(start 110.03661 -3.302)
		(end 112.381792 -5.647182)
		(width 0.1143)
		(layer "F.Cu")
		(net "SLOT_ID1")
	)
	(segment
		(start 131.058158 -24.98725)
		(end 131.095496 -24.98725)
		(width 0.1143)
		(layer "F.Cu")
		(net "SLOT_ID1")
	)
	(via
		(at 108.0516 -2.312162)
		(size 0.508)
		(drill 0.254)
		(layers "F.Cu" "B.Cu")
		(net "SLOT_ID1")
	)
	(via
		(at 112.685576 -5.647182)
		(size 0.7112)
		(drill 0.3556)
		(layers "F.Cu" "B.Cu")
		(net "SLOT_ID1")
	)
	(via
		(at 93.086936 -11.970766)
		(size 0.508)
		(drill 0.254)
		(layers "F.Cu" "B.Cu")
		(net "SLOT_ID1")
	)
	(segment
		(start 108.0516 -2.312162)
		(end 106.0323 -4.331462)
		(width 0.0889)
		(layer "In7.Cu")
		(net "SLOT_ID1")
	)
	(segment
		(start 106.0323 -11.528044)
		(end 104.822244 -12.7381)
		(width 0.0889)
		(layer "In7.Cu")
		(net "SLOT_ID1")
	)
	(segment
		(start 93.85427 -12.7381)
		(end 93.086936 -11.970766)
		(width 0.0889)
		(layer "In7.Cu")
		(net "SLOT_ID1")
	)
	(segment
		(start 104.822244 -12.7381)
		(end 93.85427 -12.7381)
		(width 0.0889)
		(layer "In7.Cu")
		(net "SLOT_ID1")
	)
	(segment
		(start 106.0323 -4.331462)
		(end 106.0323 -11.528044)
		(width 0.0889)
		(layer "In7.Cu")
		(net "SLOT_ID1")
	)
	(segment
		(start 66.9036 -54.5592)
		(end 67.375786 -55.031386)
		(width 0.1143)
		(layer "F.Cu")
		(net "CPU_THERMTRIP#")
	)
	(segment
		(start 66.04 -50.930048)
		(end 66.04 -52.197)
		(width 0.1143)
		(layer "F.Cu")
		(net "CPU_THERMTRIP#")
	)
	(segment
		(start 117.099842 -5.035296)
		(end 115.468146 -3.4036)
		(width 0.1143)
		(layer "F.Cu")
		(net "CPU_THERMTRIP#")
	)
	(segment
		(start 131.34975 -14.689582)
		(end 129.717546 -13.057378)
		(width 0.1143)
		(layer "F.Cu")
		(net "CPU_THERMTRIP#")
	)
	(segment
		(start 129.717546 -13.057378)
		(end 127.652272 -13.057378)
		(width 0.1143)
		(layer "F.Cu")
		(net "CPU_THERMTRIP#")
	)
	(segment
		(start 66.04 -52.197)
		(end 66.9036 -53.0606)
		(width 0.1143)
		(layer "F.Cu")
		(net "CPU_THERMTRIP#")
	)
	(segment
		(start 131.801108 -22.602698)
		(end 131.797552 -22.602698)
		(width 0.1143)
		(layer "F.Cu")
		(net "CPU_THERMTRIP#")
	)
	(segment
		(start 127.652272 -13.057378)
		(end 119.63019 -5.035296)
		(width 0.1143)
		(layer "F.Cu")
		(net "CPU_THERMTRIP#")
	)
	(segment
		(start 131.797552 -22.602698)
		(end 131.34975 -22.154896)
		(width 0.1143)
		(layer "F.Cu")
		(net "CPU_THERMTRIP#")
	)
	(segment
		(start 112.555274 -2.243074)
		(end 111.869474 -2.243074)
		(width 0.1143)
		(layer "F.Cu")
		(net "CPU_THERMTRIP#")
	)
	(segment
		(start 62.659006 -49.958498)
		(end 62.682374 -49.93513)
		(width 0.1143)
		(layer "F.Cu")
		(net "CPU_THERMTRIP#")
	)
	(segment
		(start 65.045082 -49.93513)
		(end 66.04 -50.930048)
		(width 0.1143)
		(layer "F.Cu")
		(net "CPU_THERMTRIP#")
	)
	(segment
		(start 111.38535 -1.75895)
		(end 111.3282 -1.75895)
		(width 0.1143)
		(layer "F.Cu")
		(net "CPU_THERMTRIP#")
	)
	(segment
		(start 131.34975 -22.154896)
		(end 131.34975 -14.689582)
		(width 0.1143)
		(layer "F.Cu")
		(net "CPU_THERMTRIP#")
	)
	(segment
		(start 84.790788 -43.403774)
		(end 85.0138 -43.626786)
		(width 0.1143)
		(layer "F.Cu")
		(net "CPU_THERMTRIP#")
	)
	(segment
		(start 119.63019 -5.035296)
		(end 117.099842 -5.035296)
		(width 0.1143)
		(layer "F.Cu")
		(net "CPU_THERMTRIP#")
	)
	(segment
		(start 62.682374 -49.93513)
		(end 65.045082 -49.93513)
		(width 0.1143)
		(layer "F.Cu")
		(net "CPU_THERMTRIP#")
	)
	(segment
		(start 111.869474 -2.243074)
		(end 111.38535 -1.75895)
		(width 0.1143)
		(layer "F.Cu")
		(net "CPU_THERMTRIP#")
	)
	(segment
		(start 113.7158 -3.4036)
		(end 112.555274 -2.243074)
		(width 0.1143)
		(layer "F.Cu")
		(net "CPU_THERMTRIP#")
	)
	(segment
		(start 85.0138 -43.626786)
		(end 85.0138 -44.2214)
		(width 0.1143)
		(layer "F.Cu")
		(net "CPU_THERMTRIP#")
	)
	(segment
		(start 66.9036 -53.0606)
		(end 66.9036 -54.5592)
		(width 0.1143)
		(layer "F.Cu")
		(net "CPU_THERMTRIP#")
	)
	(segment
		(start 115.468146 -3.4036)
		(end 113.7158 -3.4036)
		(width 0.1143)
		(layer "F.Cu")
		(net "CPU_THERMTRIP#")
	)
	(via
		(at 85.0138 -44.2214)
		(size 0.4318)
		(drill 0.2032)
		(layers "F.Cu" "B.Cu")
		(net "CPU_THERMTRIP#")
	)
	(via
		(at 111.3282 -1.75895)
		(size 0.508)
		(drill 0.254)
		(layers "F.Cu" "B.Cu")
		(net "CPU_THERMTRIP#")
	)
	(via
		(at 131.801108 -22.602698)
		(size 0.508)
		(drill 0.254)
		(layers "F.Cu" "B.Cu")
		(net "CPU_THERMTRIP#")
	)
	(via
		(at 62.659006 -49.958498)
		(size 0.508)
		(drill 0.254)
		(layers "F.Cu" "B.Cu")
		(net "CPU_THERMTRIP#")
	)
	(via
		(at 67.375786 -55.031386)
		(size 0.508)
		(drill 0.254)
		(layers "F.Cu" "B.Cu")
		(net "CPU_THERMTRIP#")
	)
	(via
		(at 59.70905 -26.8224)
		(size 0.508)
		(drill 0.254)
		(layers "F.Cu" "B.Cu")
		(net "CPU_THERMTRIP#")
	)
	(via
		(at 68.453 -55.031386)
		(size 0.7112)
		(drill 0.3556)
		(layers "F.Cu" "B.Cu")
		(net "CPU_THERMTRIP#")
	)
	(segment
		(start 60.6806 -43.1546)
		(end 60.6806 -30.7086)
		(width 0.1143)
		(layer "B.Cu")
		(net "CPU_THERMTRIP#")
	)
	(segment
		(start 76.54925 -49.539906)
		(end 76.54925 -53.153818)
		(width 0.1143)
		(layer "B.Cu")
		(net "CPU_THERMTRIP#")
	)
	(segment
		(start 83.162394 -43.649138)
		(end 82.781394 -44.030138)
		(width 0.1143)
		(layer "B.Cu")
		(net "CPU_THERMTRIP#")
	)
	(segment
		(start 71.509382 -54.991)
		(end 70.817232 -55.68315)
		(width 0.1143)
		(layer "B.Cu")
		(net "CPU_THERMTRIP#")
	)
	(segment
		(start 82.371438 -45.00372)
		(end 81.639918 -45.73524)
		(width 0.1143)
		(layer "B.Cu")
		(net "CPU_THERMTRIP#")
	)
	(segment
		(start 61.56579 -44.03979)
		(end 60.6806 -43.1546)
		(width 0.1143)
		(layer "B.Cu")
		(net "CPU_THERMTRIP#")
	)
	(segment
		(start 62.659006 -49.958498)
		(end 62.659006 -48.750474)
		(width 0.1143)
		(layer "B.Cu")
		(net "CPU_THERMTRIP#")
	)
	(segment
		(start 132.2832 -27.305)
		(end 132.2832 -26.8986)
		(width 0.1143)
		(layer "B.Cu")
		(net "CPU_THERMTRIP#")
	)
	(segment
		(start 80.899 -47.02302)
		(end 78.82382 -49.0982)
		(width 0.1143)
		(layer "B.Cu")
		(net "CPU_THERMTRIP#")
	)
	(segment
		(start 60.6806 -30.7086)
		(end 60.016898 -30.044898)
		(width 0.1143)
		(layer "B.Cu")
		(net "CPU_THERMTRIP#")
	)
	(segment
		(start 61.56579 -47.657258)
		(end 61.56579 -44.03979)
		(width 0.1143)
		(layer "B.Cu")
		(net "CPU_THERMTRIP#")
	)
	(segment
		(start 80.899 -46.670722)
		(end 80.899 -47.02302)
		(width 0.1143)
		(layer "B.Cu")
		(net "CPU_THERMTRIP#")
	)
	(segment
		(start 131.3942 -25.8572)
		(end 131.318 -25.9334)
		(width 0.1143)
		(layer "B.Cu")
		(net "CPU_THERMTRIP#")
	)
	(segment
		(start 69.104764 -55.68315)
		(end 68.453 -55.031386)
		(width 0.1143)
		(layer "B.Cu")
		(net "CPU_THERMTRIP#")
	)
	(segment
		(start 67.375786 -55.031386)
		(end 68.453 -55.031386)
		(width 0.1143)
		(layer "B.Cu")
		(net "CPU_THERMTRIP#")
	)
	(segment
		(start 60.016898 -30.044898)
		(end 60.016898 -27.130248)
		(width 0.1143)
		(layer "B.Cu")
		(net "CPU_THERMTRIP#")
	)
	(segment
		(start 132.2832 -26.8986)
		(end 131.318 -25.9334)
		(width 0.1143)
		(layer "B.Cu")
		(net "CPU_THERMTRIP#")
	)
	(segment
		(start 60.016898 -27.130248)
		(end 59.70905 -26.8224)
		(width 0.1143)
		(layer "B.Cu")
		(net "CPU_THERMTRIP#")
	)
	(segment
		(start 62.659006 -48.750474)
		(end 61.56579 -47.657258)
		(width 0.1143)
		(layer "B.Cu")
		(net "CPU_THERMTRIP#")
	)
	(segment
		(start 81.639918 -46.00829)
		(end 81.420462 -46.227746)
		(width 0.1143)
		(layer "B.Cu")
		(net "CPU_THERMTRIP#")
	)
	(segment
		(start 84.441538 -43.649138)
		(end 83.162394 -43.649138)
		(width 0.1143)
		(layer "B.Cu")
		(net "CPU_THERMTRIP#")
	)
	(segment
		(start 76.54925 -53.153818)
		(end 74.712068 -54.991)
		(width 0.1143)
		(layer "B.Cu")
		(net "CPU_THERMTRIP#")
	)
	(segment
		(start 131.3942 -24.638)
		(end 131.3942 -25.8572)
		(width 0.1143)
		(layer "B.Cu")
		(net "CPU_THERMTRIP#")
	)
	(segment
		(start 74.712068 -54.991)
		(end 71.509382 -54.991)
		(width 0.1143)
		(layer "B.Cu")
		(net "CPU_THERMTRIP#")
	)
	(segment
		(start 78.82382 -49.0982)
		(end 76.990956 -49.0982)
		(width 0.1143)
		(layer "B.Cu")
		(net "CPU_THERMTRIP#")
	)
	(segment
		(start 70.817232 -55.68315)
		(end 69.104764 -55.68315)
		(width 0.1143)
		(layer "B.Cu")
		(net "CPU_THERMTRIP#")
	)
	(segment
		(start 81.639918 -45.73524)
		(end 81.639918 -46.00829)
		(width 0.1143)
		(layer "B.Cu")
		(net "CPU_THERMTRIP#")
	)
	(segment
		(start 82.781394 -44.784518)
		(end 82.562192 -45.00372)
		(width 0.1143)
		(layer "B.Cu")
		(net "CPU_THERMTRIP#")
	)
	(segment
		(start 131.801108 -22.602698)
		(end 131.801108 -24.231092)
		(width 0.1143)
		(layer "B.Cu")
		(net "CPU_THERMTRIP#")
	)
	(segment
		(start 82.562192 -45.00372)
		(end 82.371438 -45.00372)
		(width 0.1143)
		(layer "B.Cu")
		(net "CPU_THERMTRIP#")
	)
	(segment
		(start 82.781394 -44.030138)
		(end 82.781394 -44.784518)
		(width 0.1143)
		(layer "B.Cu")
		(net "CPU_THERMTRIP#")
	)
	(segment
		(start 81.420462 -46.227746)
		(end 81.341976 -46.227746)
		(width 0.1143)
		(layer "B.Cu")
		(net "CPU_THERMTRIP#")
	)
	(segment
		(start 81.341976 -46.227746)
		(end 80.899 -46.670722)
		(width 0.1143)
		(layer "B.Cu")
		(net "CPU_THERMTRIP#")
	)
	(segment
		(start 131.801108 -24.231092)
		(end 131.3942 -24.638)
		(width 0.1143)
		(layer "B.Cu")
		(net "CPU_THERMTRIP#")
	)
	(segment
		(start 85.0138 -44.2214)
		(end 84.441538 -43.649138)
		(width 0.1143)
		(layer "B.Cu")
		(net "CPU_THERMTRIP#")
	)
	(segment
		(start 76.990956 -49.0982)
		(end 76.54925 -49.539906)
		(width 0.1143)
		(layer "B.Cu")
		(net "CPU_THERMTRIP#")
	)
	(segment
		(start 110.87735 -2.2098)
		(end 110.518956 -2.2098)
		(width 0.0889)
		(layer "In9.Cu")
		(net "CPU_THERMTRIP#")
	)
	(segment
		(start 106.987594 -11.938254)
		(end 105.238042 -13.687806)
		(width 0.0889)
		(layer "In9.Cu")
		(net "CPU_THERMTRIP#")
	)
	(segment
		(start 64.29375 -8.93445)
		(end 60.6806 -12.5476)
		(width 0.0889)
		(layer "In9.Cu")
		(net "CPU_THERMTRIP#")
	)
	(segment
		(start 80.744568 -8.93445)
		(end 64.29375 -8.93445)
		(width 0.0889)
		(layer "In9.Cu")
		(net "CPU_THERMTRIP#")
	)
	(segment
		(start 88.188038 -13.0937)
		(end 85.711538 -13.0937)
		(width 0.0889)
		(layer "In9.Cu")
		(net "CPU_THERMTRIP#")
	)
	(segment
		(start 58.52795 -25.6413)
		(end 59.70905 -26.8224)
		(width 0.0889)
		(layer "In9.Cu")
		(net "CPU_THERMTRIP#")
	)
	(segment
		(start 57.96915 -17.091914)
		(end 58.7883 -17.911064)
		(width 0.0889)
		(layer "In9.Cu")
		(net "CPU_THERMTRIP#")
	)
	(segment
		(start 111.3282 -1.75895)
		(end 110.87735 -2.2098)
		(width 0.0889)
		(layer "In9.Cu")
		(net "CPU_THERMTRIP#")
	)
	(segment
		(start 110.518956 -2.2098)
		(end 109.585506 -3.14325)
		(width 0.0889)
		(layer "In9.Cu")
		(net "CPU_THERMTRIP#")
	)
	(segment
		(start 58.52795 -21.48205)
		(end 58.52795 -25.6413)
		(width 0.0889)
		(layer "In9.Cu")
		(net "CPU_THERMTRIP#")
	)
	(segment
		(start 95.918528 -13.29055)
		(end 91.383612 -13.29055)
		(width 0.0889)
		(layer "In9.Cu")
		(net "CPU_THERMTRIP#")
	)
	(segment
		(start 58.7883 -17.911064)
		(end 58.7883 -21.2217)
		(width 0.0889)
		(layer "In9.Cu")
		(net "CPU_THERMTRIP#")
	)
	(segment
		(start 107.988862 -3.14325)
		(end 106.987594 -4.144518)
		(width 0.0889)
		(layer "In9.Cu")
		(net "CPU_THERMTRIP#")
	)
	(segment
		(start 57.96915 -13.63345)
		(end 57.96915 -17.091914)
		(width 0.0889)
		(layer "In9.Cu")
		(net "CPU_THERMTRIP#")
	)
	(segment
		(start 91.383612 -13.29055)
		(end 90.545666 -12.452604)
		(width 0.0889)
		(layer "In9.Cu")
		(net "CPU_THERMTRIP#")
	)
	(segment
		(start 105.238042 -13.687806)
		(end 96.315784 -13.687806)
		(width 0.0889)
		(layer "In9.Cu")
		(net "CPU_THERMTRIP#")
	)
	(segment
		(start 81.541112 -11.8618)
		(end 81.12125 -11.441938)
		(width 0.0889)
		(layer "In9.Cu")
		(net "CPU_THERMTRIP#")
	)
	(segment
		(start 60.6806 -12.5476)
		(end 59.055 -12.5476)
		(width 0.0889)
		(layer "In9.Cu")
		(net "CPU_THERMTRIP#")
	)
	(segment
		(start 81.12125 -10.910062)
		(end 81.209642 -10.82167)
		(width 0.0889)
		(layer "In9.Cu")
		(net "CPU_THERMTRIP#")
	)
	(segment
		(start 90.545666 -12.452604)
		(end 88.829134 -12.452604)
		(width 0.0889)
		(layer "In9.Cu")
		(net "CPU_THERMTRIP#")
	)
	(segment
		(start 85.711538 -13.0937)
		(end 84.479638 -11.8618)
		(width 0.0889)
		(layer "In9.Cu")
		(net "CPU_THERMTRIP#")
	)
	(segment
		(start 106.987594 -4.144518)
		(end 106.987594 -11.938254)
		(width 0.0889)
		(layer "In9.Cu")
		(net "CPU_THERMTRIP#")
	)
	(segment
		(start 96.315784 -13.687806)
		(end 95.918528 -13.29055)
		(width 0.0889)
		(layer "In9.Cu")
		(net "CPU_THERMTRIP#")
	)
	(segment
		(start 81.12125 -11.441938)
		(end 81.12125 -10.910062)
		(width 0.0889)
		(layer "In9.Cu")
		(net "CPU_THERMTRIP#")
	)
	(segment
		(start 59.055 -12.5476)
		(end 57.96915 -13.63345)
		(width 0.0889)
		(layer "In9.Cu")
		(net "CPU_THERMTRIP#")
	)
	(segment
		(start 88.829134 -12.452604)
		(end 88.188038 -13.0937)
		(width 0.0889)
		(layer "In9.Cu")
		(net "CPU_THERMTRIP#")
	)
	(segment
		(start 81.209642 -9.399524)
		(end 80.744568 -8.93445)
		(width 0.0889)
		(layer "In9.Cu")
		(net "CPU_THERMTRIP#")
	)
	(segment
		(start 109.585506 -3.14325)
		(end 107.988862 -3.14325)
		(width 0.0889)
		(layer "In9.Cu")
		(net "CPU_THERMTRIP#")
	)
	(segment
		(start 84.479638 -11.8618)
		(end 81.541112 -11.8618)
		(width 0.0889)
		(layer "In9.Cu")
		(net "CPU_THERMTRIP#")
	)
	(segment
		(start 58.7883 -21.2217)
		(end 58.52795 -21.48205)
		(width 0.0889)
		(layer "In9.Cu")
		(net "CPU_THERMTRIP#")
	)
	(segment
		(start 81.209642 -10.82167)
		(end 81.209642 -9.399524)
		(width 0.0889)
		(layer "In9.Cu")
		(net "CPU_THERMTRIP#")
	)
	(segment
		(start 109.65815 -3.055112)
		(end 108.9152 -2.312162)
		(width 0.1143)
		(layer "F.Cu")
		(net "SLOT_ID2")
	)
	(segment
		(start 92.107004 -11.955272)
		(end 91.429332 -11.2776)
		(width 0.1143)
		(layer "F.Cu")
		(net "SLOT_ID2")
	)
	(segment
		(start 114.48415 -6.63575)
		(end 112.92205 -5.07365)
		(width 0.1143)
		(layer "F.Cu")
		(net "SLOT_ID2")
	)
	(segment
		(start 91.948 -12.114276)
		(end 92.107004 -11.955272)
		(width 0.1143)
		(layer "F.Cu")
		(net "SLOT_ID2")
	)
	(segment
		(start 114.935 -6.63575)
		(end 114.48415 -6.63575)
		(width 0.1143)
		(layer "F.Cu")
		(net "SLOT_ID2")
	)
	(segment
		(start 130.27025 -20.719034)
		(end 129.7305 -21.258784)
		(width 0.1143)
		(layer "F.Cu")
		(net "SLOT_ID2")
	)
	(segment
		(start 129.7305 -21.258784)
		(end 129.7305 -22.989286)
		(width 0.1143)
		(layer "F.Cu")
		(net "SLOT_ID2")
	)
	(segment
		(start 133.133084 -24.8158)
		(end 137.2235 -28.906216)
		(width 0.1143)
		(layer "F.Cu")
		(net "SLOT_ID2")
	)
	(segment
		(start 90.350086 -8.435086)
		(end 90.350086 -6.195568)
		(width 0.1143)
		(layer "F.Cu")
		(net "SLOT_ID2")
	)
	(segment
		(start 130.27025 -15.13713)
		(end 130.27025 -20.719034)
		(width 0.1143)
		(layer "F.Cu")
		(net "SLOT_ID2")
	)
	(segment
		(start 91.429332 -9.514332)
		(end 90.350086 -8.435086)
		(width 0.1143)
		(layer "F.Cu")
		(net "SLOT_ID2")
	)
	(segment
		(start 129.269998 -14.136878)
		(end 130.27025 -15.13713)
		(width 0.1143)
		(layer "F.Cu")
		(net "SLOT_ID2")
	)
	(segment
		(start 91.948 -12.7762)
		(end 91.948 -12.114276)
		(width 0.1143)
		(layer "F.Cu")
		(net "SLOT_ID2")
	)
	(segment
		(start 112.92205 -5.07365)
		(end 112.149636 -5.07365)
		(width 0.1143)
		(layer "F.Cu")
		(net "SLOT_ID2")
	)
	(segment
		(start 129.7305 -22.989286)
		(end 131.557014 -24.8158)
		(width 0.1143)
		(layer "F.Cu")
		(net "SLOT_ID2")
	)
	(segment
		(start 127.093218 -14.136878)
		(end 129.269998 -14.136878)
		(width 0.1143)
		(layer "F.Cu")
		(net "SLOT_ID2")
	)
	(segment
		(start 91.429332 -11.2776)
		(end 91.429332 -9.514332)
		(width 0.1143)
		(layer "F.Cu")
		(net "SLOT_ID2")
	)
	(segment
		(start 135.99795 -43.96105)
		(end 135.99795 -45.1612)
		(width 0.1143)
		(layer "F.Cu")
		(net "SLOT_ID2")
	)
	(segment
		(start 137.2235 -42.7355)
		(end 135.99795 -43.96105)
		(width 0.1143)
		(layer "F.Cu")
		(net "SLOT_ID2")
	)
	(segment
		(start 114.935 -6.63575)
		(end 119.59209 -6.63575)
		(width 0.1143)
		(layer "F.Cu")
		(net "SLOT_ID2")
	)
	(segment
		(start 110.131098 -3.055112)
		(end 109.65815 -3.055112)
		(width 0.1143)
		(layer "F.Cu")
		(net "SLOT_ID2")
	)
	(segment
		(start 131.557014 -24.8158)
		(end 133.133084 -24.8158)
		(width 0.1143)
		(layer "F.Cu")
		(net "SLOT_ID2")
	)
	(segment
		(start 119.59209 -6.63575)
		(end 127.093218 -14.136878)
		(width 0.1143)
		(layer "F.Cu")
		(net "SLOT_ID2")
	)
	(segment
		(start 112.149636 -5.07365)
		(end 110.131098 -3.055112)
		(width 0.1143)
		(layer "F.Cu")
		(net "SLOT_ID2")
	)
	(segment
		(start 137.2235 -28.906216)
		(end 137.2235 -42.7355)
		(width 0.1143)
		(layer "F.Cu")
		(net "SLOT_ID2")
	)
	(via
		(at 92.107004 -11.955272)
		(size 0.508)
		(drill 0.254)
		(layers "F.Cu" "B.Cu")
		(net "SLOT_ID2")
	)
	(via
		(at 108.9152 -2.312162)
		(size 0.508)
		(drill 0.254)
		(layers "F.Cu" "B.Cu")
		(net "SLOT_ID2")
	)
	(via
		(at 114.935 -6.63575)
		(size 0.7112)
		(drill 0.3556)
		(layers "F.Cu" "B.Cu")
		(net "SLOT_ID2")
	)
	(segment
		(start 108.9152 -2.312162)
		(end 108.458762 -2.7686)
		(width 0.0889)
		(layer "In7.Cu")
		(net "SLOT_ID2")
	)
	(segment
		(start 104.911906 -12.954)
		(end 93.105732 -12.954)
		(width 0.0889)
		(layer "In7.Cu")
		(net "SLOT_ID2")
	)
	(segment
		(start 107.959906 -2.7686)
		(end 106.2482 -4.480306)
		(width 0.0889)
		(layer "In7.Cu")
		(net "SLOT_ID2")
	)
	(segment
		(start 106.2482 -4.480306)
		(end 106.2482 -11.617706)
		(width 0.0889)
		(layer "In7.Cu")
		(net "SLOT_ID2")
	)
	(segment
		(start 108.458762 -2.7686)
		(end 107.959906 -2.7686)
		(width 0.0889)
		(layer "In7.Cu")
		(net "SLOT_ID2")
	)
	(segment
		(start 106.2482 -11.617706)
		(end 104.911906 -12.954)
		(width 0.0889)
		(layer "In7.Cu")
		(net "SLOT_ID2")
	)
	(segment
		(start 93.105732 -12.954)
		(end 92.107004 -11.955272)
		(width 0.0889)
		(layer "In7.Cu")
		(net "SLOT_ID2")
	)
	(segment
		(start 81.836768 -46.695868)
		(end 82.072734 -46.459902)
		(width 0.1143)
		(layer "F.Cu")
		(net "SVID_ALERT#")
	)
	(segment
		(start 81.836768 -46.888654)
		(end 81.836768 -46.695868)
		(width 0.1143)
		(layer "F.Cu")
		(net "SVID_ALERT#")
	)
	(via
		(at 82.072734 -46.459902)
		(size 0.4318)
		(drill 0.2032)
		(layers "F.Cu" "B.Cu")
		(net "SVID_ALERT#")
	)
	(via
		(at 79.56804 -49.149)
		(size 0.7112)
		(drill 0.3556)
		(layers "F.Cu" "B.Cu")
		(net "SVID_ALERT#")
	)
	(segment
		(start 78.5622 -51.61915)
		(end 78.7146 -51.46675)
		(width 0.1143)
		(layer "B.Cu")
		(net "SVID_ALERT#")
	)
	(segment
		(start 77.61605 -59.84875)
		(end 79.56804 -57.89676)
		(width 0.1143)
		(layer "B.Cu")
		(net "SVID_ALERT#")
	)
	(segment
		(start 77.61605 -60.75045)
		(end 77.61605 -59.84875)
		(width 0.1143)
		(layer "B.Cu")
		(net "SVID_ALERT#")
	)
	(segment
		(start 79.56804 -50.20945)
		(end 79.56804 -49.149)
		(width 0.1143)
		(layer "B.Cu")
		(net "SVID_ALERT#")
	)
	(segment
		(start 82.072734 -46.603666)
		(end 82.072734 -46.459902)
		(width 0.1143)
		(layer "B.Cu")
		(net "SVID_ALERT#")
	)
	(segment
		(start 79.56804 -51.00955)
		(end 79.45374 -50.89525)
		(width 0.1143)
		(layer "B.Cu")
		(net "SVID_ALERT#")
	)
	(segment
		(start 79.45374 -52.03825)
		(end 78.7146 -52.03825)
		(width 0.1143)
		(layer "B.Cu")
		(net "SVID_ALERT#")
	)
	(segment
		(start 78.7146 -51.46675)
		(end 79.45374 -51.46675)
		(width 0.1143)
		(layer "B.Cu")
		(net "SVID_ALERT#")
	)
	(segment
		(start 79.56804 -49.149)
		(end 79.56804 -49.10836)
		(width 0.1143)
		(layer "B.Cu")
		(net "SVID_ALERT#")
	)
	(segment
		(start 79.56804 -51.35245)
		(end 79.56804 -51.00955)
		(width 0.1143)
		(layer "B.Cu")
		(net "SVID_ALERT#")
	)
	(segment
		(start 79.45374 -50.32375)
		(end 79.56804 -50.20945)
		(width 0.1143)
		(layer "B.Cu")
		(net "SVID_ALERT#")
	)
	(segment
		(start 79.56804 -52.15255)
		(end 79.45374 -52.03825)
		(width 0.1143)
		(layer "B.Cu")
		(net "SVID_ALERT#")
	)
	(segment
		(start 78.105 -50.74285)
		(end 78.105 -50.47615)
		(width 0.1143)
		(layer "B.Cu")
		(net "SVID_ALERT#")
	)
	(segment
		(start 79.56804 -49.10836)
		(end 82.072734 -46.603666)
		(width 0.1143)
		(layer "B.Cu")
		(net "SVID_ALERT#")
	)
	(segment
		(start 78.2574 -50.89525)
		(end 78.105 -50.74285)
		(width 0.1143)
		(layer "B.Cu")
		(net "SVID_ALERT#")
	)
	(segment
		(start 80.137 -62.8142)
		(end 79.6798 -62.8142)
		(width 0.1143)
		(layer "B.Cu")
		(net "SVID_ALERT#")
	)
	(segment
		(start 78.5622 -51.88585)
		(end 78.5622 -51.61915)
		(width 0.1143)
		(layer "B.Cu")
		(net "SVID_ALERT#")
	)
	(segment
		(start 79.6798 -62.8142)
		(end 77.61605 -60.75045)
		(width 0.1143)
		(layer "B.Cu")
		(net "SVID_ALERT#")
	)
	(segment
		(start 79.56804 -57.89676)
		(end 79.56804 -52.15255)
		(width 0.1143)
		(layer "B.Cu")
		(net "SVID_ALERT#")
	)
	(segment
		(start 78.2574 -50.32375)
		(end 79.45374 -50.32375)
		(width 0.1143)
		(layer "B.Cu")
		(net "SVID_ALERT#")
	)
	(segment
		(start 79.45374 -50.89525)
		(end 78.2574 -50.89525)
		(width 0.1143)
		(layer "B.Cu")
		(net "SVID_ALERT#")
	)
	(segment
		(start 78.105 -50.47615)
		(end 78.2574 -50.32375)
		(width 0.1143)
		(layer "B.Cu")
		(net "SVID_ALERT#")
	)
	(segment
		(start 79.45374 -51.46675)
		(end 79.56804 -51.35245)
		(width 0.1143)
		(layer "B.Cu")
		(net "SVID_ALERT#")
	)
	(segment
		(start 78.7146 -52.03825)
		(end 78.5622 -51.88585)
		(width 0.1143)
		(layer "B.Cu")
		(net "SVID_ALERT#")
	)
	(segment
		(start 77.2922 -35.9156)
		(end 77.999336 -36.622736)
		(width 0.1143)
		(layer "F.Cu")
		(net "SUS_STAT#")
	)
	(segment
		(start 79.765906 -36.622736)
		(end 80.007968 -36.380674)
		(width 0.1143)
		(layer "F.Cu")
		(net "SUS_STAT#")
	)
	(segment
		(start 80.007968 -36.380674)
		(end 80.211168 -36.380674)
		(width 0.1143)
		(layer "F.Cu")
		(net "SUS_STAT#")
	)
	(segment
		(start 77.999336 -36.622736)
		(end 79.765906 -36.622736)
		(width 0.1143)
		(layer "F.Cu")
		(net "SUS_STAT#")
	)
	(segment
		(start 88.219788 -37.654992)
		(end 87.9983 -37.87648)
		(width 0.1143)
		(layer "F.Cu")
		(net "SRTCRST_R#")
	)
	(segment
		(start 88.219788 -37.444934)
		(end 88.219788 -37.654992)
		(width 0.1143)
		(layer "F.Cu")
		(net "SRTCRST_R#")
	)
	(via
		(at 74.0156 -34.210244)
		(size 0.7112)
		(drill 0.3556)
		(layers "F.Cu" "B.Cu")
		(net "SRTCRST_R#")
	)
	(via
		(at 87.9983 -37.87648)
		(size 0.4318)
		(drill 0.2032)
		(layers "F.Cu" "B.Cu")
		(net "SRTCRST_R#")
	)
	(segment
		(start 87.63381 -37.50437)
		(end 87.9983 -37.86886)
		(width 0.1143)
		(layer "B.Cu")
		(net "SRTCRST_R#")
	)
	(segment
		(start 87.9983 -37.86886)
		(end 87.9983 -37.87648)
		(width 0.1143)
		(layer "B.Cu")
		(net "SRTCRST_R#")
	)
	(segment
		(start 75.593956 -34.210244)
		(end 75.8952 -33.909)
		(width 0.1143)
		(layer "B.Cu")
		(net "SRTCRST_R#")
	)
	(segment
		(start 77.87005 -35.32505)
		(end 79.47025 -35.32505)
		(width 0.1143)
		(layer "B.Cu")
		(net "SRTCRST_R#")
	)
	(segment
		(start 80.09255 -35.94735)
		(end 80.328516 -35.94735)
		(width 0.1143)
		(layer "B.Cu")
		(net "SRTCRST_R#")
	)
	(segment
		(start 72.7456 -33.655)
		(end 73.300844 -34.210244)
		(width 0.1143)
		(layer "B.Cu")
		(net "SRTCRST_R#")
	)
	(segment
		(start 73.300844 -34.210244)
		(end 74.0156 -34.210244)
		(width 0.1143)
		(layer "B.Cu")
		(net "SRTCRST_R#")
	)
	(segment
		(start 84.52231 -36.46805)
		(end 85.805518 -36.46805)
		(width 0.1143)
		(layer "B.Cu")
		(net "SRTCRST_R#")
	)
	(segment
		(start 86.841838 -37.50437)
		(end 87.63381 -37.50437)
		(width 0.1143)
		(layer "B.Cu")
		(net "SRTCRST_R#")
	)
	(segment
		(start 80.328516 -35.94735)
		(end 80.652366 -36.2712)
		(width 0.1143)
		(layer "B.Cu")
		(net "SRTCRST_R#")
	)
	(segment
		(start 80.652366 -36.2712)
		(end 81.8007 -36.2712)
		(width 0.1143)
		(layer "B.Cu")
		(net "SRTCRST_R#")
	)
	(segment
		(start 76.454 -33.909)
		(end 77.87005 -35.32505)
		(width 0.1143)
		(layer "B.Cu")
		(net "SRTCRST_R#")
	)
	(segment
		(start 85.805518 -36.46805)
		(end 86.841838 -37.50437)
		(width 0.1143)
		(layer "B.Cu")
		(net "SRTCRST_R#")
	)
	(segment
		(start 84.521294 -36.469066)
		(end 84.52231 -36.46805)
		(width 0.1143)
		(layer "B.Cu")
		(net "SRTCRST_R#")
	)
	(segment
		(start 79.47025 -35.32505)
		(end 80.09255 -35.94735)
		(width 0.1143)
		(layer "B.Cu")
		(net "SRTCRST_R#")
	)
	(segment
		(start 75.8952 -33.909)
		(end 76.454 -33.909)
		(width 0.1143)
		(layer "B.Cu")
		(net "SRTCRST_R#")
	)
	(segment
		(start 74.0156 -34.210244)
		(end 75.593956 -34.210244)
		(width 0.1143)
		(layer "B.Cu")
		(net "SRTCRST_R#")
	)
	(segment
		(start 81.8007 -36.2712)
		(end 81.998566 -36.469066)
		(width 0.1143)
		(layer "B.Cu")
		(net "SRTCRST_R#")
	)
	(segment
		(start 81.998566 -36.469066)
		(end 84.521294 -36.469066)
		(width 0.1143)
		(layer "B.Cu")
		(net "SRTCRST_R#")
	)
	(segment
		(start 182.5244 -38.1)
		(end 182.4228 -38.2016)
		(width 0.1143)
		(layer "F.Cu")
		(net "SVID_CPU_ALERT#")
	)
	(segment
		(start 14.757908 -62.603126)
		(end 14.757908 -62.603634)
		(width 0.1143)
		(layer "F.Cu")
		(net "SVID_CPU_ALERT#")
	)
	(segment
		(start 14.89075 -60.39485)
		(end 14.89075 -62.470284)
		(width 0.1143)
		(layer "F.Cu")
		(net "SVID_CPU_ALERT#")
	)
	(segment
		(start 181.5338 -38.1)
		(end 182.3212 -38.1)
		(width 0.1143)
		(layer "F.Cu")
		(net "SVID_CPU_ALERT#")
	)
	(segment
		(start 13.82395 -61.870082)
		(end 13.82395 -61.747146)
		(width 0.1143)
		(layer "F.Cu")
		(net "SVID_CPU_ALERT#")
	)
	(segment
		(start 183.2102 -38.1)
		(end 182.5244 -38.1)
		(width 0.1143)
		(layer "F.Cu")
		(net "SVID_CPU_ALERT#")
	)
	(segment
		(start 80.9498 -63.6016)
		(end 80.9498 -63.7286)
		(width 0.1143)
		(layer "F.Cu")
		(net "SVID_CPU_ALERT#")
	)
	(segment
		(start 14.89075 -62.470284)
		(end 14.757908 -62.603126)
		(width 0.1143)
		(layer "F.Cu")
		(net "SVID_CPU_ALERT#")
	)
	(segment
		(start 13.716254 -61.63945)
		(end 13.68425 -61.63945)
		(width 0.1143)
		(layer "F.Cu")
		(net "SVID_CPU_ALERT#")
	)
	(segment
		(start 80.9498 -63.7286)
		(end 80.137 -64.5414)
		(width 0.1143)
		(layer "F.Cu")
		(net "SVID_CPU_ALERT#")
	)
	(segment
		(start 15.4178 -59.8932)
		(end 15.3924 -59.8932)
		(width 0.1143)
		(layer "F.Cu")
		(net "SVID_CPU_ALERT#")
	)
	(segment
		(start 13.82395 -61.747146)
		(end 13.716254 -61.63945)
		(width 0.1143)
		(layer "F.Cu")
		(net "SVID_CPU_ALERT#")
	)
	(segment
		(start 14.757908 -62.603634)
		(end 14.557502 -62.603634)
		(width 0.1143)
		(layer "F.Cu")
		(net "SVID_CPU_ALERT#")
	)
	(segment
		(start 15.3924 -59.8932)
		(end 14.89075 -60.39485)
		(width 0.1143)
		(layer "F.Cu")
		(net "SVID_CPU_ALERT#")
	)
	(segment
		(start 14.557502 -62.603634)
		(end 13.82395 -61.870082)
		(width 0.1143)
		(layer "F.Cu")
		(net "SVID_CPU_ALERT#")
	)
	(segment
		(start 182.3212 -38.1)
		(end 182.4228 -38.2016)
		(width 0.1143)
		(layer "F.Cu")
		(net "SVID_CPU_ALERT#")
	)
	(segment
		(start 13.68425 -61.63945)
		(end 13.3604 -61.3156)
		(width 0.1143)
		(layer "F.Cu")
		(net "SVID_CPU_ALERT#")
	)
	(via
		(at 80.137 -64.5414)
		(size 0.508)
		(drill 0.254)
		(layers "F.Cu" "B.Cu")
		(net "SVID_CPU_ALERT#")
	)
	(via
		(at 14.757908 -62.603634)
		(size 0.508)
		(drill 0.254)
		(layers "F.Cu" "B.Cu")
		(net "SVID_CPU_ALERT#")
	)
	(via
		(at 80.9498 -63.6016)
		(size 0.7112)
		(drill 0.3556)
		(layers "F.Cu" "B.Cu")
		(net "SVID_CPU_ALERT#")
	)
	(via
		(at 182.4228 -38.2016)
		(size 0.508)
		(drill 0.254)
		(layers "F.Cu" "B.Cu")
		(net "SVID_CPU_ALERT#")
	)
	(segment
		(start 80.137 -63.6778)
		(end 80.137 -64.5414)
		(width 0.1143)
		(layer "B.Cu")
		(net "SVID_CPU_ALERT#")
	)
	(segment
		(start 80.137 -65.3542)
		(end 80.137 -64.5414)
		(width 0.1143)
		(layer "B.Cu")
		(net "SVID_CPU_ALERT#")
	)
	(segment
		(start 14.757908 -62.603634)
		(end 15.0876 -62.933326)
		(width 0.0889)
		(layer "In4.Cu")
		(net "SVID_CPU_ALERT#")
	)
	(segment
		(start 190.950342 -72.053704)
		(end 193.976498 -69.027548)
		(width 0.0889)
		(layer "In4.Cu")
		(net "SVID_CPU_ALERT#")
	)
	(segment
		(start 181.47665 -39.494714)
		(end 181.56555 -39.405814)
		(width 0.0889)
		(layer "In4.Cu")
		(net "SVID_CPU_ALERT#")
	)
	(segment
		(start 181.61 -41.636696)
		(end 181.61 -41.236646)
		(width 0.0889)
		(layer "In4.Cu")
		(net "SVID_CPU_ALERT#")
	)
	(segment
		(start 181.47665 -43.903646)
		(end 181.61 -43.770296)
		(width 0.0889)
		(layer "In4.Cu")
		(net "SVID_CPU_ALERT#")
	)
	(segment
		(start 181.9402 -40.472614)
		(end 182.0926 -40.320214)
		(width 0.0889)
		(layer "In4.Cu")
		(net "SVID_CPU_ALERT#")
	)
	(segment
		(start 191.4398 -53.0606)
		(end 189.826646 -53.0606)
		(width 0.0889)
		(layer "In4.Cu")
		(net "SVID_CPU_ALERT#")
	)
	(segment
		(start 193.976498 -69.027548)
		(end 193.976498 -55.597298)
		(width 0.0889)
		(layer "In4.Cu")
		(net "SVID_CPU_ALERT#")
	)
	(segment
		(start 181.356 -38.783514)
		(end 181.356 -37.9603)
		(width 0.0889)
		(layer "In4.Cu")
		(net "SVID_CPU_ALERT#")
	)
	(segment
		(start 14.07795 -64.0842)
		(end 14.07795 -68.055744)
		(width 0.0889)
		(layer "In4.Cu")
		(net "SVID_CPU_ALERT#")
	)
	(segment
		(start 46.52645 -68.45935)
		(end 58.73242 -68.45935)
		(width 0.0889)
		(layer "In4.Cu")
		(net "SVID_CPU_ALERT#")
	)
	(segment
		(start 182.118 -38.974014)
		(end 182.0164 -38.872414)
		(width 0.0889)
		(layer "In4.Cu")
		(net "SVID_CPU_ALERT#")
	)
	(segment
		(start 181.61 -42.303446)
		(end 181.47665 -42.170096)
		(width 0.0889)
		(layer "In4.Cu")
		(net "SVID_CPU_ALERT#")
	)
	(segment
		(start 181.61 -41.236646)
		(end 181.47665 -41.103296)
		(width 0.0889)
		(layer "In4.Cu")
		(net "SVID_CPU_ALERT#")
	)
	(segment
		(start 181.56555 -39.939214)
		(end 181.47665 -39.850314)
		(width 0.0889)
		(layer "In4.Cu")
		(net "SVID_CPU_ALERT#")
	)
	(segment
		(start 189.826646 -53.0606)
		(end 181.47665 -44.710604)
		(width 0.0889)
		(layer "In4.Cu")
		(net "SVID_CPU_ALERT#")
	)
	(segment
		(start 181.47665 -42.836846)
		(end 181.61 -42.703496)
		(width 0.0889)
		(layer "In4.Cu")
		(net "SVID_CPU_ALERT#")
	)
	(segment
		(start 15.0876 -63.8302)
		(end 14.9606 -63.9572)
		(width 0.0889)
		(layer "In4.Cu")
		(net "SVID_CPU_ALERT#")
	)
	(segment
		(start 74.64171 -68.86575)
		(end 84.289392 -68.86575)
		(width 0.0889)
		(layer "In4.Cu")
		(net "SVID_CPU_ALERT#")
	)
	(segment
		(start 181.61 -42.703496)
		(end 181.61 -42.303446)
		(width 0.0889)
		(layer "In4.Cu")
		(net "SVID_CPU_ALERT#")
	)
	(segment
		(start 181.47665 -41.770046)
		(end 181.61 -41.636696)
		(width 0.0889)
		(layer "In4.Cu")
		(net "SVID_CPU_ALERT#")
	)
	(segment
		(start 181.4449 -37.8714)
		(end 182.0926 -37.8714)
		(width 0.0889)
		(layer "In4.Cu")
		(net "SVID_CPU_ALERT#")
	)
	(segment
		(start 181.56555 -40.472614)
		(end 181.9402 -40.472614)
		(width 0.0889)
		(layer "In4.Cu")
		(net "SVID_CPU_ALERT#")
	)
	(segment
		(start 182.118 -39.304214)
		(end 182.118 -38.974014)
		(width 0.0889)
		(layer "In4.Cu")
		(net "SVID_CPU_ALERT#")
	)
	(segment
		(start 181.47665 -42.170096)
		(end 181.47665 -41.770046)
		(width 0.0889)
		(layer "In4.Cu")
		(net "SVID_CPU_ALERT#")
	)
	(segment
		(start 15.0876 -62.933326)
		(end 15.0876 -63.8302)
		(width 0.0889)
		(layer "In4.Cu")
		(net "SVID_CPU_ALERT#")
	)
	(segment
		(start 181.47665 -44.710604)
		(end 181.47665 -43.903646)
		(width 0.0889)
		(layer "In4.Cu")
		(net "SVID_CPU_ALERT#")
	)
	(segment
		(start 73.582022 -69.925438)
		(end 74.64171 -68.86575)
		(width 0.0889)
		(layer "In4.Cu")
		(net "SVID_CPU_ALERT#")
	)
	(segment
		(start 181.356 -37.9603)
		(end 181.4449 -37.8714)
		(width 0.0889)
		(layer "In4.Cu")
		(net "SVID_CPU_ALERT#")
	)
	(segment
		(start 181.47665 -43.236896)
		(end 181.47665 -42.836846)
		(width 0.0889)
		(layer "In4.Cu")
		(net "SVID_CPU_ALERT#")
	)
	(segment
		(start 84.683092 -69.25945)
		(end 88.20658 -69.25945)
		(width 0.0889)
		(layer "In4.Cu")
		(net "SVID_CPU_ALERT#")
	)
	(segment
		(start 181.61 -43.770296)
		(end 181.61 -43.370246)
		(width 0.0889)
		(layer "In4.Cu")
		(net "SVID_CPU_ALERT#")
	)
	(segment
		(start 182.0926 -37.8714)
		(end 182.4228 -38.2016)
		(width 0.0889)
		(layer "In4.Cu")
		(net "SVID_CPU_ALERT#")
	)
	(segment
		(start 193.976498 -55.597298)
		(end 191.4398 -53.0606)
		(width 0.0889)
		(layer "In4.Cu")
		(net "SVID_CPU_ALERT#")
	)
	(segment
		(start 181.9402 -39.939214)
		(end 181.56555 -39.939214)
		(width 0.0889)
		(layer "In4.Cu")
		(net "SVID_CPU_ALERT#")
	)
	(segment
		(start 182.0926 -40.320214)
		(end 182.0926 -40.091614)
		(width 0.0889)
		(layer "In4.Cu")
		(net "SVID_CPU_ALERT#")
	)
	(segment
		(start 14.20495 -63.9572)
		(end 14.07795 -64.0842)
		(width 0.0889)
		(layer "In4.Cu")
		(net "SVID_CPU_ALERT#")
	)
	(segment
		(start 181.47665 -39.850314)
		(end 181.47665 -39.494714)
		(width 0.0889)
		(layer "In4.Cu")
		(net "SVID_CPU_ALERT#")
	)
	(segment
		(start 182.0926 -40.091614)
		(end 181.9402 -39.939214)
		(width 0.0889)
		(layer "In4.Cu")
		(net "SVID_CPU_ALERT#")
	)
	(segment
		(start 84.289392 -68.86575)
		(end 84.683092 -69.25945)
		(width 0.0889)
		(layer "In4.Cu")
		(net "SVID_CPU_ALERT#")
	)
	(segment
		(start 58.73242 -68.45935)
		(end 60.198508 -69.925438)
		(width 0.0889)
		(layer "In4.Cu")
		(net "SVID_CPU_ALERT#")
	)
	(segment
		(start 60.198508 -69.925438)
		(end 73.582022 -69.925438)
		(width 0.0889)
		(layer "In4.Cu")
		(net "SVID_CPU_ALERT#")
	)
	(segment
		(start 181.61 -43.370246)
		(end 181.47665 -43.236896)
		(width 0.0889)
		(layer "In4.Cu")
		(net "SVID_CPU_ALERT#")
	)
	(segment
		(start 44.10075 -70.88505)
		(end 46.52645 -68.45935)
		(width 0.0889)
		(layer "In4.Cu")
		(net "SVID_CPU_ALERT#")
	)
	(segment
		(start 181.47665 -41.103296)
		(end 181.47665 -40.561514)
		(width 0.0889)
		(layer "In4.Cu")
		(net "SVID_CPU_ALERT#")
	)
	(segment
		(start 88.20658 -69.25945)
		(end 91.000834 -72.053704)
		(width 0.0889)
		(layer "In4.Cu")
		(net "SVID_CPU_ALERT#")
	)
	(segment
		(start 182.0164 -39.405814)
		(end 182.118 -39.304214)
		(width 0.0889)
		(layer "In4.Cu")
		(net "SVID_CPU_ALERT#")
	)
	(segment
		(start 181.56555 -39.405814)
		(end 182.0164 -39.405814)
		(width 0.0889)
		(layer "In4.Cu")
		(net "SVID_CPU_ALERT#")
	)
	(segment
		(start 182.0164 -38.872414)
		(end 181.4449 -38.872414)
		(width 0.0889)
		(layer "In4.Cu")
		(net "SVID_CPU_ALERT#")
	)
	(segment
		(start 181.47665 -40.561514)
		(end 181.56555 -40.472614)
		(width 0.0889)
		(layer "In4.Cu")
		(net "SVID_CPU_ALERT#")
	)
	(segment
		(start 181.4449 -38.872414)
		(end 181.356 -38.783514)
		(width 0.0889)
		(layer "In4.Cu")
		(net "SVID_CPU_ALERT#")
	)
	(segment
		(start 16.907256 -70.88505)
		(end 44.10075 -70.88505)
		(width 0.0889)
		(layer "In4.Cu")
		(net "SVID_CPU_ALERT#")
	)
	(segment
		(start 14.07795 -68.055744)
		(end 16.907256 -70.88505)
		(width 0.0889)
		(layer "In4.Cu")
		(net "SVID_CPU_ALERT#")
	)
	(segment
		(start 91.000834 -72.053704)
		(end 190.950342 -72.053704)
		(width 0.0889)
		(layer "In4.Cu")
		(net "SVID_CPU_ALERT#")
	)
	(segment
		(start 14.9606 -63.9572)
		(end 14.20495 -63.9572)
		(width 0.0889)
		(layer "In4.Cu")
		(net "SVID_CPU_ALERT#")
	)
	(segment
		(start 16.256 -67.05473)
		(end 19.95932 -70.75805)
		(width 0.0889)
		(layer "In7.Cu")
		(net "SVID_CPU_ALERT#")
	)
	(segment
		(start 68.002658 -65.983866)
		(end 68.128134 -65.983866)
		(width 0.0889)
		(layer "In7.Cu")
		(net "SVID_CPU_ALERT#")
	)
	(segment
		(start 80.137 -64.6938)
		(end 80.137 -64.5414)
		(width 0.0889)
		(layer "In7.Cu")
		(net "SVID_CPU_ALERT#")
	)
	(segment
		(start 19.95932 -70.75805)
		(end 43.92295 -70.75805)
		(width 0.0889)
		(layer "In7.Cu")
		(net "SVID_CPU_ALERT#")
	)
	(segment
		(start 15.230348 -63.076074)
		(end 15.355824 -63.076074)
		(width 0.0889)
		(layer "In7.Cu")
		(net "SVID_CPU_ALERT#")
	)
	(segment
		(start 66.613278 -66.355722)
		(end 66.802254 -66.166746)
		(width 0.0889)
		(layer "In7.Cu")
		(net "SVID_CPU_ALERT#")
	)
	(segment
		(start 67.059302 -66.927222)
		(end 66.613278 -66.481198)
		(width 0.0889)
		(layer "In7.Cu")
		(net "SVID_CPU_ALERT#")
	)
	(segment
		(start 46.0629 -68.6181)
		(end 65.4939 -68.6181)
		(width 0.0889)
		(layer "In7.Cu")
		(net "SVID_CPU_ALERT#")
	)
	(segment
		(start 67.373754 -66.61277)
		(end 67.49923 -66.61277)
		(width 0.0889)
		(layer "In7.Cu")
		(net "SVID_CPU_ALERT#")
	)
	(segment
		(start 16.383 -62.865)
		(end 15.89151 -63.35649)
		(width 0.0889)
		(layer "In7.Cu")
		(net "SVID_CPU_ALERT#")
	)
	(segment
		(start 14.757908 -62.603634)
		(end 15.230348 -63.076074)
		(width 0.0889)
		(layer "In7.Cu")
		(net "SVID_CPU_ALERT#")
	)
	(segment
		(start 16.383 -62.738508)
		(end 16.383 -62.865)
		(width 0.0889)
		(layer "In7.Cu")
		(net "SVID_CPU_ALERT#")
	)
	(segment
		(start 15.355824 -63.076074)
		(end 15.975584 -62.456568)
		(width 0.0889)
		(layer "In7.Cu")
		(net "SVID_CPU_ALERT#")
	)
	(segment
		(start 15.89151 -63.737236)
		(end 16.256 -64.101726)
		(width 0.0889)
		(layer "In7.Cu")
		(net "SVID_CPU_ALERT#")
	)
	(segment
		(start 68.128134 -65.983866)
		(end 68.961 -65.151)
		(width 0.0889)
		(layer "In7.Cu")
		(net "SVID_CPU_ALERT#")
	)
	(segment
		(start 66.613278 -66.481198)
		(end 66.613278 -66.355722)
		(width 0.0889)
		(layer "In7.Cu")
		(net "SVID_CPU_ALERT#")
	)
	(segment
		(start 67.688206 -66.298318)
		(end 67.305682 -65.915794)
		(width 0.0889)
		(layer "In7.Cu")
		(net "SVID_CPU_ALERT#")
	)
	(segment
		(start 67.494658 -65.601342)
		(end 67.620134 -65.601342)
		(width 0.0889)
		(layer "In7.Cu")
		(net "SVID_CPU_ALERT#")
	)
	(segment
		(start 67.620134 -65.601342)
		(end 68.002658 -65.983866)
		(width 0.0889)
		(layer "In7.Cu")
		(net "SVID_CPU_ALERT#")
	)
	(segment
		(start 67.49923 -66.61277)
		(end 67.688206 -66.423794)
		(width 0.0889)
		(layer "In7.Cu")
		(net "SVID_CPU_ALERT#")
	)
	(segment
		(start 15.89151 -63.35649)
		(end 15.89151 -63.737236)
		(width 0.0889)
		(layer "In7.Cu")
		(net "SVID_CPU_ALERT#")
	)
	(segment
		(start 65.4939 -68.6181)
		(end 67.059302 -67.052698)
		(width 0.0889)
		(layer "In7.Cu")
		(net "SVID_CPU_ALERT#")
	)
	(segment
		(start 16.10106 -62.456568)
		(end 16.383 -62.738508)
		(width 0.0889)
		(layer "In7.Cu")
		(net "SVID_CPU_ALERT#")
	)
	(segment
		(start 16.256 -64.101726)
		(end 16.256 -67.05473)
		(width 0.0889)
		(layer "In7.Cu")
		(net "SVID_CPU_ALERT#")
	)
	(segment
		(start 68.961 -65.151)
		(end 79.6798 -65.151)
		(width 0.0889)
		(layer "In7.Cu")
		(net "SVID_CPU_ALERT#")
	)
	(segment
		(start 67.059302 -67.052698)
		(end 67.059302 -66.927222)
		(width 0.0889)
		(layer "In7.Cu")
		(net "SVID_CPU_ALERT#")
	)
	(segment
		(start 67.305682 -65.915794)
		(end 67.305682 -65.790318)
		(width 0.0889)
		(layer "In7.Cu")
		(net "SVID_CPU_ALERT#")
	)
	(segment
		(start 43.92295 -70.75805)
		(end 46.0629 -68.6181)
		(width 0.0889)
		(layer "In7.Cu")
		(net "SVID_CPU_ALERT#")
	)
	(segment
		(start 15.975584 -62.456568)
		(end 16.10106 -62.456568)
		(width 0.0889)
		(layer "In7.Cu")
		(net "SVID_CPU_ALERT#")
	)
	(segment
		(start 66.92773 -66.166746)
		(end 67.373754 -66.61277)
		(width 0.0889)
		(layer "In7.Cu")
		(net "SVID_CPU_ALERT#")
	)
	(segment
		(start 66.802254 -66.166746)
		(end 66.92773 -66.166746)
		(width 0.0889)
		(layer "In7.Cu")
		(net "SVID_CPU_ALERT#")
	)
	(segment
		(start 67.305682 -65.790318)
		(end 67.494658 -65.601342)
		(width 0.0889)
		(layer "In7.Cu")
		(net "SVID_CPU_ALERT#")
	)
	(segment
		(start 79.6798 -65.151)
		(end 80.137 -64.6938)
		(width 0.0889)
		(layer "In7.Cu")
		(net "SVID_CPU_ALERT#")
	)
	(segment
		(start 67.688206 -66.423794)
		(end 67.688206 -66.298318)
		(width 0.0889)
		(layer "In7.Cu")
		(net "SVID_CPU_ALERT#")
	)
	(segment
		(start 166.332154 -48.762412)
		(end 166.477188 -48.762412)
		(width 0.1143)
		(layer "F.Cu")
		(net "XDP_SOC_CPU_TRST#")
	)
	(segment
		(start 33.981644 -34.2138)
		(end 33.981644 -33.851342)
		(width 0.1143)
		(layer "F.Cu")
		(net "XDP_SOC_CPU_TRST#")
	)
	(segment
		(start 34.777426 -33.05556)
		(end 36.37788 -33.05556)
		(width 0.1143)
		(layer "F.Cu")
		(net "XDP_SOC_CPU_TRST#")
	)
	(segment
		(start 33.828228 -34.2138)
		(end 33.040828 -35.0012)
		(width 0.1143)
		(layer "F.Cu")
		(net "XDP_SOC_CPU_TRST#")
	)
	(segment
		(start 88.657684 -37.084)
		(end 88.639396 -37.102288)
		(width 0.1143)
		(layer "F.Cu")
		(net "XDP_SOC_CPU_TRST#")
	)
	(segment
		(start 33.981644 -33.851342)
		(end 34.777426 -33.05556)
		(width 0.1143)
		(layer "F.Cu")
		(net "XDP_SOC_CPU_TRST#")
	)
	(segment
		(start 89.020904 -37.084)
		(end 88.657684 -37.084)
		(width 0.1143)
		(layer "F.Cu")
		(net "XDP_SOC_CPU_TRST#")
	)
	(segment
		(start 33.040828 -35.0012)
		(end 32.3088 -35.0012)
		(width 0.1143)
		(layer "F.Cu")
		(net "XDP_SOC_CPU_TRST#")
	)
	(segment
		(start 33.981644 -34.2138)
		(end 33.828228 -34.2138)
		(width 0.1143)
		(layer "F.Cu")
		(net "XDP_SOC_CPU_TRST#")
	)
	(segment
		(start 166.8018 -48.4378)
		(end 166.8018 -48.006)
		(width 0.1143)
		(layer "F.Cu")
		(net "XDP_SOC_CPU_TRST#")
	)
	(segment
		(start 89.850468 -36.254436)
		(end 89.020904 -37.084)
		(width 0.1143)
		(layer "F.Cu")
		(net "XDP_SOC_CPU_TRST#")
	)
	(segment
		(start 88.639396 -37.102288)
		(end 88.580722 -37.102288)
		(width 0.1143)
		(layer "F.Cu")
		(net "XDP_SOC_CPU_TRST#")
	)
	(segment
		(start 89.850468 -35.999674)
		(end 89.850468 -36.254436)
		(width 0.1143)
		(layer "F.Cu")
		(net "XDP_SOC_CPU_TRST#")
	)
	(segment
		(start 166.477188 -48.762412)
		(end 166.8018 -48.4378)
		(width 0.1143)
		(layer "F.Cu")
		(net "XDP_SOC_CPU_TRST#")
	)
	(via
		(at 88.580722 -37.102288)
		(size 0.4318)
		(drill 0.2032)
		(layers "F.Cu" "B.Cu")
		(net "XDP_SOC_CPU_TRST#")
	)
	(via
		(at 33.981644 -34.2138)
		(size 0.508)
		(drill 0.254)
		(layers "F.Cu" "B.Cu")
		(net "XDP_SOC_CPU_TRST#")
	)
	(via
		(at 56.2356 -16.383)
		(size 0.508)
		(drill 0.254)
		(layers "F.Cu" "B.Cu")
		(net "XDP_SOC_CPU_TRST#")
	)
	(via
		(at 166.332154 -48.762412)
		(size 0.508)
		(drill 0.254)
		(layers "F.Cu" "B.Cu")
		(net "XDP_SOC_CPU_TRST#")
	)
	(via
		(at 68.5292 -63.6778)
		(size 0.508)
		(drill 0.254)
		(layers "F.Cu" "B.Cu")
		(net "XDP_SOC_CPU_TRST#")
	)
	(via
		(at 187.9346 -54.0512)
		(size 0.508)
		(drill 0.254)
		(layers "F.Cu" "B.Cu")
		(net "XDP_SOC_CPU_TRST#")
	)
	(via
		(at 57.8612 -25.7048)
		(size 0.508)
		(drill 0.254)
		(layers "F.Cu" "B.Cu")
		(net "XDP_SOC_CPU_TRST#")
	)
	(segment
		(start 57.2262 -13.7668)
		(end 57.2262 -13.1064)
		(width 0.1143)
		(layer "B.Cu")
		(net "XDP_SOC_CPU_TRST#")
	)
	(segment
		(start 33.4264 -33.02)
		(end 32.67075 -32.26435)
		(width 0.1143)
		(layer "B.Cu")
		(net "XDP_SOC_CPU_TRST#")
	)
	(segment
		(start 57.2262 -13.1064)
		(end 56.3372 -12.2174)
		(width 0.1143)
		(layer "B.Cu")
		(net "XDP_SOC_CPU_TRST#")
	)
	(segment
		(start 31.162498 -32.263334)
		(end 31.160466 -32.263334)
		(width 0.1143)
		(layer "B.Cu")
		(net "XDP_SOC_CPU_TRST#")
	)
	(segment
		(start 33.4264 -33.658556)
		(end 33.4264 -33.02)
		(width 0.1143)
		(layer "B.Cu")
		(net "XDP_SOC_CPU_TRST#")
	)
	(segment
		(start 33.981644 -34.2138)
		(end 33.4264 -33.658556)
		(width 0.1143)
		(layer "B.Cu")
		(net "XDP_SOC_CPU_TRST#")
	)
	(segment
		(start 56.2356 -16.383)
		(end 56.2356 -14.7574)
		(width 0.1143)
		(layer "B.Cu")
		(net "XDP_SOC_CPU_TRST#")
	)
	(segment
		(start 32.67075 -32.26435)
		(end 31.163514 -32.26435)
		(width 0.1143)
		(layer "B.Cu")
		(net "XDP_SOC_CPU_TRST#")
	)
	(segment
		(start 31.160466 -32.263334)
		(end 30.6832 -32.7406)
		(width 0.1143)
		(layer "B.Cu")
		(net "XDP_SOC_CPU_TRST#")
	)
	(segment
		(start 31.163514 -32.26435)
		(end 31.162498 -32.263334)
		(width 0.1143)
		(layer "B.Cu")
		(net "XDP_SOC_CPU_TRST#")
	)
	(segment
		(start 56.2356 -14.7574)
		(end 57.2262 -13.7668)
		(width 0.1143)
		(layer "B.Cu")
		(net "XDP_SOC_CPU_TRST#")
	)
	(segment
		(start 55.260748 -52.008786)
		(end 61.964062 -58.7121)
		(width 0.0889)
		(layer "In2.Cu")
		(net "XDP_SOC_CPU_TRST#")
	)
	(segment
		(start 41.9735 -41.751758)
		(end 42.379392 -42.15765)
		(width 0.0889)
		(layer "In2.Cu")
		(net "XDP_SOC_CPU_TRST#")
	)
	(segment
		(start 43.42765 -42.15765)
		(end 44.3103 -43.0403)
		(width 0.0889)
		(layer "In2.Cu")
		(net "XDP_SOC_CPU_TRST#")
	)
	(segment
		(start 54.520592 -52.008786)
		(end 55.260748 -52.008786)
		(width 0.0889)
		(layer "In2.Cu")
		(net "XDP_SOC_CPU_TRST#")
	)
	(segment
		(start 51.688238 -46.999144)
		(end 51.952144 -47.26305)
		(width 0.0889)
		(layer "In2.Cu")
		(net "XDP_SOC_CPU_TRST#")
	)
	(segment
		(start 46.801024 -44.896024)
		(end 48.904144 -46.999144)
		(width 0.0889)
		(layer "In2.Cu")
		(net "XDP_SOC_CPU_TRST#")
	)
	(segment
		(start 46.801024 -43.587924)
		(end 46.801024 -44.896024)
		(width 0.0889)
		(layer "In2.Cu")
		(net "XDP_SOC_CPU_TRST#")
	)
	(segment
		(start 68.5292 -63.146178)
		(end 68.5292 -63.6778)
		(width 0.0889)
		(layer "In2.Cu")
		(net "XDP_SOC_CPU_TRST#")
	)
	(segment
		(start 61.964062 -58.7121)
		(end 64.095122 -58.7121)
		(width 0.0889)
		(layer "In2.Cu")
		(net "XDP_SOC_CPU_TRST#")
	)
	(segment
		(start 51.952144 -47.26305)
		(end 51.952144 -48.239426)
		(width 0.0889)
		(layer "In2.Cu")
		(net "XDP_SOC_CPU_TRST#")
	)
	(segment
		(start 46.2534 -43.0403)
		(end 46.801024 -43.587924)
		(width 0.0889)
		(layer "In2.Cu")
		(net "XDP_SOC_CPU_TRST#")
	)
	(segment
		(start 38.10762 -34.2138)
		(end 41.9735 -38.07968)
		(width 0.0889)
		(layer "In2.Cu")
		(net "XDP_SOC_CPU_TRST#")
	)
	(segment
		(start 41.9735 -38.07968)
		(end 41.9735 -41.751758)
		(width 0.0889)
		(layer "In2.Cu")
		(net "XDP_SOC_CPU_TRST#")
	)
	(segment
		(start 54.256686 -51.74488)
		(end 54.520592 -52.008786)
		(width 0.0889)
		(layer "In2.Cu")
		(net "XDP_SOC_CPU_TRST#")
	)
	(segment
		(start 51.9938 -48.281082)
		(end 51.9938 -49.364392)
		(width 0.0889)
		(layer "In2.Cu")
		(net "XDP_SOC_CPU_TRST#")
	)
	(segment
		(start 54.256686 -51.627278)
		(end 54.256686 -51.74488)
		(width 0.0889)
		(layer "In2.Cu")
		(net "XDP_SOC_CPU_TRST#")
	)
	(segment
		(start 48.904144 -46.999144)
		(end 51.688238 -46.999144)
		(width 0.0889)
		(layer "In2.Cu")
		(net "XDP_SOC_CPU_TRST#")
	)
	(segment
		(start 42.379392 -42.15765)
		(end 43.42765 -42.15765)
		(width 0.0889)
		(layer "In2.Cu")
		(net "XDP_SOC_CPU_TRST#")
	)
	(segment
		(start 64.095122 -58.7121)
		(end 68.5292 -63.146178)
		(width 0.0889)
		(layer "In2.Cu")
		(net "XDP_SOC_CPU_TRST#")
	)
	(segment
		(start 33.981644 -34.2138)
		(end 38.10762 -34.2138)
		(width 0.0889)
		(layer "In2.Cu")
		(net "XDP_SOC_CPU_TRST#")
	)
	(segment
		(start 51.9938 -49.364392)
		(end 54.256686 -51.627278)
		(width 0.0889)
		(layer "In2.Cu")
		(net "XDP_SOC_CPU_TRST#")
	)
	(segment
		(start 51.952144 -48.239426)
		(end 51.9938 -48.281082)
		(width 0.0889)
		(layer "In2.Cu")
		(net "XDP_SOC_CPU_TRST#")
	)
	(segment
		(start 44.3103 -43.0403)
		(end 46.2534 -43.0403)
		(width 0.0889)
		(layer "In2.Cu")
		(net "XDP_SOC_CPU_TRST#")
	)
	(segment
		(start 188.41085 -55.12435)
		(end 188.41085 -54.47665)
		(width 0.0889)
		(layer "In4.Cu")
		(net "XDP_SOC_CPU_TRST#")
	)
	(segment
		(start 55.223918 -25.7048)
		(end 57.8612 -25.7048)
		(width 0.0889)
		(layer "In4.Cu")
		(net "XDP_SOC_CPU_TRST#")
	)
	(segment
		(start 50.616612 -26.174446)
		(end 54.754272 -26.174446)
		(width 0.0889)
		(layer "In4.Cu")
		(net "XDP_SOC_CPU_TRST#")
	)
	(segment
		(start 190.4365 -69.547994)
		(end 190.4365 -65.419478)
		(width 0.0889)
		(layer "In4.Cu")
		(net "XDP_SOC_CPU_TRST#")
	)
	(segment
		(start 68.5292 -63.6778)
		(end 68.5292 -63.782194)
		(width 0.0889)
		(layer "In4.Cu")
		(net "XDP_SOC_CPU_TRST#")
	)
	(segment
		(start 191.643 -60.96)
		(end 187.7187 -57.0357)
		(width 0.0889)
		(layer "In4.Cu")
		(net "XDP_SOC_CPU_TRST#")
	)
	(segment
		(start 44.9834 -30.4546)
		(end 48.789336 -26.648664)
		(width 0.0889)
		(layer "In4.Cu")
		(net "XDP_SOC_CPU_TRST#")
	)
	(segment
		(start 86.218268 -65.061338)
		(end 91.53398 -70.37705)
		(width 0.0889)
		(layer "In4.Cu")
		(net "XDP_SOC_CPU_TRST#")
	)
	(segment
		(start 69.808344 -65.061338)
		(end 86.218268 -65.061338)
		(width 0.0889)
		(layer "In4.Cu")
		(net "XDP_SOC_CPU_TRST#")
	)
	(segment
		(start 91.53398 -70.37705)
		(end 189.607444 -70.37705)
		(width 0.0889)
		(layer "In4.Cu")
		(net "XDP_SOC_CPU_TRST#")
	)
	(segment
		(start 68.5292 -63.782194)
		(end 69.808344 -65.061338)
		(width 0.0889)
		(layer "In4.Cu")
		(net "XDP_SOC_CPU_TRST#")
	)
	(segment
		(start 191.643 -64.212978)
		(end 191.643 -60.96)
		(width 0.0889)
		(layer "In4.Cu")
		(net "XDP_SOC_CPU_TRST#")
	)
	(segment
		(start 54.754272 -26.174446)
		(end 55.223918 -25.7048)
		(width 0.0889)
		(layer "In4.Cu")
		(net "XDP_SOC_CPU_TRST#")
	)
	(segment
		(start 190.4365 -65.419478)
		(end 191.643 -64.212978)
		(width 0.0889)
		(layer "In4.Cu")
		(net "XDP_SOC_CPU_TRST#")
	)
	(segment
		(start 187.9854 -54.0512)
		(end 187.9346 -54.0512)
		(width 0.0889)
		(layer "In4.Cu")
		(net "XDP_SOC_CPU_TRST#")
	)
	(segment
		(start 187.7187 -55.8165)
		(end 188.41085 -55.12435)
		(width 0.0889)
		(layer "In4.Cu")
		(net "XDP_SOC_CPU_TRST#")
	)
	(segment
		(start 40.8178 -34.2138)
		(end 44.577 -30.4546)
		(width 0.0889)
		(layer "In4.Cu")
		(net "XDP_SOC_CPU_TRST#")
	)
	(segment
		(start 187.7187 -57.0357)
		(end 187.7187 -55.8165)
		(width 0.0889)
		(layer "In4.Cu")
		(net "XDP_SOC_CPU_TRST#")
	)
	(segment
		(start 188.41085 -54.47665)
		(end 187.9854 -54.0512)
		(width 0.0889)
		(layer "In4.Cu")
		(net "XDP_SOC_CPU_TRST#")
	)
	(segment
		(start 44.577 -30.4546)
		(end 44.9834 -30.4546)
		(width 0.0889)
		(layer "In4.Cu")
		(net "XDP_SOC_CPU_TRST#")
	)
	(segment
		(start 33.981644 -34.2138)
		(end 40.8178 -34.2138)
		(width 0.0889)
		(layer "In4.Cu")
		(net "XDP_SOC_CPU_TRST#")
	)
	(segment
		(start 50.142394 -26.648664)
		(end 50.616612 -26.174446)
		(width 0.0889)
		(layer "In4.Cu")
		(net "XDP_SOC_CPU_TRST#")
	)
	(segment
		(start 189.607444 -70.37705)
		(end 190.4365 -69.547994)
		(width 0.0889)
		(layer "In4.Cu")
		(net "XDP_SOC_CPU_TRST#")
	)
	(segment
		(start 48.789336 -26.648664)
		(end 50.142394 -26.648664)
		(width 0.0889)
		(layer "In4.Cu")
		(net "XDP_SOC_CPU_TRST#")
	)
	(segment
		(start 60.73775 -25.58415)
		(end 61.9506 -26.797)
		(width 0.0889)
		(layer "In7.Cu")
		(net "XDP_SOC_CPU_TRST#")
	)
	(segment
		(start 58.147966 -25.7048)
		(end 58.268616 -25.58415)
		(width 0.0889)
		(layer "In7.Cu")
		(net "XDP_SOC_CPU_TRST#")
	)
	(segment
		(start 83.035902 -35.524186)
		(end 83.076288 -35.4838)
		(width 0.0889)
		(layer "In7.Cu")
		(net "XDP_SOC_CPU_TRST#")
	)
	(segment
		(start 74.12355 -28.42895)
		(end 75.920346 -30.225746)
		(width 0.0889)
		(layer "In7.Cu")
		(net "XDP_SOC_CPU_TRST#")
	)
	(segment
		(start 75.920346 -30.225746)
		(end 75.920346 -30.625288)
		(width 0.0889)
		(layer "In7.Cu")
		(net "XDP_SOC_CPU_TRST#")
	)
	(segment
		(start 82.720688 -35.5092)
		(end 82.735674 -35.524186)
		(width 0.0889)
		(layer "In7.Cu")
		(net "XDP_SOC_CPU_TRST#")
	)
	(segment
		(start 69.724778 -29.0576)
		(end 70.353428 -28.42895)
		(width 0.0889)
		(layer "In7.Cu")
		(net "XDP_SOC_CPU_TRST#")
	)
	(segment
		(start 78.636114 -34.58845)
		(end 78.702916 -34.655252)
		(width 0.0889)
		(layer "In7.Cu")
		(net "XDP_SOC_CPU_TRST#")
	)
	(segment
		(start 67.7545 -29.0576)
		(end 69.724778 -29.0576)
		(width 0.0889)
		(layer "In7.Cu")
		(net "XDP_SOC_CPU_TRST#")
	)
	(segment
		(start 77.615796 -32.75076)
		(end 77.45095 -32.915606)
		(width 0.0889)
		(layer "In7.Cu")
		(net "XDP_SOC_CPU_TRST#")
	)
	(segment
		(start 58.268616 -25.58415)
		(end 60.73775 -25.58415)
		(width 0.0889)
		(layer "In7.Cu")
		(net "XDP_SOC_CPU_TRST#")
	)
	(segment
		(start 87.431372 -36.732972)
		(end 88.034114 -36.732972)
		(width 0.0889)
		(layer "In7.Cu")
		(net "XDP_SOC_CPU_TRST#")
	)
	(segment
		(start 81.310226 -35.5092)
		(end 82.720688 -35.5092)
		(width 0.0889)
		(layer "In7.Cu")
		(net "XDP_SOC_CPU_TRST#")
	)
	(segment
		(start 77.615796 -32.320738)
		(end 77.615796 -32.75076)
		(width 0.0889)
		(layer "In7.Cu")
		(net "XDP_SOC_CPU_TRST#")
	)
	(segment
		(start 82.735674 -35.524186)
		(end 83.035902 -35.524186)
		(width 0.0889)
		(layer "In7.Cu")
		(net "XDP_SOC_CPU_TRST#")
	)
	(segment
		(start 61.9506 -26.797)
		(end 65.4939 -26.797)
		(width 0.0889)
		(layer "In7.Cu")
		(net "XDP_SOC_CPU_TRST#")
	)
	(segment
		(start 83.076288 -35.4838)
		(end 86.1822 -35.4838)
		(width 0.0889)
		(layer "In7.Cu")
		(net "XDP_SOC_CPU_TRST#")
	)
	(segment
		(start 78.702916 -34.655252)
		(end 80.456278 -34.655252)
		(width 0.0889)
		(layer "In7.Cu")
		(net "XDP_SOC_CPU_TRST#")
	)
	(segment
		(start 86.1822 -35.4838)
		(end 87.431372 -36.732972)
		(width 0.0889)
		(layer "In7.Cu")
		(net "XDP_SOC_CPU_TRST#")
	)
	(segment
		(start 77.45095 -33.884108)
		(end 78.155292 -34.58845)
		(width 0.0889)
		(layer "In7.Cu")
		(net "XDP_SOC_CPU_TRST#")
	)
	(segment
		(start 80.456278 -34.655252)
		(end 81.310226 -35.5092)
		(width 0.0889)
		(layer "In7.Cu")
		(net "XDP_SOC_CPU_TRST#")
	)
	(segment
		(start 70.353428 -28.42895)
		(end 74.12355 -28.42895)
		(width 0.0889)
		(layer "In7.Cu")
		(net "XDP_SOC_CPU_TRST#")
	)
	(segment
		(start 77.45095 -32.915606)
		(end 77.45095 -33.884108)
		(width 0.0889)
		(layer "In7.Cu")
		(net "XDP_SOC_CPU_TRST#")
	)
	(segment
		(start 57.8612 -25.7048)
		(end 58.147966 -25.7048)
		(width 0.0889)
		(layer "In7.Cu")
		(net "XDP_SOC_CPU_TRST#")
	)
	(segment
		(start 88.034114 -36.732972)
		(end 88.40343 -37.102288)
		(width 0.0889)
		(layer "In7.Cu")
		(net "XDP_SOC_CPU_TRST#")
	)
	(segment
		(start 65.4939 -26.797)
		(end 67.7545 -29.0576)
		(width 0.0889)
		(layer "In7.Cu")
		(net "XDP_SOC_CPU_TRST#")
	)
	(segment
		(start 75.920346 -30.625288)
		(end 77.615796 -32.320738)
		(width 0.0889)
		(layer "In7.Cu")
		(net "XDP_SOC_CPU_TRST#")
	)
	(segment
		(start 88.40343 -37.102288)
		(end 88.580722 -37.102288)
		(width 0.0889)
		(layer "In7.Cu")
		(net "XDP_SOC_CPU_TRST#")
	)
	(segment
		(start 78.155292 -34.58845)
		(end 78.636114 -34.58845)
		(width 0.0889)
		(layer "In7.Cu")
		(net "XDP_SOC_CPU_TRST#")
	)
	(segment
		(start 56.2356 -16.383)
		(end 57.08015 -17.22755)
		(width 0.0889)
		(layer "In9.Cu")
		(net "XDP_SOC_CPU_TRST#")
	)
	(segment
		(start 57.08015 -17.22755)
		(end 57.08015 -24.628094)
		(width 0.0889)
		(layer "In9.Cu")
		(net "XDP_SOC_CPU_TRST#")
	)
	(segment
		(start 57.8612 -25.409144)
		(end 57.8612 -25.7048)
		(width 0.0889)
		(layer "In9.Cu")
		(net "XDP_SOC_CPU_TRST#")
	)
	(segment
		(start 166.332154 -48.762412)
		(end 166.332154 -49.139348)
		(width 0.0889)
		(layer "In9.Cu")
		(net "XDP_SOC_CPU_TRST#")
	)
	(segment
		(start 166.332154 -49.139348)
		(end 171.434506 -54.2417)
		(width 0.0889)
		(layer "In9.Cu")
		(net "XDP_SOC_CPU_TRST#")
	)
	(segment
		(start 187.7441 -54.2417)
		(end 187.9346 -54.0512)
		(width 0.0889)
		(layer "In9.Cu")
		(net "XDP_SOC_CPU_TRST#")
	)
	(segment
		(start 171.434506 -54.2417)
		(end 187.7441 -54.2417)
		(width 0.0889)
		(layer "In9.Cu")
		(net "XDP_SOC_CPU_TRST#")
	)
	(segment
		(start 57.08015 -24.628094)
		(end 57.8612 -25.409144)
		(width 0.0889)
		(layer "In9.Cu")
		(net "XDP_SOC_CPU_TRST#")
	)
	(segment
		(start 43.7896 -32.659828)
		(end 43.7896 -35.2298)
		(width 0.1143)
		(layer "F.Cu")
		(net "XDP_RTEST#")
	)
	(segment
		(start 37.73805 -37.343842)
		(end 37.73805 -37.57295)
		(width 0.1143)
		(layer "F.Cu")
		(net "XDP_RTEST#")
	)
	(segment
		(start 47.5488 -34.925)
		(end 46.657514 -35.816286)
		(width 0.1143)
		(layer "F.Cu")
		(net "XDP_RTEST#")
	)
	(segment
		(start 43.743626 -31.55315)
		(end 44.139104 -31.948628)
		(width 0.1143)
		(layer "F.Cu")
		(net "XDP_RTEST#")
	)
	(segment
		(start 44.26585 -35.70605)
		(end 44.26585 -36.1823)
		(width 0.1143)
		(layer "F.Cu")
		(net "XDP_RTEST#")
	)
	(segment
		(start 44.139104 -31.948628)
		(end 44.139104 -32.310324)
		(width 0.1143)
		(layer "F.Cu")
		(net "XDP_RTEST#")
	)
	(segment
		(start 43.7896 -35.2298)
		(end 44.26585 -35.70605)
		(width 0.1143)
		(layer "F.Cu")
		(net "XDP_RTEST#")
	)
	(segment
		(start 37.73805 -37.57295)
		(end 36.83 -38.481)
		(width 0.1143)
		(layer "F.Cu")
		(net "XDP_RTEST#")
	)
	(segment
		(start 43.97248 -37.719)
		(end 44.2214 -37.719)
		(width 0.1143)
		(layer "F.Cu")
		(net "XDP_RTEST#")
	)
	(segment
		(start 45.293026 -36.79825)
		(end 44.8818 -36.79825)
		(width 0.1143)
		(layer "F.Cu")
		(net "XDP_RTEST#")
	)
	(segment
		(start 42.10177 -31.55442)
		(end 40.52951 -31.55442)
		(width 0.1143)
		(layer "F.Cu")
		(net "XDP_RTEST#")
	)
	(segment
		(start 44.26585 -36.1823)
		(end 44.8818 -36.79825)
		(width 0.1143)
		(layer "F.Cu")
		(net "XDP_RTEST#")
	)
	(segment
		(start 38.6334 -33.45053)
		(end 38.6334 -36.448492)
		(width 0.1143)
		(layer "F.Cu")
		(net "XDP_RTEST#")
	)
	(segment
		(start 38.6334 -36.448492)
		(end 37.73805 -37.343842)
		(width 0.1143)
		(layer "F.Cu")
		(net "XDP_RTEST#")
	)
	(segment
		(start 44.2214 -37.719)
		(end 44.8818 -37.0586)
		(width 0.1143)
		(layer "F.Cu")
		(net "XDP_RTEST#")
	)
	(segment
		(start 40.52951 -31.55442)
		(end 38.6334 -33.45053)
		(width 0.1143)
		(layer "F.Cu")
		(net "XDP_RTEST#")
	)
	(segment
		(start 44.139104 -32.310324)
		(end 43.7896 -32.659828)
		(width 0.1143)
		(layer "F.Cu")
		(net "XDP_RTEST#")
	)
	(segment
		(start 42.971974 -31.55315)
		(end 43.743626 -31.55315)
		(width 0.1143)
		(layer "F.Cu")
		(net "XDP_RTEST#")
	)
	(segment
		(start 44.8818 -37.0586)
		(end 44.8818 -36.79825)
		(width 0.1143)
		(layer "F.Cu")
		(net "XDP_RTEST#")
	)
	(segment
		(start 42.970704 -31.55442)
		(end 42.971974 -31.55315)
		(width 0.1143)
		(layer "F.Cu")
		(net "XDP_RTEST#")
	)
	(segment
		(start 46.657514 -35.816286)
		(end 46.657514 -36.318698)
		(width 0.1143)
		(layer "F.Cu")
		(net "XDP_RTEST#")
	)
	(segment
		(start 46.326552 -36.64966)
		(end 45.441616 -36.64966)
		(width 0.1143)
		(layer "F.Cu")
		(net "XDP_RTEST#")
	)
	(segment
		(start 45.441616 -36.64966)
		(end 45.293026 -36.79825)
		(width 0.1143)
		(layer "F.Cu")
		(net "XDP_RTEST#")
	)
	(segment
		(start 42.10177 -31.55442)
		(end 42.970704 -31.55442)
		(width 0.1143)
		(layer "F.Cu")
		(net "XDP_RTEST#")
	)
	(segment
		(start 36.83 -38.481)
		(end 36.83 -38.6842)
		(width 0.1143)
		(layer "F.Cu")
		(net "XDP_RTEST#")
	)
	(segment
		(start 46.657514 -36.318698)
		(end 46.326552 -36.64966)
		(width 0.1143)
		(layer "F.Cu")
		(net "XDP_RTEST#")
	)
	(via
		(at 27.8384 -16.1798)
		(size 0.508)
		(drill 0.254)
		(layers "F.Cu" "B.Cu")
		(net "XDP_RTEST#")
	)
	(via
		(at 44.8818 -36.79825)
		(size 0.508)
		(drill 0.254)
		(layers "F.Cu" "B.Cu")
		(net "XDP_RTEST#")
	)
	(via
		(at 26.924 -15.5448)
		(size 0.7112)
		(drill 0.3556)
		(layers "F.Cu" "B.Cu")
		(net "XDP_RTEST#")
	)
	(segment
		(start 27.559 -16.1798)
		(end 27.8384 -16.1798)
		(width 0.1143)
		(layer "B.Cu")
		(net "XDP_RTEST#")
	)
	(segment
		(start 26.924 -15.5448)
		(end 27.559 -16.1798)
		(width 0.1143)
		(layer "B.Cu")
		(net "XDP_RTEST#")
	)
	(segment
		(start 27.79395 -16.22425)
		(end 27.79395 -17.255744)
		(width 0.0889)
		(layer "In9.Cu")
		(net "XDP_RTEST#")
	)
	(segment
		(start 43.366436 -36.79825)
		(end 44.8818 -36.79825)
		(width 0.0889)
		(layer "In9.Cu")
		(net "XDP_RTEST#")
	)
	(segment
		(start 36.7538 -30.185614)
		(end 43.366436 -36.79825)
		(width 0.0889)
		(layer "In9.Cu")
		(net "XDP_RTEST#")
	)
	(segment
		(start 30.08884 -17.51965)
		(end 33.63595 -21.06676)
		(width 0.0889)
		(layer "In9.Cu")
		(net "XDP_RTEST#")
	)
	(segment
		(start 33.931606 -22.352)
		(end 34.817812 -22.352)
		(width 0.0889)
		(layer "In9.Cu")
		(net "XDP_RTEST#")
	)
	(segment
		(start 33.63595 -21.06676)
		(end 33.63595 -22.056344)
		(width 0.0889)
		(layer "In9.Cu")
		(net "XDP_RTEST#")
	)
	(segment
		(start 27.79395 -17.255744)
		(end 28.057856 -17.51965)
		(width 0.0889)
		(layer "In9.Cu")
		(net "XDP_RTEST#")
	)
	(segment
		(start 33.63595 -22.056344)
		(end 33.931606 -22.352)
		(width 0.0889)
		(layer "In9.Cu")
		(net "XDP_RTEST#")
	)
	(segment
		(start 28.057856 -17.51965)
		(end 30.08884 -17.51965)
		(width 0.0889)
		(layer "In9.Cu")
		(net "XDP_RTEST#")
	)
	(segment
		(start 27.8384 -16.1798)
		(end 27.79395 -16.22425)
		(width 0.0889)
		(layer "In9.Cu")
		(net "XDP_RTEST#")
	)
	(segment
		(start 36.7538 -24.287988)
		(end 36.7538 -30.185614)
		(width 0.0889)
		(layer "In9.Cu")
		(net "XDP_RTEST#")
	)
	(segment
		(start 34.817812 -22.352)
		(end 36.7538 -24.287988)
		(width 0.0889)
		(layer "In9.Cu")
		(net "XDP_RTEST#")
	)
	(segment
		(start 86.305136 -41.107106)
		(end 86.305136 -41.109138)
		(width 0.1143)
		(layer "F.Cu")
		(net "IRQ_MCERR_R#")
	)
	(segment
		(start 86.695788 -40.716454)
		(end 86.305136 -41.107106)
		(width 0.1143)
		(layer "F.Cu")
		(net "IRQ_MCERR_R#")
	)
	(via
		(at 86.1441 -40.386)
		(size 0.7112)
		(drill 0.3556)
		(layers "F.Cu" "B.Cu")
		(net "IRQ_MCERR_R#")
	)
	(via
		(at 86.305136 -41.109138)
		(size 0.4318)
		(drill 0.2032)
		(layers "F.Cu" "B.Cu")
		(net "IRQ_MCERR_R#")
	)
	(segment
		(start 87.0077 -40.386)
		(end 86.1441 -40.386)
		(width 0.1143)
		(layer "B.Cu")
		(net "IRQ_MCERR_R#")
	)
	(segment
		(start 86.305136 -41.109138)
		(end 86.1441 -40.948102)
		(width 0.1143)
		(layer "B.Cu")
		(net "IRQ_MCERR_R#")
	)
	(segment
		(start 86.1441 -40.948102)
		(end 86.1441 -40.386)
		(width 0.1143)
		(layer "B.Cu")
		(net "IRQ_MCERR_R#")
	)
	(segment
		(start 87.0585 -40.4368)
		(end 87.0077 -40.386)
		(width 0.1143)
		(layer "B.Cu")
		(net "IRQ_MCERR_R#")
	)
	(segment
		(start 85.619336 -37.130482)
		(end 85.591142 -37.130482)
		(width 0.1143)
		(layer "F.Cu")
		(net "PU_INTRUDER#")
	)
	(segment
		(start 85.591142 -37.130482)
		(end 85.57768 -37.11702)
		(width 0.1143)
		(layer "F.Cu")
		(net "PU_INTRUDER#")
	)
	(segment
		(start 85.933788 -37.444934)
		(end 85.619336 -37.130482)
		(width 0.1143)
		(layer "F.Cu")
		(net "PU_INTRUDER#")
	)
	(via
		(at 85.57768 -37.11702)
		(size 0.4318)
		(drill 0.2032)
		(layers "F.Cu" "B.Cu")
		(net "PU_INTRUDER#")
	)
	(via
		(at 84.7852 -37.7698)
		(size 0.7112)
		(drill 0.3556)
		(layers "F.Cu" "B.Cu")
		(net "PU_INTRUDER#")
	)
	(segment
		(start 84.7852 -37.7698)
		(end 84.7852 -37.6428)
		(width 0.1143)
		(layer "B.Cu")
		(net "PU_INTRUDER#")
	)
	(segment
		(start 84.96935 -37.95395)
		(end 84.7852 -37.7698)
		(width 0.1143)
		(layer "B.Cu")
		(net "PU_INTRUDER#")
	)
	(segment
		(start 85.69579 -37.95395)
		(end 84.96935 -37.95395)
		(width 0.1143)
		(layer "B.Cu")
		(net "PU_INTRUDER#")
	)
	(segment
		(start 84.7852 -37.6428)
		(end 85.31098 -37.11702)
		(width 0.1143)
		(layer "B.Cu")
		(net "PU_INTRUDER#")
	)
	(segment
		(start 85.94344 -38.2016)
		(end 85.69579 -37.95395)
		(width 0.1143)
		(layer "B.Cu")
		(net "PU_INTRUDER#")
	)
	(segment
		(start 85.31098 -37.11702)
		(end 85.57768 -37.11702)
		(width 0.1143)
		(layer "B.Cu")
		(net "PU_INTRUDER#")
	)
	(segment
		(start 84.399628 -44.689014)
		(end 84.028534 -45.060108)
		(width 0.1143)
		(layer "F.Cu")
		(net "XDP_CPU_PRDY#")
	)
	(segment
		(start 42.10177 -21.05533)
		(end 39.952168 -21.05533)
		(width 0.1143)
		(layer "F.Cu")
		(net "XDP_CPU_PRDY#")
	)
	(segment
		(start 43.40733 -21.05533)
		(end 42.10177 -21.05533)
		(width 0.1143)
		(layer "F.Cu")
		(net "XDP_CPU_PRDY#")
	)
	(segment
		(start 84.409788 -44.689014)
		(end 84.399628 -44.689014)
		(width 0.1143)
		(layer "F.Cu")
		(net "XDP_CPU_PRDY#")
	)
	(segment
		(start 39.952168 -21.05533)
		(end 38.327076 -19.430238)
		(width 0.1143)
		(layer "F.Cu")
		(net "XDP_CPU_PRDY#")
	)
	(segment
		(start 44.2722 -21.463)
		(end 43.815 -21.463)
		(width 0.1143)
		(layer "F.Cu")
		(net "XDP_CPU_PRDY#")
	)
	(segment
		(start 43.815 -21.463)
		(end 43.40733 -21.05533)
		(width 0.1143)
		(layer "F.Cu")
		(net "XDP_CPU_PRDY#")
	)
	(via
		(at 36.068 -15.367)
		(size 0.7112)
		(drill 0.3556)
		(layers "F.Cu" "B.Cu")
		(net "XDP_CPU_PRDY#")
	)
	(via
		(at 84.028534 -45.060108)
		(size 0.4318)
		(drill 0.2032)
		(layers "F.Cu" "B.Cu")
		(net "XDP_CPU_PRDY#")
	)
	(via
		(at 38.327076 -19.430238)
		(size 0.508)
		(drill 0.254)
		(layers "F.Cu" "B.Cu")
		(net "XDP_CPU_PRDY#")
	)
	(segment
		(start 38.327076 -17.060418)
		(end 37.027358 -15.7607)
		(width 0.1143)
		(layer "B.Cu")
		(net "XDP_CPU_PRDY#")
	)
	(segment
		(start 38.327076 -19.430238)
		(end 38.327076 -17.060418)
		(width 0.1143)
		(layer "B.Cu")
		(net "XDP_CPU_PRDY#")
	)
	(segment
		(start 37.027358 -15.7607)
		(end 36.4617 -15.7607)
		(width 0.1143)
		(layer "B.Cu")
		(net "XDP_CPU_PRDY#")
	)
	(segment
		(start 36.4617 -15.7607)
		(end 36.068 -15.367)
		(width 0.1143)
		(layer "B.Cu")
		(net "XDP_CPU_PRDY#")
	)
	(segment
		(start 57.725056 -35.93465)
		(end 57.542176 -35.75177)
		(width 0.0889)
		(layer "In7.Cu")
		(net "XDP_CPU_PRDY#")
	)
	(segment
		(start 57.542176 -35.75177)
		(end 57.53989 -35.754056)
		(width 0.0889)
		(layer "In7.Cu")
		(net "XDP_CPU_PRDY#")
	)
	(segment
		(start 83.08594 -45.381164)
		(end 82.888328 -45.183552)
		(width 0.0889)
		(layer "In7.Cu")
		(net "XDP_CPU_PRDY#")
	)
	(segment
		(start 41.76522 -26.941018)
		(end 41.76522 -22.868382)
		(width 0.0889)
		(layer "In7.Cu")
		(net "XDP_CPU_PRDY#")
	)
	(segment
		(start 46.948344 -31.496)
		(end 46.320202 -31.496)
		(width 0.0889)
		(layer "In7.Cu")
		(net "XDP_CPU_PRDY#")
	)
	(segment
		(start 73.6092 -38.277292)
		(end 72.244458 -36.91255)
		(width 0.0889)
		(layer "In7.Cu")
		(net "XDP_CPU_PRDY#")
	)
	(segment
		(start 72.244458 -36.91255)
		(end 62.147196 -36.91255)
		(width 0.0889)
		(layer "In7.Cu")
		(net "XDP_CPU_PRDY#")
	)
	(segment
		(start 46.320202 -31.496)
		(end 41.76522 -26.941018)
		(width 0.0889)
		(layer "In7.Cu")
		(net "XDP_CPU_PRDY#")
	)
	(segment
		(start 59.92114 -34.686494)
		(end 58.64225 -34.686494)
		(width 0.0889)
		(layer "In7.Cu")
		(net "XDP_CPU_PRDY#")
	)
	(segment
		(start 84.028534 -45.060108)
		(end 83.709002 -45.060108)
		(width 0.0889)
		(layer "In7.Cu")
		(net "XDP_CPU_PRDY#")
	)
	(segment
		(start 75.03795 -40.856662)
		(end 75.03795 -40.65397)
		(width 0.0889)
		(layer "In7.Cu")
		(net "XDP_CPU_PRDY#")
	)
	(segment
		(start 41.76522 -22.868382)
		(end 38.327076 -19.430238)
		(width 0.0889)
		(layer "In7.Cu")
		(net "XDP_CPU_PRDY#")
	)
	(segment
		(start 77.0382 -42.545)
		(end 75.58405 -41.09085)
		(width 0.0889)
		(layer "In7.Cu")
		(net "XDP_CPU_PRDY#")
	)
	(segment
		(start 58.64225 -34.686494)
		(end 58.36285 -34.965894)
		(width 0.0889)
		(layer "In7.Cu")
		(net "XDP_CPU_PRDY#")
	)
	(segment
		(start 75.58405 -41.09085)
		(end 75.272138 -41.09085)
		(width 0.0889)
		(layer "In7.Cu")
		(net "XDP_CPU_PRDY#")
	)
	(segment
		(start 57.53989 -35.754056)
		(end 51.2064 -35.754056)
		(width 0.0889)
		(layer "In7.Cu")
		(net "XDP_CPU_PRDY#")
	)
	(segment
		(start 83.387946 -45.381164)
		(end 83.08594 -45.381164)
		(width 0.0889)
		(layer "In7.Cu")
		(net "XDP_CPU_PRDY#")
	)
	(segment
		(start 75.272138 -41.09085)
		(end 75.03795 -40.856662)
		(width 0.0889)
		(layer "In7.Cu")
		(net "XDP_CPU_PRDY#")
	)
	(segment
		(start 58.36285 -35.670744)
		(end 58.098944 -35.93465)
		(width 0.0889)
		(layer "In7.Cu")
		(net "XDP_CPU_PRDY#")
	)
	(segment
		(start 78.52029 -42.545)
		(end 77.0382 -42.545)
		(width 0.0889)
		(layer "In7.Cu")
		(net "XDP_CPU_PRDY#")
	)
	(segment
		(start 82.888328 -45.183552)
		(end 81.158842 -45.183552)
		(width 0.0889)
		(layer "In7.Cu")
		(net "XDP_CPU_PRDY#")
	)
	(segment
		(start 81.158842 -45.183552)
		(end 78.52029 -42.545)
		(width 0.0889)
		(layer "In7.Cu")
		(net "XDP_CPU_PRDY#")
	)
	(segment
		(start 83.709002 -45.060108)
		(end 83.387946 -45.381164)
		(width 0.0889)
		(layer "In7.Cu")
		(net "XDP_CPU_PRDY#")
	)
	(segment
		(start 62.147196 -36.91255)
		(end 59.92114 -34.686494)
		(width 0.0889)
		(layer "In7.Cu")
		(net "XDP_CPU_PRDY#")
	)
	(segment
		(start 75.03795 -40.65397)
		(end 73.6092 -39.22522)
		(width 0.0889)
		(layer "In7.Cu")
		(net "XDP_CPU_PRDY#")
	)
	(segment
		(start 58.098944 -35.93465)
		(end 57.725056 -35.93465)
		(width 0.0889)
		(layer "In7.Cu")
		(net "XDP_CPU_PRDY#")
	)
	(segment
		(start 58.36285 -34.965894)
		(end 58.36285 -35.670744)
		(width 0.0889)
		(layer "In7.Cu")
		(net "XDP_CPU_PRDY#")
	)
	(segment
		(start 51.2064 -35.754056)
		(end 46.948344 -31.496)
		(width 0.0889)
		(layer "In7.Cu")
		(net "XDP_CPU_PRDY#")
	)
	(segment
		(start 73.6092 -39.22522)
		(end 73.6092 -38.277292)
		(width 0.0889)
		(layer "In7.Cu")
		(net "XDP_CPU_PRDY#")
	)
	(segment
		(start 39.190676 -19.432524)
		(end 40.313102 -20.55495)
		(width 0.1143)
		(layer "F.Cu")
		(net "XDP_CPU_PREQ#")
	)
	(segment
		(start 40.313102 -20.55495)
		(end 42.10177 -20.55495)
		(width 0.1143)
		(layer "F.Cu")
		(net "XDP_CPU_PREQ#")
	)
	(segment
		(start 44.12615 -20.55495)
		(end 42.10177 -20.55495)
		(width 0.1143)
		(layer "F.Cu")
		(net "XDP_CPU_PREQ#")
	)
	(segment
		(start 85.933788 -45.741844)
		(end 85.817202 -45.85843)
		(width 0.1143)
		(layer "F.Cu")
		(net "XDP_CPU_PREQ#")
	)
	(segment
		(start 85.933788 -45.390054)
		(end 85.933788 -45.741844)
		(width 0.1143)
		(layer "F.Cu")
		(net "XDP_CPU_PREQ#")
	)
	(segment
		(start 44.2722 -20.701)
		(end 44.12615 -20.55495)
		(width 0.1143)
		(layer "F.Cu")
		(net "XDP_CPU_PREQ#")
	)
	(via
		(at 85.817202 -45.85843)
		(size 0.4318)
		(drill 0.2032)
		(layers "F.Cu" "B.Cu")
		(net "XDP_CPU_PREQ#")
	)
	(via
		(at 38.9382 -15.5194)
		(size 0.7112)
		(drill 0.3556)
		(layers "F.Cu" "B.Cu")
		(net "XDP_CPU_PREQ#")
	)
	(via
		(at 39.190676 -19.432524)
		(size 0.508)
		(drill 0.254)
		(layers "F.Cu" "B.Cu")
		(net "XDP_CPU_PREQ#")
	)
	(segment
		(start 39.30015 -17.438878)
		(end 39.190676 -17.548352)
		(width 0.1143)
		(layer "B.Cu")
		(net "XDP_CPU_PREQ#")
	)
	(segment
		(start 39.190676 -17.548352)
		(end 39.190676 -19.432524)
		(width 0.1143)
		(layer "B.Cu")
		(net "XDP_CPU_PREQ#")
	)
	(segment
		(start 39.30015 -16.84655)
		(end 39.30015 -17.438878)
		(width 0.1143)
		(layer "B.Cu")
		(net "XDP_CPU_PREQ#")
	)
	(segment
		(start 38.9382 -15.5194)
		(end 38.9382 -16.4846)
		(width 0.1143)
		(layer "B.Cu")
		(net "XDP_CPU_PREQ#")
	)
	(segment
		(start 38.9382 -16.4846)
		(end 39.30015 -16.84655)
		(width 0.1143)
		(layer "B.Cu")
		(net "XDP_CPU_PREQ#")
	)
	(segment
		(start 62.376304 -36.09975)
		(end 67.395344 -36.09975)
		(width 0.0889)
		(layer "In7.Cu")
		(net "XDP_CPU_PREQ#")
	)
	(segment
		(start 58.336942 -33.949894)
		(end 60.226448 -33.949894)
		(width 0.0889)
		(layer "In7.Cu")
		(net "XDP_CPU_PREQ#")
	)
	(segment
		(start 72.549766 -36.17595)
		(end 74.3458 -37.971984)
		(width 0.0889)
		(layer "In7.Cu")
		(net "XDP_CPU_PREQ#")
	)
	(segment
		(start 77.653642 -42.071036)
		(end 78.585314 -42.071036)
		(width 0.0889)
		(layer "In7.Cu")
		(net "XDP_CPU_PREQ#")
	)
	(segment
		(start 48.0314 -30.7594)
		(end 50.8508 -33.5788)
		(width 0.0889)
		(layer "In7.Cu")
		(net "XDP_CPU_PREQ#")
	)
	(segment
		(start 60.226448 -33.949894)
		(end 62.376304 -36.09975)
		(width 0.0889)
		(layer "In7.Cu")
		(net "XDP_CPU_PREQ#")
	)
	(segment
		(start 46.62551 -30.7594)
		(end 48.0314 -30.7594)
		(width 0.0889)
		(layer "In7.Cu")
		(net "XDP_CPU_PREQ#")
	)
	(segment
		(start 84.760308 -45.4914)
		(end 85.450172 -45.4914)
		(width 0.0889)
		(layer "In7.Cu")
		(net "XDP_CPU_PREQ#")
	)
	(segment
		(start 57.869836 -34.417)
		(end 58.336942 -33.949894)
		(width 0.0889)
		(layer "In7.Cu")
		(net "XDP_CPU_PREQ#")
	)
	(segment
		(start 43.49115 -25.15235)
		(end 44.2214 -25.8826)
		(width 0.0889)
		(layer "In7.Cu")
		(net "XDP_CPU_PREQ#")
	)
	(segment
		(start 75.526138 -40.10025)
		(end 75.682856 -40.10025)
		(width 0.0889)
		(layer "In7.Cu")
		(net "XDP_CPU_PREQ#")
	)
	(segment
		(start 68.671694 -35.56)
		(end 71.611744 -35.56)
		(width 0.0889)
		(layer "In7.Cu")
		(net "XDP_CPU_PREQ#")
	)
	(segment
		(start 68.665344 -35.56635)
		(end 68.671694 -35.56)
		(width 0.0889)
		(layer "In7.Cu")
		(net "XDP_CPU_PREQ#")
	)
	(segment
		(start 44.2214 -25.8826)
		(end 44.2214 -28.049982)
		(width 0.0889)
		(layer "In7.Cu")
		(net "XDP_CPU_PREQ#")
	)
	(segment
		(start 82.556858 -44.26712)
		(end 82.891884 -44.602146)
		(width 0.0889)
		(layer "In7.Cu")
		(net "XDP_CPU_PREQ#")
	)
	(segment
		(start 84.390484 -44.909994)
		(end 84.390484 -45.121576)
		(width 0.0889)
		(layer "In7.Cu")
		(net "XDP_CPU_PREQ#")
	)
	(segment
		(start 82.891884 -44.602146)
		(end 84.082636 -44.602146)
		(width 0.0889)
		(layer "In7.Cu")
		(net "XDP_CPU_PREQ#")
	)
	(segment
		(start 84.082636 -44.602146)
		(end 84.390484 -44.909994)
		(width 0.0889)
		(layer "In7.Cu")
		(net "XDP_CPU_PREQ#")
	)
	(segment
		(start 57.37352 -34.417)
		(end 57.869836 -34.417)
		(width 0.0889)
		(layer "In7.Cu")
		(net "XDP_CPU_PREQ#")
	)
	(segment
		(start 71.611744 -35.56)
		(end 72.227694 -36.17595)
		(width 0.0889)
		(layer "In7.Cu")
		(net "XDP_CPU_PREQ#")
	)
	(segment
		(start 40.54475 -19.432524)
		(end 44.189396 -23.07717)
		(width 0.0889)
		(layer "In7.Cu")
		(net "XDP_CPU_PREQ#")
	)
	(segment
		(start 44.221146 -28.050236)
		(end 44.221146 -28.355036)
		(width 0.0889)
		(layer "In7.Cu")
		(net "XDP_CPU_PREQ#")
	)
	(segment
		(start 84.390484 -45.121576)
		(end 84.760308 -45.4914)
		(width 0.0889)
		(layer "In7.Cu")
		(net "XDP_CPU_PREQ#")
	)
	(segment
		(start 74.3458 -37.971984)
		(end 74.3458 -38.919912)
		(width 0.0889)
		(layer "In7.Cu")
		(net "XDP_CPU_PREQ#")
	)
	(segment
		(start 78.585314 -42.071036)
		(end 80.781398 -44.26712)
		(width 0.0889)
		(layer "In7.Cu")
		(net "XDP_CPU_PREQ#")
	)
	(segment
		(start 75.682856 -40.10025)
		(end 77.653642 -42.071036)
		(width 0.0889)
		(layer "In7.Cu")
		(net "XDP_CPU_PREQ#")
	)
	(segment
		(start 43.49115 -24.451056)
		(end 43.49115 -25.15235)
		(width 0.0889)
		(layer "In7.Cu")
		(net "XDP_CPU_PREQ#")
	)
	(segment
		(start 67.395344 -36.09975)
		(end 67.928744 -35.56635)
		(width 0.0889)
		(layer "In7.Cu")
		(net "XDP_CPU_PREQ#")
	)
	(segment
		(start 44.221146 -28.355036)
		(end 46.62551 -30.7594)
		(width 0.0889)
		(layer "In7.Cu")
		(net "XDP_CPU_PREQ#")
	)
	(segment
		(start 39.190676 -19.432524)
		(end 40.54475 -19.432524)
		(width 0.0889)
		(layer "In7.Cu")
		(net "XDP_CPU_PREQ#")
	)
	(segment
		(start 50.8508 -33.5788)
		(end 56.53532 -33.5788)
		(width 0.0889)
		(layer "In7.Cu")
		(net "XDP_CPU_PREQ#")
	)
	(segment
		(start 56.53532 -33.5788)
		(end 57.37352 -34.417)
		(width 0.0889)
		(layer "In7.Cu")
		(net "XDP_CPU_PREQ#")
	)
	(segment
		(start 67.928744 -35.56635)
		(end 68.665344 -35.56635)
		(width 0.0889)
		(layer "In7.Cu")
		(net "XDP_CPU_PREQ#")
	)
	(segment
		(start 44.189396 -23.75281)
		(end 43.49115 -24.451056)
		(width 0.0889)
		(layer "In7.Cu")
		(net "XDP_CPU_PREQ#")
	)
	(segment
		(start 44.189396 -23.07717)
		(end 44.189396 -23.75281)
		(width 0.0889)
		(layer "In7.Cu")
		(net "XDP_CPU_PREQ#")
	)
	(segment
		(start 85.450172 -45.4914)
		(end 85.817202 -45.85843)
		(width 0.0889)
		(layer "In7.Cu")
		(net "XDP_CPU_PREQ#")
	)
	(segment
		(start 44.2214 -28.049982)
		(end 44.221146 -28.050236)
		(width 0.0889)
		(layer "In7.Cu")
		(net "XDP_CPU_PREQ#")
	)
	(segment
		(start 74.3458 -38.919912)
		(end 75.526138 -40.10025)
		(width 0.0889)
		(layer "In7.Cu")
		(net "XDP_CPU_PREQ#")
	)
	(segment
		(start 80.781398 -44.26712)
		(end 82.556858 -44.26712)
		(width 0.0889)
		(layer "In7.Cu")
		(net "XDP_CPU_PREQ#")
	)
	(segment
		(start 72.227694 -36.17595)
		(end 72.549766 -36.17595)
		(width 0.0889)
		(layer "In7.Cu")
		(net "XDP_CPU_PREQ#")
	)
	(segment
		(start 118.3894 -6.0706)
		(end 116.9162 -6.0706)
		(width 0.1143)
		(layer "F.Cu")
		(net "SLOT_ID3")
	)
	(segment
		(start 119.479822 -6.0706)
		(end 127.3048 -13.895578)
		(width 0.1143)
		(layer "F.Cu")
		(net "SLOT_ID3")
	)
	(segment
		(start 130.51155 -20.81911)
		(end 129.9718 -21.35886)
		(width 0.1143)
		(layer "F.Cu")
		(net "SLOT_ID3")
	)
	(segment
		(start 111.916972 -3.103372)
		(end 110.57001 -3.103372)
		(width 0.1143)
		(layer "F.Cu")
		(net "SLOT_ID3")
	)
	(segment
		(start 137.4648 -43.3832)
		(end 136.49833 -44.34967)
		(width 0.1143)
		(layer "F.Cu")
		(net "SLOT_ID3")
	)
	(segment
		(start 129.9718 -22.888956)
		(end 131.657344 -24.5745)
		(width 0.1143)
		(layer "F.Cu")
		(net "SLOT_ID3")
	)
	(segment
		(start 131.657344 -24.5745)
		(end 133.23316 -24.5745)
		(width 0.1143)
		(layer "F.Cu")
		(net "SLOT_ID3")
	)
	(segment
		(start 136.49833 -44.34967)
		(end 136.49833 -45.1612)
		(width 0.1143)
		(layer "F.Cu")
		(net "SLOT_ID3")
	)
	(segment
		(start 91.186 -10.091166)
		(end 90.670634 -9.5758)
		(width 0.1143)
		(layer "F.Cu")
		(net "SLOT_ID3")
	)
	(segment
		(start 130.51155 -15.037054)
		(end 130.51155 -20.81911)
		(width 0.1143)
		(layer "F.Cu")
		(net "SLOT_ID3")
	)
	(segment
		(start 116.9162 -6.0706)
		(end 115.0874 -4.2418)
		(width 0.1143)
		(layer "F.Cu")
		(net "SLOT_ID3")
	)
	(segment
		(start 110.57001 -3.103372)
		(end 109.7788 -2.312162)
		(width 0.1143)
		(layer "F.Cu")
		(net "SLOT_ID3")
	)
	(segment
		(start 129.9718 -21.35886)
		(end 129.9718 -22.888956)
		(width 0.1143)
		(layer "F.Cu")
		(net "SLOT_ID3")
	)
	(segment
		(start 89.350088 -9.15924)
		(end 89.766648 -9.5758)
		(width 0.1143)
		(layer "F.Cu")
		(net "SLOT_ID3")
	)
	(segment
		(start 89.766648 -9.5758)
		(end 90.670634 -9.5758)
		(width 0.1143)
		(layer "F.Cu")
		(net "SLOT_ID3")
	)
	(segment
		(start 118.3894 -6.0706)
		(end 119.479822 -6.0706)
		(width 0.1143)
		(layer "F.Cu")
		(net "SLOT_ID3")
	)
	(segment
		(start 113.0554 -4.2418)
		(end 111.916972 -3.103372)
		(width 0.1143)
		(layer "F.Cu")
		(net "SLOT_ID3")
	)
	(segment
		(start 115.0874 -4.2418)
		(end 113.0554 -4.2418)
		(width 0.1143)
		(layer "F.Cu")
		(net "SLOT_ID3")
	)
	(segment
		(start 137.4648 -28.80614)
		(end 137.4648 -43.3832)
		(width 0.1143)
		(layer "F.Cu")
		(net "SLOT_ID3")
	)
	(segment
		(start 91.186 -12.7762)
		(end 91.186 -10.091166)
		(width 0.1143)
		(layer "F.Cu")
		(net "SLOT_ID3")
	)
	(segment
		(start 127.3048 -13.895578)
		(end 129.370074 -13.895578)
		(width 0.1143)
		(layer "F.Cu")
		(net "SLOT_ID3")
	)
	(segment
		(start 133.23316 -24.5745)
		(end 137.4648 -28.80614)
		(width 0.1143)
		(layer "F.Cu")
		(net "SLOT_ID3")
	)
	(segment
		(start 89.350088 -6.195568)
		(end 89.350088 -9.15924)
		(width 0.1143)
		(layer "F.Cu")
		(net "SLOT_ID3")
	)
	(segment
		(start 129.370074 -13.895578)
		(end 130.51155 -15.037054)
		(width 0.1143)
		(layer "F.Cu")
		(net "SLOT_ID3")
	)
	(via
		(at 90.670634 -9.5758)
		(size 0.508)
		(drill 0.254)
		(layers "F.Cu" "B.Cu")
		(net "SLOT_ID3")
	)
	(via
		(at 118.3894 -6.0706)
		(size 0.7112)
		(drill 0.3556)
		(layers "F.Cu" "B.Cu")
		(net "SLOT_ID3")
	)
	(via
		(at 109.7788 -2.312162)
		(size 0.508)
		(drill 0.254)
		(layers "F.Cu" "B.Cu")
		(net "SLOT_ID3")
	)
	(segment
		(start 91.656154 -10.56132)
		(end 90.670634 -9.5758)
		(width 0.0889)
		(layer "In7.Cu")
		(net "SLOT_ID3")
	)
	(segment
		(start 108.036868 -2.9972)
		(end 106.4641 -4.569968)
		(width 0.0889)
		(layer "In7.Cu")
		(net "SLOT_ID3")
	)
	(segment
		(start 106.4641 -4.569968)
		(end 106.4641 -11.707368)
		(width 0.0889)
		(layer "In7.Cu")
		(net "SLOT_ID3")
	)
	(segment
		(start 106.4641 -11.707368)
		(end 105.001568 -13.1699)
		(width 0.0889)
		(layer "In7.Cu")
		(net "SLOT_ID3")
	)
	(segment
		(start 109.093762 -2.9972)
		(end 108.036868 -2.9972)
		(width 0.0889)
		(layer "In7.Cu")
		(net "SLOT_ID3")
	)
	(segment
		(start 91.656154 -12.142216)
		(end 91.656154 -10.56132)
		(width 0.0889)
		(layer "In7.Cu")
		(net "SLOT_ID3")
	)
	(segment
		(start 92.683838 -13.1699)
		(end 91.656154 -12.142216)
		(width 0.0889)
		(layer "In7.Cu")
		(net "SLOT_ID3")
	)
	(segment
		(start 109.7788 -2.312162)
		(end 109.093762 -2.9972)
		(width 0.0889)
		(layer "In7.Cu")
		(net "SLOT_ID3")
	)
	(segment
		(start 105.001568 -13.1699)
		(end 92.683838 -13.1699)
		(width 0.0889)
		(layer "In7.Cu")
		(net "SLOT_ID3")
	)
	(segment
		(start 86.33587 -41.777412)
		(end 86.295738 -41.777412)
		(width 0.1143)
		(layer "F.Cu")
		(net "IRQ_CPU_IERR#")
	)
	(segment
		(start 86.695788 -41.417494)
		(end 86.33587 -41.777412)
		(width 0.1143)
		(layer "F.Cu")
		(net "IRQ_CPU_IERR#")
	)
	(via
		(at 107.442 -11.1506)
		(size 0.508)
		(drill 0.254)
		(layers "F.Cu" "B.Cu")
		(net "IRQ_CPU_IERR#")
	)
	(via
		(at 105.35666 -13.23594)
		(size 0.7112)
		(drill 0.3556)
		(layers "F.Cu" "B.Cu")
		(net "IRQ_CPU_IERR#")
	)
	(via
		(at 86.295738 -41.777412)
		(size 0.4318)
		(drill 0.2032)
		(layers "F.Cu" "B.Cu")
		(net "IRQ_CPU_IERR#")
	)
	(segment
		(start 103.3272 -15.0368)
		(end 102.616 -15.748)
		(width 0.1143)
		(layer "B.Cu")
		(net "IRQ_CPU_IERR#")
	)
	(segment
		(start 103.9114 -13.5128)
		(end 103.3272 -14.097)
		(width 0.1143)
		(layer "B.Cu")
		(net "IRQ_CPU_IERR#")
	)
	(segment
		(start 102.616 -15.748)
		(end 102.31628 -15.748)
		(width 0.1143)
		(layer "B.Cu")
		(net "IRQ_CPU_IERR#")
	)
	(segment
		(start 103.3272 -14.097)
		(end 103.3272 -15.0368)
		(width 0.1143)
		(layer "B.Cu")
		(net "IRQ_CPU_IERR#")
	)
	(segment
		(start 105.35666 -13.23594)
		(end 105.0798 -13.5128)
		(width 0.1143)
		(layer "B.Cu")
		(net "IRQ_CPU_IERR#")
	)
	(segment
		(start 107.442 -11.1506)
		(end 105.35666 -13.23594)
		(width 0.1143)
		(layer "B.Cu")
		(net "IRQ_CPU_IERR#")
	)
	(segment
		(start 105.0798 -13.5128)
		(end 103.9114 -13.5128)
		(width 0.1143)
		(layer "B.Cu")
		(net "IRQ_CPU_IERR#")
	)
	(segment
		(start 87.870792 -22.973792)
		(end 87.870792 -25.226772)
		(width 0.0889)
		(layer "In2.Cu")
		(net "IRQ_CPU_IERR#")
	)
	(segment
		(start 105.269538 -13.764006)
		(end 93.189044 -13.764006)
		(width 0.0889)
		(layer "In2.Cu")
		(net "IRQ_CPU_IERR#")
	)
	(segment
		(start 88.719914 -41.43375)
		(end 86.639654 -41.43375)
		(width 0.0889)
		(layer "In2.Cu")
		(net "IRQ_CPU_IERR#")
	)
	(segment
		(start 88.93175 -41.221914)
		(end 88.719914 -41.43375)
		(width 0.0889)
		(layer "In2.Cu")
		(net "IRQ_CPU_IERR#")
	)
	(segment
		(start 90.63355 -16.3195)
		(end 88.128348 -16.3195)
		(width 0.0889)
		(layer "In2.Cu")
		(net "IRQ_CPU_IERR#")
	)
	(segment
		(start 87.83447 -26.182828)
		(end 89.63025 -27.978608)
		(width 0.0889)
		(layer "In2.Cu")
		(net "IRQ_CPU_IERR#")
	)
	(segment
		(start 107.442 -11.1506)
		(end 107.442 -11.591544)
		(width 0.0889)
		(layer "In2.Cu")
		(net "IRQ_CPU_IERR#")
	)
	(segment
		(start 86.639654 -41.43375)
		(end 86.295992 -41.777412)
		(width 0.0889)
		(layer "In2.Cu")
		(net "IRQ_CPU_IERR#")
	)
	(segment
		(start 87.83447 -25.263094)
		(end 87.83447 -26.182828)
		(width 0.0889)
		(layer "In2.Cu")
		(net "IRQ_CPU_IERR#")
	)
	(segment
		(start 89.63025 -33.669986)
		(end 89.85885 -33.898586)
		(width 0.0889)
		(layer "In2.Cu")
		(net "IRQ_CPU_IERR#")
	)
	(segment
		(start 89.44356 -40.47744)
		(end 88.93175 -40.98925)
		(width 0.0889)
		(layer "In2.Cu")
		(net "IRQ_CPU_IERR#")
	)
	(segment
		(start 107.442 -11.591544)
		(end 105.269538 -13.764006)
		(width 0.0889)
		(layer "In2.Cu")
		(net "IRQ_CPU_IERR#")
	)
	(segment
		(start 89.85885 -33.898586)
		(end 89.85885 -35.28695)
		(width 0.0889)
		(layer "In2.Cu")
		(net "IRQ_CPU_IERR#")
	)
	(segment
		(start 89.85885 -35.28695)
		(end 89.44356 -35.70224)
		(width 0.0889)
		(layer "In2.Cu")
		(net "IRQ_CPU_IERR#")
	)
	(segment
		(start 86.401656 -18.046192)
		(end 86.401656 -21.504656)
		(width 0.0889)
		(layer "In2.Cu")
		(net "IRQ_CPU_IERR#")
	)
	(segment
		(start 87.870792 -25.226772)
		(end 87.83447 -25.263094)
		(width 0.0889)
		(layer "In2.Cu")
		(net "IRQ_CPU_IERR#")
	)
	(segment
		(start 86.295992 -41.777412)
		(end 86.295738 -41.777412)
		(width 0.0889)
		(layer "In2.Cu")
		(net "IRQ_CPU_IERR#")
	)
	(segment
		(start 88.93175 -40.98925)
		(end 88.93175 -41.221914)
		(width 0.0889)
		(layer "In2.Cu")
		(net "IRQ_CPU_IERR#")
	)
	(segment
		(start 89.63025 -27.978608)
		(end 89.63025 -33.669986)
		(width 0.0889)
		(layer "In2.Cu")
		(net "IRQ_CPU_IERR#")
	)
	(segment
		(start 89.44356 -35.70224)
		(end 89.44356 -40.47744)
		(width 0.0889)
		(layer "In2.Cu")
		(net "IRQ_CPU_IERR#")
	)
	(segment
		(start 93.189044 -13.764006)
		(end 90.63355 -16.3195)
		(width 0.0889)
		(layer "In2.Cu")
		(net "IRQ_CPU_IERR#")
	)
	(segment
		(start 86.401656 -21.504656)
		(end 87.870792 -22.973792)
		(width 0.0889)
		(layer "In2.Cu")
		(net "IRQ_CPU_IERR#")
	)
	(segment
		(start 88.128348 -16.3195)
		(end 86.401656 -18.046192)
		(width 0.0889)
		(layer "In2.Cu")
		(net "IRQ_CPU_IERR#")
	)
	(segment
		(start 79.344266 -34.592514)
		(end 78.613 -33.861248)
		(width 0.1143)
		(layer "F.Cu")
		(net "SPI_CPU_WP#")
	)
	(segment
		(start 56.4388 -35.306)
		(end 56.5404 -35.306)
		(width 0.1143)
		(layer "F.Cu")
		(net "SPI_CPU_WP#")
	)
	(segment
		(start 61.657992 -36.995608)
		(end 61.797692 -36.855908)
		(width 0.1143)
		(layer "F.Cu")
		(net "SPI_CPU_WP#")
	)
	(segment
		(start 57.023 -35.7886)
		(end 57.314084 -35.7886)
		(width 0.1143)
		(layer "F.Cu")
		(net "SPI_CPU_WP#")
	)
	(segment
		(start 78.613 -33.861248)
		(end 78.613 -33.76295)
		(width 0.1143)
		(layer "F.Cu")
		(net "SPI_CPU_WP#")
	)
	(segment
		(start 61.797692 -36.855908)
		(end 63.9191 -36.855908)
		(width 0.1143)
		(layer "F.Cu")
		(net "SPI_CPU_WP#")
	)
	(segment
		(start 63.9191 -36.855908)
		(end 64.0588 -36.995608)
		(width 0.1143)
		(layer "F.Cu")
		(net "SPI_CPU_WP#")
	)
	(segment
		(start 58.521092 -36.995608)
		(end 61.657992 -36.995608)
		(width 0.1143)
		(layer "F.Cu")
		(net "SPI_CPU_WP#")
	)
	(segment
		(start 57.314084 -35.7886)
		(end 58.521092 -36.995608)
		(width 0.1143)
		(layer "F.Cu")
		(net "SPI_CPU_WP#")
	)
	(segment
		(start 67.7164 -38.0492)
		(end 67.865498 -38.0492)
		(width 0.1143)
		(layer "F.Cu")
		(net "SPI_CPU_WP#")
	)
	(segment
		(start 64.0588 -36.995608)
		(end 65.786 -36.995608)
		(width 0.1143)
		(layer "F.Cu")
		(net "SPI_CPU_WP#")
	)
	(segment
		(start 66.662808 -36.995608)
		(end 67.7164 -38.0492)
		(width 0.1143)
		(layer "F.Cu")
		(net "SPI_CPU_WP#")
	)
	(segment
		(start 65.786 -36.995608)
		(end 66.662808 -36.995608)
		(width 0.1143)
		(layer "F.Cu")
		(net "SPI_CPU_WP#")
	)
	(segment
		(start 56.5404 -35.306)
		(end 57.023 -35.7886)
		(width 0.1143)
		(layer "F.Cu")
		(net "SPI_CPU_WP#")
	)
	(segment
		(start 79.601568 -34.592514)
		(end 79.344266 -34.592514)
		(width 0.1143)
		(layer "F.Cu")
		(net "SPI_CPU_WP#")
	)
	(via
		(at 65.786 -36.995608)
		(size 0.7112)
		(drill 0.3556)
		(layers "F.Cu" "B.Cu")
		(net "SPI_CPU_WP#")
	)
	(via
		(at 67.865498 -38.0492)
		(size 0.508)
		(drill 0.254)
		(layers "F.Cu" "B.Cu")
		(net "SPI_CPU_WP#")
	)
	(via
		(at 78.613 -33.76295)
		(size 0.4318)
		(drill 0.2032)
		(layers "F.Cu" "B.Cu")
		(net "SPI_CPU_WP#")
	)
	(segment
		(start 69.367654 -36.568634)
		(end 67.887088 -38.0492)
		(width 0.0889)
		(layer "In2.Cu")
		(net "SPI_CPU_WP#")
	)
	(segment
		(start 67.887088 -38.0492)
		(end 67.865498 -38.0492)
		(width 0.0889)
		(layer "In2.Cu")
		(net "SPI_CPU_WP#")
	)
	(segment
		(start 78.2574 -34.1122)
		(end 77.6224 -34.1122)
		(width 0.0889)
		(layer "In2.Cu")
		(net "SPI_CPU_WP#")
	)
	(segment
		(start 77.6224 -34.1122)
		(end 75.165966 -36.568634)
		(width 0.0889)
		(layer "In2.Cu")
		(net "SPI_CPU_WP#")
	)
	(segment
		(start 78.613 -33.76295)
		(end 78.60665 -33.76295)
		(width 0.0889)
		(layer "In2.Cu")
		(net "SPI_CPU_WP#")
	)
	(segment
		(start 75.165966 -36.568634)
		(end 69.367654 -36.568634)
		(width 0.0889)
		(layer "In2.Cu")
		(net "SPI_CPU_WP#")
	)
	(segment
		(start 78.60665 -33.76295)
		(end 78.2574 -34.1122)
		(width 0.0889)
		(layer "In2.Cu")
		(net "SPI_CPU_WP#")
	)
	(segment
		(start 76.068936 -37.29482)
		(end 76.31049 -37.536374)
		(width 0.1143)
		(layer "F.Cu")
		(net "PMU_WAKE#")
	)
	(segment
		(start 75.617324 -36.449)
		(end 76.068936 -36.900612)
		(width 0.1143)
		(layer "F.Cu")
		(net "PMU_WAKE#")
	)
	(segment
		(start 77.3176 -37.211)
		(end 79.154274 -37.211)
		(width 0.1143)
		(layer "F.Cu")
		(net "PMU_WAKE#")
	)
	(segment
		(start 74.2188 -36.449)
		(end 75.617324 -36.449)
		(width 0.1143)
		(layer "F.Cu")
		(net "PMU_WAKE#")
	)
	(segment
		(start 76.992226 -37.536374)
		(end 77.3176 -37.211)
		(width 0.1143)
		(layer "F.Cu")
		(net "PMU_WAKE#")
	)
	(segment
		(start 76.31049 -37.536374)
		(end 76.992226 -37.536374)
		(width 0.1143)
		(layer "F.Cu")
		(net "PMU_WAKE#")
	)
	(segment
		(start 74.0918 -36.576)
		(end 74.2188 -36.449)
		(width 0.1143)
		(layer "F.Cu")
		(net "PMU_WAKE#")
	)
	(segment
		(start 76.068936 -36.900612)
		(end 76.068936 -37.29482)
		(width 0.1143)
		(layer "F.Cu")
		(net "PMU_WAKE#")
	)
	(segment
		(start 79.154274 -37.211)
		(end 79.601568 -37.658294)
		(width 0.1143)
		(layer "F.Cu")
		(net "PMU_WAKE#")
	)
	(via
		(at 77.3176 -37.211)
		(size 0.7112)
		(drill 0.3556)
		(layers "F.Cu" "B.Cu")
		(net "PMU_WAKE#")
	)
	(segment
		(start 56.4388 -36.83)
		(end 56.855868 -36.83)
		(width 0.1143)
		(layer "F.Cu")
		(net "SPI_CPU_CS0#")
	)
	(segment
		(start 80.085692 -35.32505)
		(end 80.096868 -35.313874)
		(width 0.1143)
		(layer "F.Cu")
		(net "SPI_CPU_CS0#")
	)
	(segment
		(start 75.55738 -34.036)
		(end 76.327 -34.036)
		(width 0.1143)
		(layer "F.Cu")
		(net "SPI_CPU_CS0#")
	)
	(segment
		(start 76.962 -34.671)
		(end 77.597 -34.671)
		(width 0.1143)
		(layer "F.Cu")
		(net "SPI_CPU_CS0#")
	)
	(segment
		(start 57.023 -38.1508)
		(end 57.16905 -38.29685)
		(width 0.1143)
		(layer "F.Cu")
		(net "SPI_CPU_CS0#")
	)
	(segment
		(start 66.963798 -39.30523)
		(end 67.333368 -39.6748)
		(width 0.1143)
		(layer "F.Cu")
		(net "SPI_CPU_CS0#")
	)
	(segment
		(start 77.597 -34.671)
		(end 78.25105 -35.32505)
		(width 0.1143)
		(layer "F.Cu")
		(net "SPI_CPU_CS0#")
	)
	(segment
		(start 76.327 -34.036)
		(end 76.454 -34.163)
		(width 0.1143)
		(layer "F.Cu")
		(net "SPI_CPU_CS0#")
	)
	(segment
		(start 56.855868 -36.83)
		(end 57.023 -36.997132)
		(width 0.1143)
		(layer "F.Cu")
		(net "SPI_CPU_CS0#")
	)
	(segment
		(start 67.333368 -39.6748)
		(end 67.8434 -39.6748)
		(width 0.1143)
		(layer "F.Cu")
		(net "SPI_CPU_CS0#")
	)
	(segment
		(start 66.345816 -39.30523)
		(end 66.963798 -39.30523)
		(width 0.1143)
		(layer "F.Cu")
		(net "SPI_CPU_CS0#")
	)
	(segment
		(start 74.4728 -32.893)
		(end 74.9554 -32.893)
		(width 0.1143)
		(layer "F.Cu")
		(net "SPI_CPU_CS0#")
	)
	(segment
		(start 78.25105 -35.32505)
		(end 80.085692 -35.32505)
		(width 0.1143)
		(layer "F.Cu")
		(net "SPI_CPU_CS0#")
	)
	(segment
		(start 76.454 -34.163)
		(end 76.962 -34.671)
		(width 0.1143)
		(layer "F.Cu")
		(net "SPI_CPU_CS0#")
	)
	(segment
		(start 75.318874 -33.797494)
		(end 75.55738 -34.036)
		(width 0.1143)
		(layer "F.Cu")
		(net "SPI_CPU_CS0#")
	)
	(segment
		(start 57.16905 -38.29685)
		(end 57.583578 -38.29685)
		(width 0.1143)
		(layer "F.Cu")
		(net "SPI_CPU_CS0#")
	)
	(segment
		(start 75.318874 -33.256474)
		(end 75.318874 -33.797494)
		(width 0.1143)
		(layer "F.Cu")
		(net "SPI_CPU_CS0#")
	)
	(segment
		(start 57.023 -36.997132)
		(end 57.023 -38.1508)
		(width 0.1143)
		(layer "F.Cu")
		(net "SPI_CPU_CS0#")
	)
	(segment
		(start 57.89422 -37.986208)
		(end 65.026794 -37.986208)
		(width 0.1143)
		(layer "F.Cu")
		(net "SPI_CPU_CS0#")
	)
	(segment
		(start 65.026794 -37.986208)
		(end 66.345816 -39.30523)
		(width 0.1143)
		(layer "F.Cu")
		(net "SPI_CPU_CS0#")
	)
	(segment
		(start 57.583578 -38.29685)
		(end 57.89422 -37.986208)
		(width 0.1143)
		(layer "F.Cu")
		(net "SPI_CPU_CS0#")
	)
	(segment
		(start 74.9554 -32.893)
		(end 75.318874 -33.256474)
		(width 0.1143)
		(layer "F.Cu")
		(net "SPI_CPU_CS0#")
	)
	(via
		(at 75.318874 -33.797494)
		(size 0.508)
		(drill 0.254)
		(layers "F.Cu" "B.Cu")
		(net "SPI_CPU_CS0#")
	)
	(via
		(at 67.8434 -39.6748)
		(size 0.508)
		(drill 0.254)
		(layers "F.Cu" "B.Cu")
		(net "SPI_CPU_CS0#")
	)
	(via
		(at 76.454 -34.163)
		(size 0.7112)
		(drill 0.3556)
		(layers "F.Cu" "B.Cu")
		(net "SPI_CPU_CS0#")
	)
	(segment
		(start 73.14311 -35.59175)
		(end 72.85101 -35.59175)
		(width 0.0889)
		(layer "In2.Cu")
		(net "SPI_CPU_CS0#")
	)
	(segment
		(start 73.70191 -36.009834)
		(end 73.61301 -36.098734)
		(width 0.0889)
		(layer "In2.Cu")
		(net "SPI_CPU_CS0#")
	)
	(segment
		(start 73.70191 -35.68065)
		(end 73.70191 -36.009834)
		(width 0.0889)
		(layer "In2.Cu")
		(net "SPI_CPU_CS0#")
	)
	(segment
		(start 72.29221 -35.68065)
		(end 72.20331 -35.59175)
		(width 0.0889)
		(layer "In2.Cu")
		(net "SPI_CPU_CS0#")
	)
	(segment
		(start 70.1548 -35.9918)
		(end 70.0532 -36.0934)
		(width 0.0889)
		(layer "In2.Cu")
		(net "SPI_CPU_CS0#")
	)
	(segment
		(start 72.29221 -36.009834)
		(end 72.29221 -35.68065)
		(width 0.0889)
		(layer "In2.Cu")
		(net "SPI_CPU_CS0#")
	)
	(segment
		(start 74.26071 -36.098734)
		(end 74.17181 -36.009834)
		(width 0.0889)
		(layer "In2.Cu")
		(net "SPI_CPU_CS0#")
	)
	(segment
		(start 67.414648 -37.817552)
		(end 67.414648 -39.246048)
		(width 0.0889)
		(layer "In2.Cu")
		(net "SPI_CPU_CS0#")
	)
	(segment
		(start 72.76211 -35.68065)
		(end 72.76211 -36.009834)
		(width 0.0889)
		(layer "In2.Cu")
		(net "SPI_CPU_CS0#")
	)
	(segment
		(start 73.32091 -36.098734)
		(end 73.23201 -36.009834)
		(width 0.0889)
		(layer "In2.Cu")
		(net "SPI_CPU_CS0#")
	)
	(segment
		(start 67.414648 -39.246048)
		(end 67.8434 -39.6748)
		(width 0.0889)
		(layer "In2.Cu")
		(net "SPI_CPU_CS0#")
	)
	(segment
		(start 74.0156 -34.925)
		(end 74.1172 -35.0266)
		(width 0.0889)
		(layer "In2.Cu")
		(net "SPI_CPU_CS0#")
	)
	(segment
		(start 73.79081 -35.59175)
		(end 73.70191 -35.68065)
		(width 0.0889)
		(layer "In2.Cu")
		(net "SPI_CPU_CS0#")
	)
	(segment
		(start 74.1172 -35.0266)
		(end 75.6158 -35.0266)
		(width 0.0889)
		(layer "In2.Cu")
		(net "SPI_CPU_CS0#")
	)
	(segment
		(start 67.54114 -37.107368)
		(end 67.770248 -37.336476)
		(width 0.0889)
		(layer "In2.Cu")
		(net "SPI_CPU_CS0#")
	)
	(segment
		(start 75.217274 -34.222944)
		(end 74.1172 -34.222944)
		(width 0.0889)
		(layer "In2.Cu")
		(net "SPI_CPU_CS0#")
	)
	(segment
		(start 74.17181 -35.68065)
		(end 74.08291 -35.59175)
		(width 0.0889)
		(layer "In2.Cu")
		(net "SPI_CPU_CS0#")
	)
	(segment
		(start 74.08291 -35.59175)
		(end 73.79081 -35.59175)
		(width 0.0889)
		(layer "In2.Cu")
		(net "SPI_CPU_CS0#")
	)
	(segment
		(start 70.2564 -35.59175)
		(end 70.1548 -35.69335)
		(width 0.0889)
		(layer "In2.Cu")
		(net "SPI_CPU_CS0#")
	)
	(segment
		(start 69.42455 -35.59175)
		(end 69.0245 -35.59175)
		(width 0.0889)
		(layer "In2.Cu")
		(net "SPI_CPU_CS0#")
	)
	(segment
		(start 72.38111 -36.098734)
		(end 72.29221 -36.009834)
		(width 0.0889)
		(layer "In2.Cu")
		(net "SPI_CPU_CS0#")
	)
	(segment
		(start 72.20331 -35.59175)
		(end 70.2564 -35.59175)
		(width 0.0889)
		(layer "In2.Cu")
		(net "SPI_CPU_CS0#")
	)
	(segment
		(start 67.54114 -36.981892)
		(end 67.54114 -37.107368)
		(width 0.0889)
		(layer "In2.Cu")
		(net "SPI_CPU_CS0#")
	)
	(segment
		(start 74.1172 -34.222944)
		(end 74.0156 -34.324544)
		(width 0.0889)
		(layer "In2.Cu")
		(net "SPI_CPU_CS0#")
	)
	(segment
		(start 75.6158 -35.59175)
		(end 74.73061 -35.59175)
		(width 0.0889)
		(layer "In2.Cu")
		(net "SPI_CPU_CS0#")
	)
	(segment
		(start 73.61301 -36.098734)
		(end 73.32091 -36.098734)
		(width 0.0889)
		(layer "In2.Cu")
		(net "SPI_CPU_CS0#")
	)
	(segment
		(start 74.64171 -35.68065)
		(end 74.64171 -36.009834)
		(width 0.0889)
		(layer "In2.Cu")
		(net "SPI_CPU_CS0#")
	)
	(segment
		(start 68.22821 -37.00399)
		(end 68.102734 -37.00399)
		(width 0.0889)
		(layer "In2.Cu")
		(net "SPI_CPU_CS0#")
	)
	(segment
		(start 67.873626 -36.774882)
		(end 67.74815 -36.774882)
		(width 0.0889)
		(layer "In2.Cu")
		(net "SPI_CPU_CS0#")
	)
	(segment
		(start 73.23201 -36.009834)
		(end 73.23201 -35.68065)
		(width 0.0889)
		(layer "In2.Cu")
		(net "SPI_CPU_CS0#")
	)
	(segment
		(start 69.0245 -35.59175)
		(end 68.92925 -35.687)
		(width 0.0889)
		(layer "In2.Cu")
		(net "SPI_CPU_CS0#")
	)
	(segment
		(start 73.23201 -35.68065)
		(end 73.14311 -35.59175)
		(width 0.0889)
		(layer "In2.Cu")
		(net "SPI_CPU_CS0#")
	)
	(segment
		(start 75.6158 -35.0266)
		(end 75.7174 -35.1282)
		(width 0.0889)
		(layer "In2.Cu")
		(net "SPI_CPU_CS0#")
	)
	(segment
		(start 68.92925 -35.687)
		(end 68.92925 -36.30295)
		(width 0.0889)
		(layer "In2.Cu")
		(net "SPI_CPU_CS0#")
	)
	(segment
		(start 70.0532 -36.0934)
		(end 69.6214 -36.0934)
		(width 0.0889)
		(layer "In2.Cu")
		(net "SPI_CPU_CS0#")
	)
	(segment
		(start 69.5198 -35.9918)
		(end 69.5198 -35.687)
		(width 0.0889)
		(layer "In2.Cu")
		(net "SPI_CPU_CS0#")
	)
	(segment
		(start 69.6214 -36.0934)
		(end 69.5198 -35.9918)
		(width 0.0889)
		(layer "In2.Cu")
		(net "SPI_CPU_CS0#")
	)
	(segment
		(start 74.17181 -36.009834)
		(end 74.17181 -35.68065)
		(width 0.0889)
		(layer "In2.Cu")
		(net "SPI_CPU_CS0#")
	)
	(segment
		(start 75.318874 -33.797494)
		(end 75.318874 -34.121344)
		(width 0.0889)
		(layer "In2.Cu")
		(net "SPI_CPU_CS0#")
	)
	(segment
		(start 75.7174 -35.1282)
		(end 75.7174 -35.49015)
		(width 0.0889)
		(layer "In2.Cu")
		(net "SPI_CPU_CS0#")
	)
	(segment
		(start 74.0156 -34.324544)
		(end 74.0156 -34.925)
		(width 0.0889)
		(layer "In2.Cu")
		(net "SPI_CPU_CS0#")
	)
	(segment
		(start 75.7174 -35.49015)
		(end 75.6158 -35.59175)
		(width 0.0889)
		(layer "In2.Cu")
		(net "SPI_CPU_CS0#")
	)
	(segment
		(start 69.5198 -35.687)
		(end 69.42455 -35.59175)
		(width 0.0889)
		(layer "In2.Cu")
		(net "SPI_CPU_CS0#")
	)
	(segment
		(start 68.92925 -36.30295)
		(end 68.22821 -37.00399)
		(width 0.0889)
		(layer "In2.Cu")
		(net "SPI_CPU_CS0#")
	)
	(segment
		(start 74.64171 -36.009834)
		(end 74.55281 -36.098734)
		(width 0.0889)
		(layer "In2.Cu")
		(net "SPI_CPU_CS0#")
	)
	(segment
		(start 74.73061 -35.59175)
		(end 74.64171 -35.68065)
		(width 0.0889)
		(layer "In2.Cu")
		(net "SPI_CPU_CS0#")
	)
	(segment
		(start 72.76211 -36.009834)
		(end 72.67321 -36.098734)
		(width 0.0889)
		(layer "In2.Cu")
		(net "SPI_CPU_CS0#")
	)
	(segment
		(start 67.770248 -37.461952)
		(end 67.414648 -37.817552)
		(width 0.0889)
		(layer "In2.Cu")
		(net "SPI_CPU_CS0#")
	)
	(segment
		(start 67.770248 -37.336476)
		(end 67.770248 -37.461952)
		(width 0.0889)
		(layer "In2.Cu")
		(net "SPI_CPU_CS0#")
	)
	(segment
		(start 74.55281 -36.098734)
		(end 74.26071 -36.098734)
		(width 0.0889)
		(layer "In2.Cu")
		(net "SPI_CPU_CS0#")
	)
	(segment
		(start 70.1548 -35.69335)
		(end 70.1548 -35.9918)
		(width 0.0889)
		(layer "In2.Cu")
		(net "SPI_CPU_CS0#")
	)
	(segment
		(start 72.67321 -36.098734)
		(end 72.38111 -36.098734)
		(width 0.0889)
		(layer "In2.Cu")
		(net "SPI_CPU_CS0#")
	)
	(segment
		(start 68.102734 -37.00399)
		(end 67.873626 -36.774882)
		(width 0.0889)
		(layer "In2.Cu")
		(net "SPI_CPU_CS0#")
	)
	(segment
		(start 67.74815 -36.774882)
		(end 67.54114 -36.981892)
		(width 0.0889)
		(layer "In2.Cu")
		(net "SPI_CPU_CS0#")
	)
	(segment
		(start 72.85101 -35.59175)
		(end 72.76211 -35.68065)
		(width 0.0889)
		(layer "In2.Cu")
		(net "SPI_CPU_CS0#")
	)
	(segment
		(start 75.318874 -34.121344)
		(end 75.217274 -34.222944)
		(width 0.0889)
		(layer "In2.Cu")
		(net "SPI_CPU_CS0#")
	)
	(segment
		(start 113.182146 -24.485346)
		(end 127.49022 -38.79342)
		(width 0.1143)
		(layer "F.Cu")
		(net "LPC_CPU_CLKRUN#")
	)
	(segment
		(start 89.636346 -22.4536)
		(end 84.8106 -22.4536)
		(width 0.1143)
		(layer "F.Cu")
		(net "LPC_CPU_CLKRUN#")
	)
	(segment
		(start 88.986614 -39.431214)
		(end 88.600788 -39.431214)
		(width 0.1143)
		(layer "F.Cu")
		(net "LPC_CPU_CLKRUN#")
	)
	(segment
		(start 104.092248 -20.253452)
		(end 106.299 -18.0467)
		(width 0.1143)
		(layer "F.Cu")
		(net "LPC_CPU_CLKRUN#")
	)
	(segment
		(start 94.199456 -20.253452)
		(end 104.092248 -20.253452)
		(width 0.1143)
		(layer "F.Cu")
		(net "LPC_CPU_CLKRUN#")
	)
	(segment
		(start 89.951814 -22.138132)
		(end 89.636346 -22.4536)
		(width 0.1143)
		(layer "F.Cu")
		(net "LPC_CPU_CLKRUN#")
	)
	(segment
		(start 93.326458 -21.12645)
		(end 94.199456 -20.253452)
		(width 0.1143)
		(layer "F.Cu")
		(net "LPC_CPU_CLKRUN#")
	)
	(segment
		(start 91.553538 -21.12645)
		(end 93.326458 -21.12645)
		(width 0.1143)
		(layer "F.Cu")
		(net "LPC_CPU_CLKRUN#")
	)
	(segment
		(start 84.8106 -22.4536)
		(end 84.0486 -23.2156)
		(width 0.1143)
		(layer "F.Cu")
		(net "LPC_CPU_CLKRUN#")
	)
	(segment
		(start 113.182146 -18.3007)
		(end 113.182146 -24.485346)
		(width 0.1143)
		(layer "F.Cu")
		(net "LPC_CPU_CLKRUN#")
	)
	(segment
		(start 112.928146 -18.0467)
		(end 113.182146 -18.3007)
		(width 0.1143)
		(layer "F.Cu")
		(net "LPC_CPU_CLKRUN#")
	)
	(segment
		(start 90.3097 -21.7805)
		(end 90.899488 -21.7805)
		(width 0.1143)
		(layer "F.Cu")
		(net "LPC_CPU_CLKRUN#")
	)
	(segment
		(start 106.299 -18.0467)
		(end 112.928146 -18.0467)
		(width 0.1143)
		(layer "F.Cu")
		(net "LPC_CPU_CLKRUN#")
	)
	(segment
		(start 127.49022 -38.79342)
		(end 132.1308 -38.79342)
		(width 0.1143)
		(layer "F.Cu")
		(net "LPC_CPU_CLKRUN#")
	)
	(segment
		(start 89.0778 -39.5224)
		(end 88.986614 -39.431214)
		(width 0.1143)
		(layer "F.Cu")
		(net "LPC_CPU_CLKRUN#")
	)
	(segment
		(start 89.951814 -22.138132)
		(end 90.3097 -21.7805)
		(width 0.1143)
		(layer "F.Cu")
		(net "LPC_CPU_CLKRUN#")
	)
	(segment
		(start 84.0486 -23.2156)
		(end 84.0486 -23.7236)
		(width 0.1143)
		(layer "F.Cu")
		(net "LPC_CPU_CLKRUN#")
	)
	(segment
		(start 90.899488 -21.7805)
		(end 91.553538 -21.12645)
		(width 0.1143)
		(layer "F.Cu")
		(net "LPC_CPU_CLKRUN#")
	)
	(via
		(at 89.951814 -22.138132)
		(size 0.7112)
		(drill 0.3556)
		(layers "F.Cu" "B.Cu")
		(net "LPC_CPU_CLKRUN#")
	)
	(via
		(at 89.0778 -39.5224)
		(size 0.4318)
		(drill 0.2032)
		(layers "F.Cu" "B.Cu")
		(net "LPC_CPU_CLKRUN#")
	)
	(via
		(at 84.0486 -23.7236)
		(size 0.4318)
		(drill 0.2032)
		(layers "F.Cu" "B.Cu")
		(net "LPC_CPU_CLKRUN#")
	)
	(segment
		(start 89.0778 -40.1574)
		(end 88.7476 -40.4876)
		(width 0.1143)
		(layer "B.Cu")
		(net "LPC_CPU_CLKRUN#")
	)
	(segment
		(start 89.0778 -39.5224)
		(end 89.0778 -40.1574)
		(width 0.1143)
		(layer "B.Cu")
		(net "LPC_CPU_CLKRUN#")
	)
	(segment
		(start 83.43265 -25.358598)
		(end 83.43265 -25.600914)
		(width 0.0889)
		(layer "In9.Cu")
		(net "LPC_CPU_CLKRUN#")
	)
	(segment
		(start 85.486748 -33.598866)
		(end 87.192866 -33.598866)
		(width 0.0889)
		(layer "In9.Cu")
		(net "LPC_CPU_CLKRUN#")
	)
	(segment
		(start 87.383112 -33.789112)
		(end 87.383112 -34.938716)
		(width 0.0889)
		(layer "In9.Cu")
		(net "LPC_CPU_CLKRUN#")
	)
	(segment
		(start 88.797638 -39.50716)
		(end 89.06256 -39.50716)
		(width 0.0889)
		(layer "In9.Cu")
		(net "LPC_CPU_CLKRUN#")
	)
	(segment
		(start 83.57743 -25.745694)
		(end 83.57743 -29.47543)
		(width 0.0889)
		(layer "In9.Cu")
		(net "LPC_CPU_CLKRUN#")
	)
	(segment
		(start 87.503 -38.212522)
		(end 88.797638 -39.50716)
		(width 0.0889)
		(layer "In9.Cu")
		(net "LPC_CPU_CLKRUN#")
	)
	(segment
		(start 89.06256 -39.50716)
		(end 89.0778 -39.5224)
		(width 0.0889)
		(layer "In9.Cu")
		(net "LPC_CPU_CLKRUN#")
	)
	(segment
		(start 87.148162 -36.119562)
		(end 87.148162 -36.449762)
		(width 0.0889)
		(layer "In9.Cu")
		(net "LPC_CPU_CLKRUN#")
	)
	(segment
		(start 87.0077 -35.9791)
		(end 87.148162 -36.119562)
		(width 0.0889)
		(layer "In9.Cu")
		(net "LPC_CPU_CLKRUN#")
	)
	(segment
		(start 84.03336 -29.93136)
		(end 84.03336 -31.242)
		(width 0.0889)
		(layer "In9.Cu")
		(net "LPC_CPU_CLKRUN#")
	)
	(segment
		(start 84.03336 -31.242)
		(end 84.55152 -31.76016)
		(width 0.0889)
		(layer "In9.Cu")
		(net "LPC_CPU_CLKRUN#")
	)
	(segment
		(start 82.95005 -24.41575)
		(end 82.95005 -24.875998)
		(width 0.0889)
		(layer "In9.Cu")
		(net "LPC_CPU_CLKRUN#")
	)
	(segment
		(start 87.148162 -36.449762)
		(end 87.503 -36.8046)
		(width 0.0889)
		(layer "In9.Cu")
		(net "LPC_CPU_CLKRUN#")
	)
	(segment
		(start 87.383112 -34.938716)
		(end 87.0077 -35.314128)
		(width 0.0889)
		(layer "In9.Cu")
		(net "LPC_CPU_CLKRUN#")
	)
	(segment
		(start 84.468208 -32.237172)
		(end 84.468208 -32.580326)
		(width 0.0889)
		(layer "In9.Cu")
		(net "LPC_CPU_CLKRUN#")
	)
	(segment
		(start 83.57743 -29.47543)
		(end 84.03336 -29.93136)
		(width 0.0889)
		(layer "In9.Cu")
		(net "LPC_CPU_CLKRUN#")
	)
	(segment
		(start 84.0486 -23.7236)
		(end 83.5406 -24.2316)
		(width 0.0889)
		(layer "In9.Cu")
		(net "LPC_CPU_CLKRUN#")
	)
	(segment
		(start 82.95005 -24.875998)
		(end 83.43265 -25.358598)
		(width 0.0889)
		(layer "In9.Cu")
		(net "LPC_CPU_CLKRUN#")
	)
	(segment
		(start 87.503 -36.8046)
		(end 87.503 -38.212522)
		(width 0.0889)
		(layer "In9.Cu")
		(net "LPC_CPU_CLKRUN#")
	)
	(segment
		(start 84.55152 -31.76016)
		(end 84.55152 -32.15386)
		(width 0.0889)
		(layer "In9.Cu")
		(net "LPC_CPU_CLKRUN#")
	)
	(segment
		(start 83.43265 -25.600914)
		(end 83.57743 -25.745694)
		(width 0.0889)
		(layer "In9.Cu")
		(net "LPC_CPU_CLKRUN#")
	)
	(segment
		(start 83.1342 -24.2316)
		(end 82.95005 -24.41575)
		(width 0.0889)
		(layer "In9.Cu")
		(net "LPC_CPU_CLKRUN#")
	)
	(segment
		(start 83.5406 -24.2316)
		(end 83.1342 -24.2316)
		(width 0.0889)
		(layer "In9.Cu")
		(net "LPC_CPU_CLKRUN#")
	)
	(segment
		(start 84.55152 -32.15386)
		(end 84.468208 -32.237172)
		(width 0.0889)
		(layer "In9.Cu")
		(net "LPC_CPU_CLKRUN#")
	)
	(segment
		(start 87.0077 -35.314128)
		(end 87.0077 -35.9791)
		(width 0.0889)
		(layer "In9.Cu")
		(net "LPC_CPU_CLKRUN#")
	)
	(segment
		(start 84.468208 -32.580326)
		(end 85.486748 -33.598866)
		(width 0.0889)
		(layer "In9.Cu")
		(net "LPC_CPU_CLKRUN#")
	)
	(segment
		(start 87.192866 -33.598866)
		(end 87.383112 -33.789112)
		(width 0.0889)
		(layer "In9.Cu")
		(net "LPC_CPU_CLKRUN#")
	)
	(segment
		(start 84.13115 -21.79955)
		(end 84.3534 -22.0218)
		(width 0.1143)
		(layer "F.Cu")
		(net "LPC_CPU_FRAME#")
	)
	(segment
		(start 83.26755 -22.019006)
		(end 83.487006 -21.79955)
		(width 0.1143)
		(layer "F.Cu")
		(net "LPC_CPU_FRAME#")
	)
	(segment
		(start 94.02572 -19.834352)
		(end 103.863648 -19.834352)
		(width 0.1143)
		(layer "F.Cu")
		(net "LPC_CPU_FRAME#")
	)
	(segment
		(start 83.487006 -21.79955)
		(end 84.13115 -21.79955)
		(width 0.1143)
		(layer "F.Cu")
		(net "LPC_CPU_FRAME#")
	)
	(segment
		(start 83.26755 -23.203662)
		(end 83.26755 -22.019006)
		(width 0.1143)
		(layer "F.Cu")
		(net "LPC_CPU_FRAME#")
	)
	(segment
		(start 130.48488 -38.37432)
		(end 131.56565 -37.29355)
		(width 0.1143)
		(layer "F.Cu")
		(net "LPC_CPU_FRAME#")
	)
	(segment
		(start 84.7598 -40.0304)
		(end 84.582 -40.2082)
		(width 0.1143)
		(layer "F.Cu")
		(net "LPC_CPU_FRAME#")
	)
	(segment
		(start 84.7598 -39.462202)
		(end 84.7598 -40.0304)
		(width 0.1143)
		(layer "F.Cu")
		(net "LPC_CPU_FRAME#")
	)
	(segment
		(start 106.0704 -17.6276)
		(end 113.11128 -17.6276)
		(width 0.1143)
		(layer "F.Cu")
		(net "LPC_CPU_FRAME#")
	)
	(segment
		(start 84.3534 -22.0218)
		(end 89.174574 -22.0218)
		(width 0.1143)
		(layer "F.Cu")
		(net "LPC_CPU_FRAME#")
	)
	(segment
		(start 113.601246 -24.31161)
		(end 127.663956 -38.37432)
		(width 0.1143)
		(layer "F.Cu")
		(net "LPC_CPU_FRAME#")
	)
	(segment
		(start 103.863648 -19.834352)
		(end 106.0704 -17.6276)
		(width 0.1143)
		(layer "F.Cu")
		(net "LPC_CPU_FRAME#")
	)
	(segment
		(start 83.312 -23.5458)
		(end 83.312 -23.248112)
		(width 0.1143)
		(layer "F.Cu")
		(net "LPC_CPU_FRAME#")
	)
	(segment
		(start 89.894918 -21.301456)
		(end 90.687652 -21.301456)
		(width 0.1143)
		(layer "F.Cu")
		(net "LPC_CPU_FRAME#")
	)
	(segment
		(start 127.663956 -38.37432)
		(end 130.48488 -38.37432)
		(width 0.1143)
		(layer "F.Cu")
		(net "LPC_CPU_FRAME#")
	)
	(segment
		(start 93.152722 -20.70735)
		(end 94.02572 -19.834352)
		(width 0.1143)
		(layer "F.Cu")
		(net "LPC_CPU_FRAME#")
	)
	(segment
		(start 83.312 -23.248112)
		(end 83.26755 -23.203662)
		(width 0.1143)
		(layer "F.Cu")
		(net "LPC_CPU_FRAME#")
	)
	(segment
		(start 89.174574 -22.0218)
		(end 89.894918 -21.301456)
		(width 0.1143)
		(layer "F.Cu")
		(net "LPC_CPU_FRAME#")
	)
	(segment
		(start 90.687652 -21.301456)
		(end 91.281758 -20.70735)
		(width 0.1143)
		(layer "F.Cu")
		(net "LPC_CPU_FRAME#")
	)
	(segment
		(start 113.11128 -17.6276)
		(end 113.601246 -18.117566)
		(width 0.1143)
		(layer "F.Cu")
		(net "LPC_CPU_FRAME#")
	)
	(segment
		(start 84.790788 -39.431214)
		(end 84.7598 -39.462202)
		(width 0.1143)
		(layer "F.Cu")
		(net "LPC_CPU_FRAME#")
	)
	(segment
		(start 113.601246 -18.117566)
		(end 113.601246 -24.31161)
		(width 0.1143)
		(layer "F.Cu")
		(net "LPC_CPU_FRAME#")
	)
	(segment
		(start 91.281758 -20.70735)
		(end 93.152722 -20.70735)
		(width 0.1143)
		(layer "F.Cu")
		(net "LPC_CPU_FRAME#")
	)
	(segment
		(start 131.56565 -37.29355)
		(end 132.1308 -37.29355)
		(width 0.1143)
		(layer "F.Cu")
		(net "LPC_CPU_FRAME#")
	)
	(via
		(at 84.582 -40.2082)
		(size 0.4318)
		(drill 0.2032)
		(layers "F.Cu" "B.Cu")
		(net "LPC_CPU_FRAME#")
	)
	(via
		(at 83.312 -23.5458)
		(size 0.4318)
		(drill 0.2032)
		(layers "F.Cu" "B.Cu")
		(net "LPC_CPU_FRAME#")
	)
	(via
		(at 75.640438 -44.195238)
		(size 0.7112)
		(drill 0.3556)
		(layers "F.Cu" "B.Cu")
		(net "LPC_CPU_FRAME#")
	)
	(segment
		(start 76.947776 -42.8879)
		(end 80.198976 -42.8879)
		(width 0.1143)
		(layer "B.Cu")
		(net "LPC_CPU_FRAME#")
	)
	(segment
		(start 75.640438 -44.195238)
		(end 76.947776 -42.8879)
		(width 0.1143)
		(layer "B.Cu")
		(net "LPC_CPU_FRAME#")
	)
	(segment
		(start 82.614262 -40.702738)
		(end 83.420966 -39.896034)
		(width 0.1143)
		(layer "B.Cu")
		(net "LPC_CPU_FRAME#")
	)
	(segment
		(start 83.420966 -39.896034)
		(end 84.269834 -39.896034)
		(width 0.1143)
		(layer "B.Cu")
		(net "LPC_CPU_FRAME#")
	)
	(segment
		(start 82.163412 -40.922194)
		(end 82.382868 -40.702738)
		(width 0.1143)
		(layer "B.Cu")
		(net "LPC_CPU_FRAME#")
	)
	(segment
		(start 80.198976 -42.8879)
		(end 82.163412 -40.923464)
		(width 0.1143)
		(layer "B.Cu")
		(net "LPC_CPU_FRAME#")
	)
	(segment
		(start 74.5998 -44.196)
		(end 75.639676 -44.196)
		(width 0.1143)
		(layer "B.Cu")
		(net "LPC_CPU_FRAME#")
	)
	(segment
		(start 82.163412 -40.923464)
		(end 82.163412 -40.922194)
		(width 0.1143)
		(layer "B.Cu")
		(net "LPC_CPU_FRAME#")
	)
	(segment
		(start 82.382868 -40.702738)
		(end 82.614262 -40.702738)
		(width 0.1143)
		(layer "B.Cu")
		(net "LPC_CPU_FRAME#")
	)
	(segment
		(start 75.639676 -44.196)
		(end 75.640438 -44.195238)
		(width 0.1143)
		(layer "B.Cu")
		(net "LPC_CPU_FRAME#")
	)
	(segment
		(start 84.269834 -39.896034)
		(end 84.582 -40.2082)
		(width 0.1143)
		(layer "B.Cu")
		(net "LPC_CPU_FRAME#")
	)
	(segment
		(start 84.737702 -36.70935)
		(end 84.223352 -36.195)
		(width 0.0889)
		(layer "In2.Cu")
		(net "LPC_CPU_FRAME#")
	)
	(segment
		(start 82.566256 -27.1907)
		(end 82.477356 -27.1018)
		(width 0.0889)
		(layer "In2.Cu")
		(net "LPC_CPU_FRAME#")
	)
	(segment
		(start 83.0072 -27.2796)
		(end 82.9183 -27.1907)
		(width 0.0889)
		(layer "In2.Cu")
		(net "LPC_CPU_FRAME#")
	)
	(segment
		(start 82.4103 -30.988)
		(end 81.6483 -30.988)
		(width 0.0889)
		(layer "In2.Cu")
		(net "LPC_CPU_FRAME#")
	)
	(segment
		(start 84.582 -40.2082)
		(end 84.7852 -40.005)
		(width 0.0889)
		(layer "In2.Cu")
		(net "LPC_CPU_FRAME#")
	)
	(segment
		(start 82.1309 -29.39415)
		(end 81.4578 -29.39415)
		(width 0.0889)
		(layer "In2.Cu")
		(net "LPC_CPU_FRAME#")
	)
	(segment
		(start 83.2358 -30.353)
		(end 83.2358 -29.9339)
		(width 0.0889)
		(layer "In2.Cu")
		(net "LPC_CPU_FRAME#")
	)
	(segment
		(start 81.2292 -28.1305)
		(end 81.1276 -28.0289)
		(width 0.0889)
		(layer "In2.Cu")
		(net "LPC_CPU_FRAME#")
	)
	(segment
		(start 81.8388 -24.310086)
		(end 81.8388 -24.003)
		(width 0.0889)
		(layer "In2.Cu")
		(net "LPC_CPU_FRAME#")
	)
	(segment
		(start 83.2358 -29.9339)
		(end 83.1469 -29.845)
		(width 0.0889)
		(layer "In2.Cu")
		(net "LPC_CPU_FRAME#")
	)
	(segment
		(start 81.2165 -27.7241)
		(end 82.9183 -27.7241)
		(width 0.0889)
		(layer "In2.Cu")
		(net "LPC_CPU_FRAME#")
	)
	(segment
		(start 81.1022 -32.538162)
		(end 80.9498 -32.385762)
		(width 0.0889)
		(layer "In2.Cu")
		(net "LPC_CPU_FRAME#")
	)
	(segment
		(start 81.6483 -30.988)
		(end 81.5594 -30.8991)
		(width 0.0889)
		(layer "In2.Cu")
		(net "LPC_CPU_FRAME#")
	)
	(segment
		(start 84.7852 -40.005)
		(end 84.7852 -38.7985)
		(width 0.0889)
		(layer "In2.Cu")
		(net "LPC_CPU_FRAME#")
	)
	(segment
		(start 85.1662 -37.7698)
		(end 85.1662 -36.952936)
		(width 0.0889)
		(layer "In2.Cu")
		(net "LPC_CPU_FRAME#")
	)
	(segment
		(start 83.1469 -29.845)
		(end 82.3087 -29.845)
		(width 0.0889)
		(layer "In2.Cu")
		(net "LPC_CPU_FRAME#")
	)
	(segment
		(start 81.3562 -29.05125)
		(end 81.4578 -28.94965)
		(width 0.0889)
		(layer "In2.Cu")
		(net "LPC_CPU_FRAME#")
	)
	(segment
		(start 85.2678 -37.8714)
		(end 85.1662 -37.7698)
		(width 0.0889)
		(layer "In2.Cu")
		(net "LPC_CPU_FRAME#")
	)
	(segment
		(start 81.380838 -32.538162)
		(end 81.1022 -32.538162)
		(width 0.0889)
		(layer "In2.Cu")
		(net "LPC_CPU_FRAME#")
	)
	(segment
		(start 82.9056 -24.551386)
		(end 82.7532 -24.398986)
		(width 0.0889)
		(layer "In2.Cu")
		(net "LPC_CPU_FRAME#")
	)
	(segment
		(start 85.1662 -36.952936)
		(end 84.922614 -36.70935)
		(width 0.0889)
		(layer "In2.Cu")
		(net "LPC_CPU_FRAME#")
	)
	(segment
		(start 82.2198 -28.2194)
		(end 82.1309 -28.1305)
		(width 0.0889)
		(layer "In2.Cu")
		(net "LPC_CPU_FRAME#")
	)
	(segment
		(start 82.9183 -27.1907)
		(end 82.566256 -27.1907)
		(width 0.0889)
		(layer "In2.Cu")
		(net "LPC_CPU_FRAME#")
	)
	(segment
		(start 82.9183 -27.7241)
		(end 83.0072 -27.6352)
		(width 0.0889)
		(layer "In2.Cu")
		(net "LPC_CPU_FRAME#")
	)
	(segment
		(start 86.614 -38.6969)
		(end 86.7664 -38.5445)
		(width 0.0889)
		(layer "In2.Cu")
		(net "LPC_CPU_FRAME#")
	)
	(segment
		(start 82.639916 -25.04567)
		(end 82.9056 -24.779986)
		(width 0.0889)
		(layer "In2.Cu")
		(net "LPC_CPU_FRAME#")
	)
	(segment
		(start 81.3562 -29.29255)
		(end 81.3562 -29.05125)
		(width 0.0889)
		(layer "In2.Cu")
		(net "LPC_CPU_FRAME#")
	)
	(segment
		(start 82.7532 -24.398986)
		(end 81.9277 -24.398986)
		(width 0.0889)
		(layer "In2.Cu")
		(net "LPC_CPU_FRAME#")
	)
	(segment
		(start 81.421986 -31.5214)
		(end 82.4103 -31.5214)
		(width 0.0889)
		(layer "In2.Cu")
		(net "LPC_CPU_FRAME#")
	)
	(segment
		(start 82.804 -32.7406)
		(end 83.0834 -32.7406)
		(width 0.0889)
		(layer "In2.Cu")
		(net "LPC_CPU_FRAME#")
	)
	(segment
		(start 83.1596 -33.528)
		(end 82.804 -33.528)
		(width 0.0889)
		(layer "In2.Cu")
		(net "LPC_CPU_FRAME#")
	)
	(segment
		(start 86.7664 -38.0238)
		(end 86.614 -37.8714)
		(width 0.0889)
		(layer "In2.Cu")
		(net "LPC_CPU_FRAME#")
	)
	(segment
		(start 81.4451 -25.414986)
		(end 81.814416 -25.04567)
		(width 0.0889)
		(layer "In2.Cu")
		(net "LPC_CPU_FRAME#")
	)
	(segment
		(start 82.2198 -29.7561)
		(end 82.2198 -29.48305)
		(width 0.0889)
		(layer "In2.Cu")
		(net "LPC_CPU_FRAME#")
	)
	(segment
		(start 82.388456 -26.5938)
		(end 82.032856 -26.5938)
		(width 0.0889)
		(layer "In2.Cu")
		(net "LPC_CPU_FRAME#")
	)
	(segment
		(start 80.9498 -31.993586)
		(end 81.421986 -31.5214)
		(width 0.0889)
		(layer "In2.Cu")
		(net "LPC_CPU_FRAME#")
	)
	(segment
		(start 81.5594 -30.6578)
		(end 81.7118 -30.5054)
		(width 0.0889)
		(layer "In2.Cu")
		(net "LPC_CPU_FRAME#")
	)
	(segment
		(start 82.804 -33.528)
		(end 82.7024 -33.4264)
		(width 0.0889)
		(layer "In2.Cu")
		(net "LPC_CPU_FRAME#")
	)
	(segment
		(start 82.7024 -32.8422)
		(end 82.804 -32.7406)
		(width 0.0889)
		(layer "In2.Cu")
		(net "LPC_CPU_FRAME#")
	)
	(segment
		(start 81.855056 -27.1907)
		(end 81.2165 -27.1907)
		(width 0.0889)
		(layer "In2.Cu")
		(net "LPC_CPU_FRAME#")
	)
	(segment
		(start 82.477356 -26.6827)
		(end 82.388456 -26.5938)
		(width 0.0889)
		(layer "In2.Cu")
		(net "LPC_CPU_FRAME#")
	)
	(segment
		(start 84.8868 -38.6969)
		(end 86.614 -38.6969)
		(width 0.0889)
		(layer "In2.Cu")
		(net "LPC_CPU_FRAME#")
	)
	(segment
		(start 86.7664 -38.5445)
		(end 86.7664 -38.0238)
		(width 0.0889)
		(layer "In2.Cu")
		(net "LPC_CPU_FRAME#")
	)
	(segment
		(start 80.9498 -32.385762)
		(end 80.9498 -31.993586)
		(width 0.0889)
		(layer "In2.Cu")
		(net "LPC_CPU_FRAME#")
	)
	(segment
		(start 81.9912 -23.8506)
		(end 83.0072 -23.8506)
		(width 0.0889)
		(layer "In2.Cu")
		(net "LPC_CPU_FRAME#")
	)
	(segment
		(start 81.8388 -24.003)
		(end 81.9912 -23.8506)
		(width 0.0889)
		(layer "In2.Cu")
		(net "LPC_CPU_FRAME#")
	)
	(segment
		(start 81.4578 -29.39415)
		(end 81.3562 -29.29255)
		(width 0.0889)
		(layer "In2.Cu")
		(net "LPC_CPU_FRAME#")
	)
	(segment
		(start 83.185 -32.131)
		(end 83.0326 -31.9786)
		(width 0.0889)
		(layer "In2.Cu")
		(net "LPC_CPU_FRAME#")
	)
	(segment
		(start 81.4451 -26.3779)
		(end 81.4451 -25.414986)
		(width 0.0889)
		(layer "In2.Cu")
		(net "LPC_CPU_FRAME#")
	)
	(segment
		(start 86.614 -37.8714)
		(end 85.2678 -37.8714)
		(width 0.0889)
		(layer "In2.Cu")
		(net "LPC_CPU_FRAME#")
	)
	(segment
		(start 81.943956 -26.6827)
		(end 81.943956 -27.1018)
		(width 0.0889)
		(layer "In2.Cu")
		(net "LPC_CPU_FRAME#")
	)
	(segment
		(start 84.011516 -35.708082)
		(end 83.637882 -35.708082)
		(width 0.0889)
		(layer "In2.Cu")
		(net "LPC_CPU_FRAME#")
	)
	(segment
		(start 81.9277 -24.398986)
		(end 81.8388 -24.310086)
		(width 0.0889)
		(layer "In2.Cu")
		(net "LPC_CPU_FRAME#")
	)
	(segment
		(start 82.477356 -27.1018)
		(end 82.477356 -26.6827)
		(width 0.0889)
		(layer "In2.Cu")
		(net "LPC_CPU_FRAME#")
	)
	(segment
		(start 81.1276 -27.813)
		(end 81.2165 -27.7241)
		(width 0.0889)
		(layer "In2.Cu")
		(net "LPC_CPU_FRAME#")
	)
	(segment
		(start 81.9404 -31.9786)
		(end 81.380838 -32.538162)
		(width 0.0889)
		(layer "In2.Cu")
		(net "LPC_CPU_FRAME#")
	)
	(segment
		(start 82.7024 -33.4264)
		(end 82.7024 -32.8422)
		(width 0.0889)
		(layer "In2.Cu")
		(net "LPC_CPU_FRAME#")
	)
	(segment
		(start 81.5594 -30.8991)
		(end 81.5594 -30.6578)
		(width 0.0889)
		(layer "In2.Cu")
		(net "LPC_CPU_FRAME#")
	)
	(segment
		(start 83.0072 -27.6352)
		(end 83.0072 -27.2796)
		(width 0.0889)
		(layer "In2.Cu")
		(net "LPC_CPU_FRAME#")
	)
	(segment
		(start 83.185 -32.639)
		(end 83.185 -32.131)
		(width 0.0889)
		(layer "In2.Cu")
		(net "LPC_CPU_FRAME#")
	)
	(segment
		(start 81.2165 -27.1907)
		(end 81.1276 -27.1018)
		(width 0.0889)
		(layer "In2.Cu")
		(net "LPC_CPU_FRAME#")
	)
	(segment
		(start 83.2612 -35.3314)
		(end 83.2612 -33.6296)
		(width 0.0889)
		(layer "In2.Cu")
		(net "LPC_CPU_FRAME#")
	)
	(segment
		(start 82.4992 -31.4325)
		(end 82.4992 -31.0769)
		(width 0.0889)
		(layer "In2.Cu")
		(net "LPC_CPU_FRAME#")
	)
	(segment
		(start 82.2198 -28.86075)
		(end 82.2198 -28.2194)
		(width 0.0889)
		(layer "In2.Cu")
		(net "LPC_CPU_FRAME#")
	)
	(segment
		(start 81.4578 -28.94965)
		(end 82.1309 -28.94965)
		(width 0.0889)
		(layer "In2.Cu")
		(net "LPC_CPU_FRAME#")
	)
	(segment
		(start 81.814416 -25.04567)
		(end 82.639916 -25.04567)
		(width 0.0889)
		(layer "In2.Cu")
		(net "LPC_CPU_FRAME#")
	)
	(segment
		(start 82.9056 -24.779986)
		(end 82.9056 -24.551386)
		(width 0.0889)
		(layer "In2.Cu")
		(net "LPC_CPU_FRAME#")
	)
	(segment
		(start 82.3087 -29.845)
		(end 82.2198 -29.7561)
		(width 0.0889)
		(layer "In2.Cu")
		(net "LPC_CPU_FRAME#")
	)
	(segment
		(start 81.1276 -28.0289)
		(end 81.1276 -27.813)
		(width 0.0889)
		(layer "In2.Cu")
		(net "LPC_CPU_FRAME#")
	)
	(segment
		(start 84.922614 -36.70935)
		(end 84.737702 -36.70935)
		(width 0.0889)
		(layer "In2.Cu")
		(net "LPC_CPU_FRAME#")
	)
	(segment
		(start 83.637882 -35.708082)
		(end 83.2612 -35.3314)
		(width 0.0889)
		(layer "In2.Cu")
		(net "LPC_CPU_FRAME#")
	)
	(segment
		(start 82.1309 -28.94965)
		(end 82.2198 -28.86075)
		(width 0.0889)
		(layer "In2.Cu")
		(net "LPC_CPU_FRAME#")
	)
	(segment
		(start 83.0834 -30.5054)
		(end 83.2358 -30.353)
		(width 0.0889)
		(layer "In2.Cu")
		(net "LPC_CPU_FRAME#")
	)
	(segment
		(start 81.943956 -27.1018)
		(end 81.855056 -27.1907)
		(width 0.0889)
		(layer "In2.Cu")
		(net "LPC_CPU_FRAME#")
	)
	(segment
		(start 83.0834 -32.7406)
		(end 83.185 -32.639)
		(width 0.0889)
		(layer "In2.Cu")
		(net "LPC_CPU_FRAME#")
	)
	(segment
		(start 83.0072 -23.8506)
		(end 83.312 -23.5458)
		(width 0.0889)
		(layer "In2.Cu")
		(net "LPC_CPU_FRAME#")
	)
	(segment
		(start 84.223352 -36.195)
		(end 84.223352 -35.919918)
		(width 0.0889)
		(layer "In2.Cu")
		(net "LPC_CPU_FRAME#")
	)
	(segment
		(start 82.1309 -28.1305)
		(end 81.2292 -28.1305)
		(width 0.0889)
		(layer "In2.Cu")
		(net "LPC_CPU_FRAME#")
	)
	(segment
		(start 81.1276 -27.1018)
		(end 81.1276 -26.6954)
		(width 0.0889)
		(layer "In2.Cu")
		(net "LPC_CPU_FRAME#")
	)
	(segment
		(start 82.4103 -31.5214)
		(end 82.4992 -31.4325)
		(width 0.0889)
		(layer "In2.Cu")
		(net "LPC_CPU_FRAME#")
	)
	(segment
		(start 81.1276 -26.6954)
		(end 81.4451 -26.3779)
		(width 0.0889)
		(layer "In2.Cu")
		(net "LPC_CPU_FRAME#")
	)
	(segment
		(start 84.7852 -38.7985)
		(end 84.8868 -38.6969)
		(width 0.0889)
		(layer "In2.Cu")
		(net "LPC_CPU_FRAME#")
	)
	(segment
		(start 82.032856 -26.5938)
		(end 81.943956 -26.6827)
		(width 0.0889)
		(layer "In2.Cu")
		(net "LPC_CPU_FRAME#")
	)
	(segment
		(start 83.2612 -33.6296)
		(end 83.1596 -33.528)
		(width 0.0889)
		(layer "In2.Cu")
		(net "LPC_CPU_FRAME#")
	)
	(segment
		(start 81.7118 -30.5054)
		(end 83.0834 -30.5054)
		(width 0.0889)
		(layer "In2.Cu")
		(net "LPC_CPU_FRAME#")
	)
	(segment
		(start 84.223352 -35.919918)
		(end 84.011516 -35.708082)
		(width 0.0889)
		(layer "In2.Cu")
		(net "LPC_CPU_FRAME#")
	)
	(segment
		(start 82.2198 -29.48305)
		(end 82.1309 -29.39415)
		(width 0.0889)
		(layer "In2.Cu")
		(net "LPC_CPU_FRAME#")
	)
	(segment
		(start 83.0326 -31.9786)
		(end 81.9404 -31.9786)
		(width 0.0889)
		(layer "In2.Cu")
		(net "LPC_CPU_FRAME#")
	)
	(segment
		(start 82.4992 -31.0769)
		(end 82.4103 -30.988)
		(width 0.0889)
		(layer "In2.Cu")
		(net "LPC_CPU_FRAME#")
	)
	(segment
		(start 108.88345 -6.01345)
		(end 110.84179 -6.01345)
		(width 0.1143)
		(layer "F.Cu")
		(net "PMU_PLTRST#")
	)
	(segment
		(start 113.80724 -8.9789)
		(end 112.11306 -7.28472)
		(width 0.1143)
		(layer "F.Cu")
		(net "PMU_PLTRST#")
	)
	(segment
		(start 118.9228 -10.2362)
		(end 117.6655 -8.9789)
		(width 0.1143)
		(layer "F.Cu")
		(net "PMU_PLTRST#")
	)
	(segment
		(start 110.84179 -6.01345)
		(end 112.11306 -7.28472)
		(width 0.1143)
		(layer "F.Cu")
		(net "PMU_PLTRST#")
	)
	(segment
		(start 128.9558 -24.9682)
		(end 123.753626 -24.9682)
		(width 0.1143)
		(layer "F.Cu")
		(net "PMU_PLTRST#")
	)
	(segment
		(start 117.6655 -8.9789)
		(end 113.80724 -8.9789)
		(width 0.1143)
		(layer "F.Cu")
		(net "PMU_PLTRST#")
	)
	(segment
		(start 118.9228 -13.3604)
		(end 118.9228 -10.2362)
		(width 0.1143)
		(layer "F.Cu")
		(net "PMU_PLTRST#")
	)
	(segment
		(start 123.753626 -24.9682)
		(end 120.116346 -21.33092)
		(width 0.1143)
		(layer "F.Cu")
		(net "PMU_PLTRST#")
	)
	(segment
		(start 107.569 -4.28879)
		(end 107.569 -4.699)
		(width 0.1143)
		(layer "F.Cu")
		(net "PMU_PLTRST#")
	)
	(segment
		(start 107.569 -4.699)
		(end 108.88345 -6.01345)
		(width 0.1143)
		(layer "F.Cu")
		(net "PMU_PLTRST#")
	)
	(segment
		(start 129.3368 -25.3492)
		(end 128.9558 -24.9682)
		(width 0.1143)
		(layer "F.Cu")
		(net "PMU_PLTRST#")
	)
	(segment
		(start 120.116346 -21.33092)
		(end 120.116346 -14.553946)
		(width 0.1143)
		(layer "F.Cu")
		(net "PMU_PLTRST#")
	)
	(segment
		(start 120.116346 -14.553946)
		(end 118.9228 -13.3604)
		(width 0.1143)
		(layer "F.Cu")
		(net "PMU_PLTRST#")
	)
	(via
		(at 112.11306 -7.28472)
		(size 0.508)
		(drill 0.254)
		(layers "F.Cu" "B.Cu")
		(net "PMU_PLTRST#")
	)
	(via
		(at 83.204558 -12.31265)
		(size 0.508)
		(drill 0.254)
		(layers "F.Cu" "B.Cu")
		(net "PMU_PLTRST#")
	)
	(via
		(at 9.6266 -49.6062)
		(size 0.508)
		(drill 0.254)
		(layers "F.Cu" "B.Cu")
		(net "PMU_PLTRST#")
	)
	(via
		(at 102.31628 -13.843)
		(size 0.7112)
		(drill 0.3556)
		(layers "F.Cu" "B.Cu")
		(net "PMU_PLTRST#")
	)
	(via
		(at 77.968094 -39.044118)
		(size 0.4318)
		(drill 0.2032)
		(layers "F.Cu" "B.Cu")
		(net "PMU_PLTRST#")
	)
	(via
		(at 55.8546 -9.9314)
		(size 0.508)
		(drill 0.254)
		(layers "F.Cu" "B.Cu")
		(net "PMU_PLTRST#")
	)
	(via
		(at 107.569 -4.28879)
		(size 0.508)
		(drill 0.254)
		(layers "F.Cu" "B.Cu")
		(net "PMU_PLTRST#")
	)
	(segment
		(start 105.918 -11.354816)
		(end 105.918 -5.93979)
		(width 0.1143)
		(layer "B.Cu")
		(net "PMU_PLTRST#")
	)
	(segment
		(start 102.31628 -13.50772)
		(end 102.82428 -12.99972)
		(width 0.1143)
		(layer "B.Cu")
		(net "PMU_PLTRST#")
	)
	(segment
		(start 111.49076 -8.17372)
		(end 111.49076 -7.90702)
		(width 0.1143)
		(layer "B.Cu")
		(net "PMU_PLTRST#")
	)
	(segment
		(start 55.9308 -9.9314)
		(end 55.8546 -9.9314)
		(width 0.1143)
		(layer "B.Cu")
		(net "PMU_PLTRST#")
	)
	(segment
		(start 78.1812 -38.831012)
		(end 77.968094 -39.044118)
		(width 0.1143)
		(layer "B.Cu")
		(net "PMU_PLTRST#")
	)
	(segment
		(start 102.31628 -15.09776)
		(end 102.31628 -13.843)
		(width 0.1143)
		(layer "B.Cu")
		(net "PMU_PLTRST#")
	)
	(segment
		(start 14.097 -54.7116)
		(end 14.3002 -54.9148)
		(width 0.1143)
		(layer "B.Cu")
		(net "PMU_PLTRST#")
	)
	(segment
		(start 58.2168 -12.2174)
		(end 55.9308 -9.9314)
		(width 0.1143)
		(layer "B.Cu")
		(net "PMU_PLTRST#")
	)
	(segment
		(start 15.8496 -54.9148)
		(end 16.3068 -55.372)
		(width 0.1143)
		(layer "B.Cu")
		(net "PMU_PLTRST#")
	)
	(segment
		(start 102.82428 -12.99972)
		(end 104.273096 -12.99972)
		(width 0.1143)
		(layer "B.Cu")
		(net "PMU_PLTRST#")
	)
	(segment
		(start 9.6266 -49.6062)
		(end 9.7536 -49.6062)
		(width 0.1143)
		(layer "B.Cu")
		(net "PMU_PLTRST#")
	)
	(segment
		(start 105.918 -5.93979)
		(end 107.569 -4.28879)
		(width 0.1143)
		(layer "B.Cu")
		(net "PMU_PLTRST#")
	)
	(segment
		(start 9.7536 -49.6062)
		(end 10.2108 -50.0634)
		(width 0.1143)
		(layer "B.Cu")
		(net "PMU_PLTRST#")
	)
	(segment
		(start 14.3002 -54.9148)
		(end 15.8496 -54.9148)
		(width 0.1143)
		(layer "B.Cu")
		(net "PMU_PLTRST#")
	)
	(segment
		(start 104.273096 -12.99972)
		(end 105.918 -11.354816)
		(width 0.1143)
		(layer "B.Cu")
		(net "PMU_PLTRST#")
	)
	(segment
		(start 78.1812 -38.4302)
		(end 78.1812 -38.831012)
		(width 0.1143)
		(layer "B.Cu")
		(net "PMU_PLTRST#")
	)
	(segment
		(start 102.31628 -13.843)
		(end 102.31628 -13.50772)
		(width 0.1143)
		(layer "B.Cu")
		(net "PMU_PLTRST#")
	)
	(segment
		(start 14.097 -53.484018)
		(end 14.097 -54.7116)
		(width 0.1143)
		(layer "B.Cu")
		(net "PMU_PLTRST#")
	)
	(segment
		(start 111.49076 -7.90702)
		(end 112.11306 -7.28472)
		(width 0.1143)
		(layer "B.Cu")
		(net "PMU_PLTRST#")
	)
	(segment
		(start 10.676382 -50.0634)
		(end 14.097 -53.484018)
		(width 0.1143)
		(layer "B.Cu")
		(net "PMU_PLTRST#")
	)
	(segment
		(start 58.2168 -12.40028)
		(end 58.2168 -12.2174)
		(width 0.1143)
		(layer "B.Cu")
		(net "PMU_PLTRST#")
	)
	(segment
		(start 10.2108 -50.0634)
		(end 10.676382 -50.0634)
		(width 0.1143)
		(layer "B.Cu")
		(net "PMU_PLTRST#")
	)
	(segment
		(start 81.961482 -36.749482)
		(end 83.384898 -36.749482)
		(width 0.0889)
		(layer "In2.Cu")
		(net "PMU_PLTRST#")
	)
	(segment
		(start 83.235292 -38.325044)
		(end 78.687168 -38.325044)
		(width 0.0889)
		(layer "In2.Cu")
		(net "PMU_PLTRST#")
	)
	(segment
		(start 82.378042 -14.621256)
		(end 82.378042 -14.995144)
		(width 0.0889)
		(layer "In2.Cu")
		(net "PMU_PLTRST#")
	)
	(segment
		(start 80.61325 -24.906986)
		(end 80.61325 -25.680416)
		(width 0.0889)
		(layer "In2.Cu")
		(net "PMU_PLTRST#")
	)
	(segment
		(start 78.687168 -38.325044)
		(end 77.968094 -39.044118)
		(width 0.0889)
		(layer "In2.Cu")
		(net "PMU_PLTRST#")
	)
	(segment
		(start 80.164432 -24.458168)
		(end 80.61325 -24.906986)
		(width 0.0889)
		(layer "In2.Cu")
		(net "PMU_PLTRST#")
	)
	(segment
		(start 78.560168 -24.458168)
		(end 80.164432 -24.458168)
		(width 0.0889)
		(layer "In2.Cu")
		(net "PMU_PLTRST#")
	)
	(segment
		(start 81.451958 -36.239958)
		(end 81.961482 -36.749482)
		(width 0.0889)
		(layer "In2.Cu")
		(net "PMU_PLTRST#")
	)
	(segment
		(start 83.384898 -36.749482)
		(end 83.596734 -36.961318)
		(width 0.0889)
		(layer "In2.Cu")
		(net "PMU_PLTRST#")
	)
	(segment
		(start 83.596734 -36.961318)
		(end 83.596734 -37.963602)
		(width 0.0889)
		(layer "In2.Cu")
		(net "PMU_PLTRST#")
	)
	(segment
		(start 82.378042 -14.995144)
		(end 82.114136 -15.25905)
		(width 0.0889)
		(layer "In2.Cu")
		(net "PMU_PLTRST#")
	)
	(segment
		(start 80.61325 -25.680416)
		(end 79.74965 -26.544016)
		(width 0.0889)
		(layer "In2.Cu")
		(net "PMU_PLTRST#")
	)
	(segment
		(start 79.74965 -33.11144)
		(end 81.451958 -34.813748)
		(width 0.0889)
		(layer "In2.Cu")
		(net "PMU_PLTRST#")
	)
	(segment
		(start 82.114136 -15.25905)
		(end 81.877154 -15.25905)
		(width 0.0889)
		(layer "In2.Cu")
		(net "PMU_PLTRST#")
	)
	(segment
		(start 79.74965 -26.544016)
		(end 79.74965 -33.11144)
		(width 0.0889)
		(layer "In2.Cu")
		(net "PMU_PLTRST#")
	)
	(segment
		(start 81.451958 -34.813748)
		(end 81.451958 -36.239958)
		(width 0.0889)
		(layer "In2.Cu")
		(net "PMU_PLTRST#")
	)
	(segment
		(start 76.73975 -22.63775)
		(end 78.560168 -24.458168)
		(width 0.0889)
		(layer "In2.Cu")
		(net "PMU_PLTRST#")
	)
	(segment
		(start 82.101944 -14.35735)
		(end 82.114136 -14.35735)
		(width 0.0889)
		(layer "In2.Cu")
		(net "PMU_PLTRST#")
	)
	(segment
		(start 81.877154 -15.25905)
		(end 76.73975 -20.396454)
		(width 0.0889)
		(layer "In2.Cu")
		(net "PMU_PLTRST#")
	)
	(segment
		(start 81.867756 -13.649452)
		(end 81.867756 -14.123162)
		(width 0.0889)
		(layer "In2.Cu")
		(net "PMU_PLTRST#")
	)
	(segment
		(start 83.596734 -37.963602)
		(end 83.235292 -38.325044)
		(width 0.0889)
		(layer "In2.Cu")
		(net "PMU_PLTRST#")
	)
	(segment
		(start 76.73975 -20.396454)
		(end 76.73975 -22.63775)
		(width 0.0889)
		(layer "In2.Cu")
		(net "PMU_PLTRST#")
	)
	(segment
		(start 82.114136 -14.35735)
		(end 82.378042 -14.621256)
		(width 0.0889)
		(layer "In2.Cu")
		(net "PMU_PLTRST#")
	)
	(segment
		(start 83.204558 -12.31265)
		(end 81.867756 -13.649452)
		(width 0.0889)
		(layer "In2.Cu")
		(net "PMU_PLTRST#")
	)
	(segment
		(start 81.867756 -14.123162)
		(end 82.101944 -14.35735)
		(width 0.0889)
		(layer "In2.Cu")
		(net "PMU_PLTRST#")
	)
	(segment
		(start 76.767182 -8.255)
		(end 77.6478 -9.135618)
		(width 0.0889)
		(layer "In7.Cu")
		(net "PMU_PLTRST#")
	)
	(segment
		(start 31.7754 -14.854682)
		(end 33.155636 -13.474446)
		(width 0.0889)
		(layer "In7.Cu")
		(net "PMU_PLTRST#")
	)
	(segment
		(start 28.53055 -33.37941)
		(end 28.28925 -33.13811)
		(width 0.0889)
		(layer "In7.Cu")
		(net "PMU_PLTRST#")
	)
	(segment
		(start 12.0904 -46.8376)
		(end 16.1036 -42.8244)
		(width 0.0889)
		(layer "In7.Cu")
		(net "PMU_PLTRST#")
	)
	(segment
		(start 33.155636 -13.474446)
		(end 33.61817 -13.474446)
		(width 0.0889)
		(layer "In7.Cu")
		(net "PMU_PLTRST#")
	)
	(segment
		(start 81.3816 -11.8618)
		(end 82.753708 -11.8618)
		(width 0.0889)
		(layer "In7.Cu")
		(net "PMU_PLTRST#")
	)
	(segment
		(start 9.4996 -47.5234)
		(end 10.1854 -46.8376)
		(width 0.0889)
		(layer "In7.Cu")
		(net "PMU_PLTRST#")
	)
	(segment
		(start 77.6478 -9.135618)
		(end 77.6478 -9.8552)
		(width 0.0889)
		(layer "In7.Cu")
		(net "PMU_PLTRST#")
	)
	(segment
		(start 22.484588 -42.8244)
		(end 23.132796 -42.176192)
		(width 0.0889)
		(layer "In7.Cu")
		(net "PMU_PLTRST#")
	)
	(segment
		(start 82.753708 -11.8618)
		(end 83.204558 -12.31265)
		(width 0.0889)
		(layer "In7.Cu")
		(net "PMU_PLTRST#")
	)
	(segment
		(start 31.7754 -15.861284)
		(end 31.7754 -14.854682)
		(width 0.0889)
		(layer "In7.Cu")
		(net "PMU_PLTRST#")
	)
	(segment
		(start 28.28925 -33.13811)
		(end 28.28925 -19.347434)
		(width 0.0889)
		(layer "In7.Cu")
		(net "PMU_PLTRST#")
	)
	(segment
		(start 80.6831 -11.1633)
		(end 81.3816 -11.8618)
		(width 0.0889)
		(layer "In7.Cu")
		(net "PMU_PLTRST#")
	)
	(segment
		(start 23.132796 -40.113458)
		(end 23.495254 -39.751)
		(width 0.0889)
		(layer "In7.Cu")
		(net "PMU_PLTRST#")
	)
	(segment
		(start 10.1854 -46.8376)
		(end 12.0904 -46.8376)
		(width 0.0889)
		(layer "In7.Cu")
		(net "PMU_PLTRST#")
	)
	(segment
		(start 23.495254 -39.751)
		(end 28.53055 -34.715196)
		(width 0.0889)
		(layer "In7.Cu")
		(net "PMU_PLTRST#")
	)
	(segment
		(start 37.294058 -10.8458)
		(end 54.9402 -10.8458)
		(width 0.0889)
		(layer "In7.Cu")
		(net "PMU_PLTRST#")
	)
	(segment
		(start 9.4996 -49.4792)
		(end 9.4996 -47.5234)
		(width 0.0889)
		(layer "In7.Cu")
		(net "PMU_PLTRST#")
	)
	(segment
		(start 33.61817 -13.474446)
		(end 33.618424 -13.4747)
		(width 0.0889)
		(layer "In7.Cu")
		(net "PMU_PLTRST#")
	)
	(segment
		(start 23.132796 -42.176192)
		(end 23.132796 -40.113458)
		(width 0.0889)
		(layer "In7.Cu")
		(net "PMU_PLTRST#")
	)
	(segment
		(start 35.7886 -12.550394)
		(end 35.7886 -12.351258)
		(width 0.0889)
		(layer "In7.Cu")
		(net "PMU_PLTRST#")
	)
	(segment
		(start 57.531 -8.255)
		(end 76.767182 -8.255)
		(width 0.0889)
		(layer "In7.Cu")
		(net "PMU_PLTRST#")
	)
	(segment
		(start 54.9402 -10.8458)
		(end 55.8546 -9.9314)
		(width 0.0889)
		(layer "In7.Cu")
		(net "PMU_PLTRST#")
	)
	(segment
		(start 55.8546 -9.9314)
		(end 57.531 -8.255)
		(width 0.0889)
		(layer "In7.Cu")
		(net "PMU_PLTRST#")
	)
	(segment
		(start 28.53055 -34.715196)
		(end 28.53055 -33.37941)
		(width 0.0889)
		(layer "In7.Cu")
		(net "PMU_PLTRST#")
	)
	(segment
		(start 9.6266 -49.6062)
		(end 9.4996 -49.4792)
		(width 0.0889)
		(layer "In7.Cu")
		(net "PMU_PLTRST#")
	)
	(segment
		(start 28.28925 -19.347434)
		(end 31.7754 -15.861284)
		(width 0.0889)
		(layer "In7.Cu")
		(net "PMU_PLTRST#")
	)
	(segment
		(start 77.6478 -9.8552)
		(end 78.9559 -11.1633)
		(width 0.0889)
		(layer "In7.Cu")
		(net "PMU_PLTRST#")
	)
	(segment
		(start 78.9559 -11.1633)
		(end 80.6831 -11.1633)
		(width 0.0889)
		(layer "In7.Cu")
		(net "PMU_PLTRST#")
	)
	(segment
		(start 34.864294 -13.4747)
		(end 35.7886 -12.550394)
		(width 0.0889)
		(layer "In7.Cu")
		(net "PMU_PLTRST#")
	)
	(segment
		(start 35.7886 -12.351258)
		(end 37.294058 -10.8458)
		(width 0.0889)
		(layer "In7.Cu")
		(net "PMU_PLTRST#")
	)
	(segment
		(start 33.618424 -13.4747)
		(end 34.864294 -13.4747)
		(width 0.0889)
		(layer "In7.Cu")
		(net "PMU_PLTRST#")
	)
	(segment
		(start 16.1036 -42.8244)
		(end 22.484588 -42.8244)
		(width 0.0889)
		(layer "In7.Cu")
		(net "PMU_PLTRST#")
	)
	(segment
		(start 105.401364 -14.081506)
		(end 107.89285 -11.59002)
		(width 0.0889)
		(layer "In9.Cu")
		(net "PMU_PLTRST#")
	)
	(segment
		(start 107.89285 -11.59002)
		(end 107.89285 -10.065512)
		(width 0.0889)
		(layer "In9.Cu")
		(net "PMU_PLTRST#")
	)
	(segment
		(start 96.152462 -14.081506)
		(end 105.401364 -14.081506)
		(width 0.0889)
		(layer "In9.Cu")
		(net "PMU_PLTRST#")
	)
	(segment
		(start 88.35136 -13.4874)
		(end 88.992456 -12.846304)
		(width 0.0889)
		(layer "In9.Cu")
		(net "PMU_PLTRST#")
	)
	(segment
		(start 107.381294 -9.553956)
		(end 107.381294 -4.476496)
		(width 0.0889)
		(layer "In9.Cu")
		(net "PMU_PLTRST#")
	)
	(segment
		(start 107.381294 -4.476496)
		(end 107.569 -4.28879)
		(width 0.0889)
		(layer "In9.Cu")
		(net "PMU_PLTRST#")
	)
	(segment
		(start 95.755206 -13.68425)
		(end 96.152462 -14.081506)
		(width 0.0889)
		(layer "In9.Cu")
		(net "PMU_PLTRST#")
	)
	(segment
		(start 88.992456 -12.846304)
		(end 90.382344 -12.846304)
		(width 0.0889)
		(layer "In9.Cu")
		(net "PMU_PLTRST#")
	)
	(segment
		(start 83.204558 -12.31265)
		(end 83.512406 -12.31265)
		(width 0.0889)
		(layer "In9.Cu")
		(net "PMU_PLTRST#")
	)
	(segment
		(start 91.22029 -13.68425)
		(end 95.755206 -13.68425)
		(width 0.0889)
		(layer "In9.Cu")
		(net "PMU_PLTRST#")
	)
	(segment
		(start 84.687156 -13.4874)
		(end 88.35136 -13.4874)
		(width 0.0889)
		(layer "In9.Cu")
		(net "PMU_PLTRST#")
	)
	(segment
		(start 83.512406 -12.31265)
		(end 84.687156 -13.4874)
		(width 0.0889)
		(layer "In9.Cu")
		(net "PMU_PLTRST#")
	)
	(segment
		(start 107.89285 -10.065512)
		(end 107.381294 -9.553956)
		(width 0.0889)
		(layer "In9.Cu")
		(net "PMU_PLTRST#")
	)
	(segment
		(start 90.382344 -12.846304)
		(end 91.22029 -13.68425)
		(width 0.0889)
		(layer "In9.Cu")
		(net "PMU_PLTRST#")
	)
	(segment
		(start 88.219788 -36.581588)
		(end 87.9602 -36.322)
		(width 0.1143)
		(layer "F.Cu")
		(net "PMU_PWRBTN_R#")
	)
	(segment
		(start 47.129954 -27.20594)
		(end 46.69536 -27.640534)
		(width 0.1143)
		(layer "F.Cu")
		(net "PMU_PWRBTN_R#")
	)
	(segment
		(start 88.219788 -36.743894)
		(end 88.219788 -36.581588)
		(width 0.1143)
		(layer "F.Cu")
		(net "PMU_PWRBTN_R#")
	)
	(segment
		(start 46.69536 -27.640534)
		(end 46.69536 -29.80436)
		(width 0.1143)
		(layer "F.Cu")
		(net "PMU_PWRBTN_R#")
	)
	(segment
		(start 48.032924 -24.69769)
		(end 47.129954 -25.60066)
		(width 0.1143)
		(layer "F.Cu")
		(net "PMU_PWRBTN_R#")
	)
	(segment
		(start 47.129954 -25.60066)
		(end 47.129954 -27.20594)
		(width 0.1143)
		(layer "F.Cu")
		(net "PMU_PWRBTN_R#")
	)
	(via
		(at 65.99428 -26.277316)
		(size 0.508)
		(drill 0.254)
		(layers "F.Cu" "B.Cu")
		(net "PMU_PWRBTN_R#")
	)
	(via
		(at 87.9602 -36.322)
		(size 0.4318)
		(drill 0.2032)
		(layers "F.Cu" "B.Cu")
		(net "PMU_PWRBTN_R#")
	)
	(via
		(at 78.486 -29.1338)
		(size 0.4318)
		(drill 0.2032)
		(layers "F.Cu" "B.Cu")
		(net "PMU_PWRBTN_R#")
	)
	(via
		(at 68.8848 -26.4922)
		(size 0.7112)
		(drill 0.3556)
		(layers "F.Cu" "B.Cu")
		(net "PMU_PWRBTN_R#")
	)
	(via
		(at 48.032924 -24.69769)
		(size 0.508)
		(drill 0.254)
		(layers "F.Cu" "B.Cu")
		(net "PMU_PWRBTN_R#")
	)
	(segment
		(start 71.280274 -27.76855)
		(end 70.38975 -27.76855)
		(width 0.1143)
		(layer "B.Cu")
		(net "PMU_PWRBTN_R#")
	)
	(segment
		(start 65.99428 -26.277316)
		(end 66.209164 -26.4922)
		(width 0.1143)
		(layer "B.Cu")
		(net "PMU_PWRBTN_R#")
	)
	(segment
		(start 78.486 -28.982416)
		(end 75.729338 -26.225754)
		(width 0.1143)
		(layer "B.Cu")
		(net "PMU_PWRBTN_R#")
	)
	(segment
		(start 69.1134 -26.4922)
		(end 68.8848 -26.4922)
		(width 0.1143)
		(layer "B.Cu")
		(net "PMU_PWRBTN_R#")
	)
	(segment
		(start 70.38975 -27.76855)
		(end 69.1134 -26.4922)
		(width 0.1143)
		(layer "B.Cu")
		(net "PMU_PWRBTN_R#")
	)
	(segment
		(start 66.209164 -26.4922)
		(end 68.8848 -26.4922)
		(width 0.1143)
		(layer "B.Cu")
		(net "PMU_PWRBTN_R#")
	)
	(segment
		(start 75.729338 -26.225754)
		(end 72.82307 -26.225754)
		(width 0.1143)
		(layer "B.Cu")
		(net "PMU_PWRBTN_R#")
	)
	(segment
		(start 72.82307 -26.225754)
		(end 71.280274 -27.76855)
		(width 0.1143)
		(layer "B.Cu")
		(net "PMU_PWRBTN_R#")
	)
	(segment
		(start 78.486 -29.1338)
		(end 78.486 -28.982416)
		(width 0.1143)
		(layer "B.Cu")
		(net "PMU_PWRBTN_R#")
	)
	(segment
		(start 48.032924 -24.69769)
		(end 49.662334 -26.3271)
		(width 0.0889)
		(layer "In7.Cu")
		(net "PMU_PWRBTN_R#")
	)
	(segment
		(start 87.9602 -36.322)
		(end 87.9602 -35.936428)
		(width 0.0889)
		(layer "In7.Cu")
		(net "PMU_PWRBTN_R#")
	)
	(segment
		(start 82.092038 -31.520638)
		(end 79.3496 -28.7782)
		(width 0.0889)
		(layer "In7.Cu")
		(net "PMU_PWRBTN_R#")
	)
	(segment
		(start 86.106 -33.401)
		(end 84.963 -33.401)
		(width 0.0889)
		(layer "In7.Cu")
		(net "PMU_PWRBTN_R#")
	)
	(segment
		(start 62.16015 -26.4033)
		(end 65.868296 -26.4033)
		(width 0.0889)
		(layer "In7.Cu")
		(net "PMU_PWRBTN_R#")
	)
	(segment
		(start 84.963 -33.401)
		(end 84.1248 -32.5628)
		(width 0.0889)
		(layer "In7.Cu")
		(net "PMU_PWRBTN_R#")
	)
	(segment
		(start 58.048144 -25.2476)
		(end 58.194194 -25.10155)
		(width 0.0889)
		(layer "In7.Cu")
		(net "PMU_PWRBTN_R#")
	)
	(segment
		(start 78.8416 -28.7782)
		(end 78.486 -29.1338)
		(width 0.0889)
		(layer "In7.Cu")
		(net "PMU_PWRBTN_R#")
	)
	(segment
		(start 87.383112 -33.778698)
		(end 87.196676 -33.592262)
		(width 0.0889)
		(layer "In7.Cu")
		(net "PMU_PWRBTN_R#")
	)
	(segment
		(start 87.383112 -35.330384)
		(end 87.383112 -33.778698)
		(width 0.0889)
		(layer "In7.Cu")
		(net "PMU_PWRBTN_R#")
	)
	(segment
		(start 53.806598 -26.3271)
		(end 54.886098 -25.2476)
		(width 0.0889)
		(layer "In7.Cu")
		(net "PMU_PWRBTN_R#")
	)
	(segment
		(start 82.66557 -31.520638)
		(end 82.092038 -31.520638)
		(width 0.0889)
		(layer "In7.Cu")
		(net "PMU_PWRBTN_R#")
	)
	(segment
		(start 87.9602 -35.936428)
		(end 87.765382 -35.74161)
		(width 0.0889)
		(layer "In7.Cu")
		(net "PMU_PWRBTN_R#")
	)
	(segment
		(start 58.194194 -25.10155)
		(end 60.8584 -25.10155)
		(width 0.0889)
		(layer "In7.Cu")
		(net "PMU_PWRBTN_R#")
	)
	(segment
		(start 87.765382 -35.712654)
		(end 87.383112 -35.330384)
		(width 0.0889)
		(layer "In7.Cu")
		(net "PMU_PWRBTN_R#")
	)
	(segment
		(start 83.707732 -32.5628)
		(end 82.66557 -31.520638)
		(width 0.0889)
		(layer "In7.Cu")
		(net "PMU_PWRBTN_R#")
	)
	(segment
		(start 84.1248 -32.5628)
		(end 83.707732 -32.5628)
		(width 0.0889)
		(layer "In7.Cu")
		(net "PMU_PWRBTN_R#")
	)
	(segment
		(start 79.3496 -28.7782)
		(end 78.8416 -28.7782)
		(width 0.0889)
		(layer "In7.Cu")
		(net "PMU_PWRBTN_R#")
	)
	(segment
		(start 65.868296 -26.4033)
		(end 65.99428 -26.277316)
		(width 0.0889)
		(layer "In7.Cu")
		(net "PMU_PWRBTN_R#")
	)
	(segment
		(start 54.886098 -25.2476)
		(end 58.048144 -25.2476)
		(width 0.0889)
		(layer "In7.Cu")
		(net "PMU_PWRBTN_R#")
	)
	(segment
		(start 86.297262 -33.592262)
		(end 86.106 -33.401)
		(width 0.0889)
		(layer "In7.Cu")
		(net "PMU_PWRBTN_R#")
	)
	(segment
		(start 87.765382 -35.74161)
		(end 87.765382 -35.712654)
		(width 0.0889)
		(layer "In7.Cu")
		(net "PMU_PWRBTN_R#")
	)
	(segment
		(start 49.662334 -26.3271)
		(end 53.806598 -26.3271)
		(width 0.0889)
		(layer "In7.Cu")
		(net "PMU_PWRBTN_R#")
	)
	(segment
		(start 60.8584 -25.10155)
		(end 62.16015 -26.4033)
		(width 0.0889)
		(layer "In7.Cu")
		(net "PMU_PWRBTN_R#")
	)
	(segment
		(start 87.196676 -33.592262)
		(end 86.297262 -33.592262)
		(width 0.0889)
		(layer "In7.Cu")
		(net "PMU_PWRBTN_R#")
	)
	(segment
		(start 87.503 -35.9918)
		(end 87.503 -35.794442)
		(width 0.1143)
		(layer "F.Cu")
		(net "PMU_SLP_LAN#")
	)
	(segment
		(start 87.503 -35.794442)
		(end 87.838788 -35.458654)
		(width 0.1143)
		(layer "F.Cu")
		(net "PMU_SLP_LAN#")
	)
	(via
		(at 86.9442 -36.4236)
		(size 0.7112)
		(drill 0.3556)
		(layers "F.Cu" "B.Cu")
		(net "PMU_SLP_LAN#")
	)
	(via
		(at 87.503 -35.9918)
		(size 0.4318)
		(drill 0.2032)
		(layers "F.Cu" "B.Cu")
		(net "PMU_SLP_LAN#")
	)
	(segment
		(start 86.9442 -36.4236)
		(end 87.0712 -36.4236)
		(width 0.1143)
		(layer "B.Cu")
		(net "PMU_SLP_LAN#")
	)
	(segment
		(start 87.503 -35.3822)
		(end 87.503 -35.9918)
		(width 0.1143)
		(layer "B.Cu")
		(net "PMU_SLP_LAN#")
	)
	(segment
		(start 87.0712 -36.4236)
		(end 87.503 -35.9918)
		(width 0.1143)
		(layer "B.Cu")
		(net "PMU_SLP_LAN#")
	)
	(segment
		(start 81.836768 -37.884354)
		(end 81.87944 -37.927026)
		(width 0.1143)
		(layer "F.Cu")
		(net "PMU_PLTRST_R#")
	)
	(segment
		(start 81.87944 -37.927026)
		(end 82.6008 -37.927026)
		(width 0.1143)
		(layer "F.Cu")
		(net "PMU_PLTRST_R#")
	)
	(via
		(at 79.9592 -38.521894)
		(size 0.7112)
		(drill 0.3556)
		(layers "F.Cu" "B.Cu")
		(net "PMU_PLTRST_R#")
	)
	(via
		(at 82.6008 -37.927026)
		(size 0.4318)
		(drill 0.2032)
		(layers "F.Cu" "B.Cu")
		(net "PMU_PLTRST_R#")
	)
	(segment
		(start 79.9592 -38.521894)
		(end 80.170528 -38.310566)
		(width 0.1143)
		(layer "B.Cu")
		(net "PMU_PLTRST_R#")
	)
	(segment
		(start 81.570068 -38.0238)
		(end 82.504026 -38.0238)
		(width 0.1143)
		(layer "B.Cu")
		(net "PMU_PLTRST_R#")
	)
	(segment
		(start 82.504026 -38.0238)
		(end 82.6008 -37.927026)
		(width 0.1143)
		(layer "B.Cu")
		(net "PMU_PLTRST_R#")
	)
	(segment
		(start 79.0448 -38.4302)
		(end 79.136494 -38.521894)
		(width 0.1143)
		(layer "B.Cu")
		(net "PMU_PLTRST_R#")
	)
	(segment
		(start 79.136494 -38.521894)
		(end 79.9592 -38.521894)
		(width 0.1143)
		(layer "B.Cu")
		(net "PMU_PLTRST_R#")
	)
	(segment
		(start 80.170528 -38.310566)
		(end 81.283302 -38.310566)
		(width 0.1143)
		(layer "B.Cu")
		(net "PMU_PLTRST_R#")
	)
	(segment
		(start 81.283302 -38.310566)
		(end 81.570068 -38.0238)
		(width 0.1143)
		(layer "B.Cu")
		(net "PMU_PLTRST_R#")
	)
	(segment
		(start 86.253574 -36.363402)
		(end 86.634066 -36.743894)
		(width 0.1143)
		(layer "F.Cu")
		(net "PMU_SLP_DDRVTT#")
	)
	(segment
		(start 86.230714 -36.363402)
		(end 86.253574 -36.363402)
		(width 0.1143)
		(layer "F.Cu")
		(net "PMU_SLP_DDRVTT#")
	)
	(segment
		(start 86.634066 -36.743894)
		(end 86.695788 -36.743894)
		(width 0.1143)
		(layer "F.Cu")
		(net "PMU_SLP_DDRVTT#")
	)
	(via
		(at 86.230714 -36.363402)
		(size 0.4318)
		(drill 0.2032)
		(layers "F.Cu" "B.Cu")
		(net "PMU_SLP_DDRVTT#")
	)
	(via
		(at 71.49465 -29.58465)
		(size 0.508)
		(drill 0.254)
		(layers "F.Cu" "B.Cu")
		(net "PMU_SLP_DDRVTT#")
	)
	(via
		(at 70.817994 -30.756606)
		(size 0.7112)
		(drill 0.3556)
		(layers "F.Cu" "B.Cu")
		(net "PMU_SLP_DDRVTT#")
	)
	(segment
		(start 87.503 -34.5186)
		(end 87.075518 -34.946082)
		(width 0.1143)
		(layer "B.Cu")
		(net "PMU_SLP_DDRVTT#")
	)
	(segment
		(start 66.7004 -34.459164)
		(end 67.5386 -35.297364)
		(width 0.1143)
		(layer "B.Cu")
		(net "PMU_SLP_DDRVTT#")
	)
	(segment
		(start 69.031358 -31.369)
		(end 67.817492 -31.369)
		(width 0.1143)
		(layer "B.Cu")
		(net "PMU_SLP_DDRVTT#")
	)
	(segment
		(start 71.49465 -30.07995)
		(end 70.817994 -30.756606)
		(width 0.1143)
		(layer "B.Cu")
		(net "PMU_SLP_DDRVTT#")
	)
	(segment
		(start 67.5386 -36.046156)
		(end 66.5988 -36.985956)
		(width 0.1143)
		(layer "B.Cu")
		(net "PMU_SLP_DDRVTT#")
	)
	(segment
		(start 87.075518 -34.946082)
		(end 87.075518 -35.27806)
		(width 0.1143)
		(layer "B.Cu")
		(net "PMU_SLP_DDRVTT#")
	)
	(segment
		(start 67.5386 -35.297364)
		(end 67.5386 -36.046156)
		(width 0.1143)
		(layer "B.Cu")
		(net "PMU_SLP_DDRVTT#")
	)
	(segment
		(start 69.643752 -30.756606)
		(end 69.031358 -31.369)
		(width 0.1143)
		(layer "B.Cu")
		(net "PMU_SLP_DDRVTT#")
	)
	(segment
		(start 67.817492 -31.369)
		(end 66.7004 -32.487108)
		(width 0.1143)
		(layer "B.Cu")
		(net "PMU_SLP_DDRVTT#")
	)
	(segment
		(start 87.075518 -35.27806)
		(end 86.230714 -36.122864)
		(width 0.1143)
		(layer "B.Cu")
		(net "PMU_SLP_DDRVTT#")
	)
	(segment
		(start 86.230714 -36.122864)
		(end 86.230714 -36.363402)
		(width 0.1143)
		(layer "B.Cu")
		(net "PMU_SLP_DDRVTT#")
	)
	(segment
		(start 66.7004 -32.487108)
		(end 66.7004 -34.459164)
		(width 0.1143)
		(layer "B.Cu")
		(net "PMU_SLP_DDRVTT#")
	)
	(segment
		(start 66.5988 -37.973)
		(end 66.5988 -37.1602)
		(width 0.1143)
		(layer "B.Cu")
		(net "PMU_SLP_DDRVTT#")
	)
	(segment
		(start 66.5988 -36.985956)
		(end 66.5988 -37.1602)
		(width 0.1143)
		(layer "B.Cu")
		(net "PMU_SLP_DDRVTT#")
	)
	(segment
		(start 70.817994 -30.756606)
		(end 69.643752 -30.756606)
		(width 0.1143)
		(layer "B.Cu")
		(net "PMU_SLP_DDRVTT#")
	)
	(segment
		(start 67.0814 -38.4556)
		(end 66.5988 -37.973)
		(width 0.1143)
		(layer "B.Cu")
		(net "PMU_SLP_DDRVTT#")
	)
	(segment
		(start 71.49465 -29.58465)
		(end 71.49465 -30.07995)
		(width 0.1143)
		(layer "B.Cu")
		(net "PMU_SLP_DDRVTT#")
	)
	(segment
		(start 71.86295 -29.21635)
		(end 71.49465 -29.58465)
		(width 0.0889)
		(layer "In7.Cu")
		(net "PMU_SLP_DDRVTT#")
	)
	(segment
		(start 79.6544 -35.6362)
		(end 78.390242 -35.6362)
		(width 0.0889)
		(layer "In7.Cu")
		(net "PMU_SLP_DDRVTT#")
	)
	(segment
		(start 73.796906 -29.21635)
		(end 71.86295 -29.21635)
		(width 0.0889)
		(layer "In7.Cu")
		(net "PMU_SLP_DDRVTT#")
	)
	(segment
		(start 76.6826 -32.102044)
		(end 73.796906 -29.21635)
		(width 0.0889)
		(layer "In7.Cu")
		(net "PMU_SLP_DDRVTT#")
	)
	(segment
		(start 76.6826 -33.928558)
		(end 76.6826 -32.102044)
		(width 0.0889)
		(layer "In7.Cu")
		(net "PMU_SLP_DDRVTT#")
	)
	(segment
		(start 86.230714 -36.363402)
		(end 86.224618 -36.363402)
		(width 0.0889)
		(layer "In7.Cu")
		(net "PMU_SLP_DDRVTT#")
	)
	(segment
		(start 86.224618 -36.363402)
		(end 85.92312 -36.6649)
		(width 0.0889)
		(layer "In7.Cu")
		(net "PMU_SLP_DDRVTT#")
	)
	(segment
		(start 78.390242 -35.6362)
		(end 76.6826 -33.928558)
		(width 0.0889)
		(layer "In7.Cu")
		(net "PMU_SLP_DDRVTT#")
	)
	(segment
		(start 85.92312 -36.6649)
		(end 80.6831 -36.6649)
		(width 0.0889)
		(layer "In7.Cu")
		(net "PMU_SLP_DDRVTT#")
	)
	(segment
		(start 80.6831 -36.6649)
		(end 79.6544 -35.6362)
		(width 0.0889)
		(layer "In7.Cu")
		(net "PMU_SLP_DDRVTT#")
	)
	(segment
		(start 80.546448 -34.643314)
		(end 80.171544 -34.26841)
		(width 0.1143)
		(layer "F.Cu")
		(net "PMU_SLP_S45#")
	)
	(segment
		(start 143.70939 -25.87879)
		(end 135.58139 -25.87879)
		(width 0.1143)
		(layer "F.Cu")
		(net "PMU_SLP_S45#")
	)
	(segment
		(start 80.171544 -34.26841)
		(end 79.325724 -34.26841)
		(width 0.1143)
		(layer "F.Cu")
		(net "PMU_SLP_S45#")
	)
	(segment
		(start 133.768846 -24.74595)
		(end 133.6167 -24.593804)
		(width 0.1143)
		(layer "F.Cu")
		(net "PMU_SLP_S45#")
	)
	(segment
		(start 74.603356 -30.734)
		(end 74.4728 -30.734)
		(width 0.1143)
		(layer "F.Cu")
		(net "PMU_SLP_S45#")
	)
	(segment
		(start 130.3909 -22.71522)
		(end 130.3909 -21.532596)
		(width 0.1143)
		(layer "F.Cu")
		(net "PMU_SLP_S45#")
	)
	(segment
		(start 133.6167 -24.593804)
		(end 133.6167 -24.400764)
		(width 0.1143)
		(layer "F.Cu")
		(net "PMU_SLP_S45#")
	)
	(segment
		(start 131.831334 -24.1554)
		(end 130.3909 -22.71522)
		(width 0.1143)
		(layer "F.Cu")
		(net "PMU_SLP_S45#")
	)
	(segment
		(start 133.6167 -24.400764)
		(end 133.371336 -24.1554)
		(width 0.1143)
		(layer "F.Cu")
		(net "PMU_SLP_S45#")
	)
	(segment
		(start 180.797962 -36.449)
		(end 180.213 -36.449)
		(width 0.1143)
		(layer "F.Cu")
		(net "PMU_SLP_S45#")
	)
	(segment
		(start 130.93065 -14.863318)
		(end 129.54381 -13.476478)
		(width 0.1143)
		(layer "F.Cu")
		(net "PMU_SLP_S45#")
	)
	(segment
		(start 77.026262 -33.156906)
		(end 74.603356 -30.734)
		(width 0.1143)
		(layer "F.Cu")
		(net "PMU_SLP_S45#")
	)
	(segment
		(start 112.339374 -2.662174)
		(end 111.035846 -2.662174)
		(width 0.1143)
		(layer "F.Cu")
		(net "PMU_SLP_S45#")
	)
	(segment
		(start 149.5044 -31.6738)
		(end 143.70939 -25.87879)
		(width 0.1143)
		(layer "F.Cu")
		(net "PMU_SLP_S45#")
	)
	(segment
		(start 79.106268 -34.048954)
		(end 79.106268 -33.726374)
		(width 0.1143)
		(layer "F.Cu")
		(net "PMU_SLP_S45#")
	)
	(segment
		(start 115.29441 -3.8227)
		(end 113.609628 -3.8227)
		(width 0.1143)
		(layer "F.Cu")
		(net "PMU_SLP_S45#")
	)
	(segment
		(start 78.194916 -33.156906)
		(end 77.026262 -33.156906)
		(width 0.1143)
		(layer "F.Cu")
		(net "PMU_SLP_S45#")
	)
	(segment
		(start 134.44855 -24.74595)
		(end 133.768846 -24.74595)
		(width 0.1143)
		(layer "F.Cu")
		(net "PMU_SLP_S45#")
	)
	(segment
		(start 113.603278 -3.81635)
		(end 113.49355 -3.81635)
		(width 0.1143)
		(layer "F.Cu")
		(net "PMU_SLP_S45#")
	)
	(segment
		(start 181.61 -35.6362)
		(end 180.797962 -36.448238)
		(width 0.1143)
		(layer "F.Cu")
		(net "PMU_SLP_S45#")
	)
	(segment
		(start 129.54381 -13.476478)
		(end 127.478536 -13.476478)
		(width 0.1143)
		(layer "F.Cu")
		(net "PMU_SLP_S45#")
	)
	(segment
		(start 135.58139 -25.87879)
		(end 134.44855 -24.74595)
		(width 0.1143)
		(layer "F.Cu")
		(net "PMU_SLP_S45#")
	)
	(segment
		(start 74.4728 -30.734)
		(end 74.4728 -29.972)
		(width 0.1143)
		(layer "F.Cu")
		(net "PMU_SLP_S45#")
	)
	(segment
		(start 113.49355 -3.81635)
		(end 112.339374 -2.662174)
		(width 0.1143)
		(layer "F.Cu")
		(net "PMU_SLP_S45#")
	)
	(segment
		(start 111.035846 -2.662174)
		(end 111.013494 -2.639822)
		(width 0.1143)
		(layer "F.Cu")
		(net "PMU_SLP_S45#")
	)
	(segment
		(start 119.456454 -5.454396)
		(end 116.926106 -5.454396)
		(width 0.1143)
		(layer "F.Cu")
		(net "PMU_SLP_S45#")
	)
	(segment
		(start 78.5368 -33.156906)
		(end 78.194916 -33.156906)
		(width 0.1143)
		(layer "F.Cu")
		(net "PMU_SLP_S45#")
	)
	(segment
		(start 130.93065 -20.992846)
		(end 130.93065 -14.863318)
		(width 0.1143)
		(layer "F.Cu")
		(net "PMU_SLP_S45#")
	)
	(segment
		(start 130.3909 -21.532596)
		(end 130.93065 -20.992846)
		(width 0.1143)
		(layer "F.Cu")
		(net "PMU_SLP_S45#")
	)
	(segment
		(start 113.609628 -3.8227)
		(end 113.603278 -3.81635)
		(width 0.1143)
		(layer "F.Cu")
		(net "PMU_SLP_S45#")
	)
	(segment
		(start 79.325724 -34.26841)
		(end 79.106268 -34.048954)
		(width 0.1143)
		(layer "F.Cu")
		(net "PMU_SLP_S45#")
	)
	(segment
		(start 116.926106 -5.454396)
		(end 115.29441 -3.8227)
		(width 0.1143)
		(layer "F.Cu")
		(net "PMU_SLP_S45#")
	)
	(segment
		(start 79.106268 -33.726374)
		(end 78.5368 -33.156906)
		(width 0.1143)
		(layer "F.Cu")
		(net "PMU_SLP_S45#")
	)
	(segment
		(start 127.478536 -13.476478)
		(end 119.456454 -5.454396)
		(width 0.1143)
		(layer "F.Cu")
		(net "PMU_SLP_S45#")
	)
	(segment
		(start 180.797962 -36.448238)
		(end 180.797962 -36.449)
		(width 0.1143)
		(layer "F.Cu")
		(net "PMU_SLP_S45#")
	)
	(segment
		(start 133.371336 -24.1554)
		(end 131.831334 -24.1554)
		(width 0.1143)
		(layer "F.Cu")
		(net "PMU_SLP_S45#")
	)
	(via
		(at 149.5044 -31.6738)
		(size 0.508)
		(drill 0.254)
		(layers "F.Cu" "B.Cu")
		(net "PMU_SLP_S45#")
	)
	(via
		(at 177.763932 -33.504632)
		(size 0.7112)
		(drill 0.3556)
		(layers "F.Cu" "B.Cu")
		(net "PMU_SLP_S45#")
	)
	(via
		(at 78.194916 -33.156906)
		(size 0.4318)
		(drill 0.2032)
		(layers "F.Cu" "B.Cu")
		(net "PMU_SLP_S45#")
	)
	(via
		(at 111.013494 -2.639822)
		(size 0.508)
		(drill 0.254)
		(layers "F.Cu" "B.Cu")
		(net "PMU_SLP_S45#")
	)
	(via
		(at 180.213 -36.449)
		(size 0.508)
		(drill 0.254)
		(layers "F.Cu" "B.Cu")
		(net "PMU_SLP_S45#")
	)
	(segment
		(start 180.77815 -35.88385)
		(end 180.213 -36.449)
		(width 0.1143)
		(layer "B.Cu")
		(net "PMU_SLP_S45#")
	)
	(segment
		(start 178.940206 -33.504632)
		(end 180.77815 -35.342576)
		(width 0.1143)
		(layer "B.Cu")
		(net "PMU_SLP_S45#")
	)
	(segment
		(start 139.4968 -30.353)
		(end 140.8176 -31.6738)
		(width 0.1143)
		(layer "B.Cu")
		(net "PMU_SLP_S45#")
	)
	(segment
		(start 151.335232 -33.504632)
		(end 149.5044 -31.6738)
		(width 0.1143)
		(layer "B.Cu")
		(net "PMU_SLP_S45#")
	)
	(segment
		(start 180.77815 -35.342576)
		(end 180.77815 -35.88385)
		(width 0.1143)
		(layer "B.Cu")
		(net "PMU_SLP_S45#")
	)
	(segment
		(start 140.8176 -31.6738)
		(end 149.5044 -31.6738)
		(width 0.1143)
		(layer "B.Cu")
		(net "PMU_SLP_S45#")
	)
	(segment
		(start 177.763932 -33.504632)
		(end 178.940206 -33.504632)
		(width 0.1143)
		(layer "B.Cu")
		(net "PMU_SLP_S45#")
	)
	(segment
		(start 177.763932 -33.504632)
		(end 151.335232 -33.504632)
		(width 0.1143)
		(layer "B.Cu")
		(net "PMU_SLP_S45#")
	)
	(segment
		(start 109.67085 -12.2555)
		(end 106.117644 -15.808706)
		(width 0.0889)
		(layer "In9.Cu")
		(net "PMU_SLP_S45#")
	)
	(segment
		(start 95.436182 -15.808706)
		(end 95.038926 -15.41145)
		(width 0.0889)
		(layer "In9.Cu")
		(net "PMU_SLP_S45#")
	)
	(segment
		(start 77.10805 -31.28645)
		(end 77.928978 -32.107378)
		(width 0.0889)
		(layer "In9.Cu")
		(net "PMU_SLP_S45#")
	)
	(segment
		(start 77.928978 -32.107378)
		(end 77.928978 -32.890968)
		(width 0.0889)
		(layer "In9.Cu")
		(net "PMU_SLP_S45#")
	)
	(segment
		(start 83.085178 -18.010378)
		(end 83.085178 -18.015966)
		(width 0.0889)
		(layer "In9.Cu")
		(net "PMU_SLP_S45#")
	)
	(segment
		(start 106.117644 -15.808706)
		(end 95.436182 -15.808706)
		(width 0.0889)
		(layer "In9.Cu")
		(net "PMU_SLP_S45#")
	)
	(segment
		(start 83.349084 -17.746472)
		(end 83.085178 -18.010378)
		(width 0.0889)
		(layer "In9.Cu")
		(net "PMU_SLP_S45#")
	)
	(segment
		(start 83.853528 -17.746472)
		(end 83.349084 -17.746472)
		(width 0.0889)
		(layer "In9.Cu")
		(net "PMU_SLP_S45#")
	)
	(segment
		(start 77.722222 -28.319476)
		(end 77.10805 -28.933648)
		(width 0.0889)
		(layer "In9.Cu")
		(net "PMU_SLP_S45#")
	)
	(segment
		(start 95.038926 -15.41145)
		(end 86.18855 -15.41145)
		(width 0.0889)
		(layer "In9.Cu")
		(net "PMU_SLP_S45#")
	)
	(segment
		(start 86.18855 -15.41145)
		(end 83.853528 -17.746472)
		(width 0.0889)
		(layer "In9.Cu")
		(net "PMU_SLP_S45#")
	)
	(segment
		(start 111.013494 -2.639822)
		(end 111.013494 -3.388106)
		(width 0.0889)
		(layer "In9.Cu")
		(net "PMU_SLP_S45#")
	)
	(segment
		(start 111.013494 -3.388106)
		(end 109.67085 -4.73075)
		(width 0.0889)
		(layer "In9.Cu")
		(net "PMU_SLP_S45#")
	)
	(segment
		(start 109.67085 -4.73075)
		(end 109.67085 -12.2555)
		(width 0.0889)
		(layer "In9.Cu")
		(net "PMU_SLP_S45#")
	)
	(segment
		(start 78.4606 -25.019)
		(end 77.722222 -25.757378)
		(width 0.0889)
		(layer "In9.Cu")
		(net "PMU_SLP_S45#")
	)
	(segment
		(start 78.4606 -22.640544)
		(end 78.4606 -25.019)
		(width 0.0889)
		(layer "In9.Cu")
		(net "PMU_SLP_S45#")
	)
	(segment
		(start 77.10805 -28.933648)
		(end 77.10805 -31.28645)
		(width 0.0889)
		(layer "In9.Cu")
		(net "PMU_SLP_S45#")
	)
	(segment
		(start 83.085178 -18.015966)
		(end 78.4606 -22.640544)
		(width 0.0889)
		(layer "In9.Cu")
		(net "PMU_SLP_S45#")
	)
	(segment
		(start 77.928978 -32.890968)
		(end 78.194916 -33.156906)
		(width 0.0889)
		(layer "In9.Cu")
		(net "PMU_SLP_S45#")
	)
	(segment
		(start 77.722222 -25.757378)
		(end 77.722222 -28.319476)
		(width 0.0889)
		(layer "In9.Cu")
		(net "PMU_SLP_S45#")
	)
	(segment
		(start 70.6374 -36.9316)
		(end 70.6628 -36.957)
		(width 0.1143)
		(layer "F.Cu")
		(net "PMU_SLP_S3#")
	)
	(segment
		(start 79.186024 -38.336474)
		(end 78.867 -38.01745)
		(width 0.1143)
		(layer "F.Cu")
		(net "PMU_SLP_S3#")
	)
	(segment
		(start 14.533372 -58.3692)
		(end 14.480286 -58.422286)
		(width 0.1143)
		(layer "F.Cu")
		(net "PMU_SLP_S3#")
	)
	(segment
		(start 70.7898 -37.084)
		(end 71.628 -37.084)
		(width 0.1143)
		(layer "F.Cu")
		(net "PMU_SLP_S3#")
	)
	(segment
		(start 15.4178 -58.3692)
		(end 14.533372 -58.3692)
		(width 0.1143)
		(layer "F.Cu")
		(net "PMU_SLP_S3#")
	)
	(segment
		(start 80.043528 -38.336474)
		(end 79.186024 -38.336474)
		(width 0.1143)
		(layer "F.Cu")
		(net "PMU_SLP_S3#")
	)
	(segment
		(start 70.612 -36.0426)
		(end 70.6374 -36.068)
		(width 0.1143)
		(layer "F.Cu")
		(net "PMU_SLP_S3#")
	)
	(segment
		(start 71.755 -37.084)
		(end 71.628 -37.084)
		(width 0.1143)
		(layer "F.Cu")
		(net "PMU_SLP_S3#")
	)
	(segment
		(start 72.68845 -38.01745)
		(end 71.755 -37.084)
		(width 0.1143)
		(layer "F.Cu")
		(net "PMU_SLP_S3#")
	)
	(segment
		(start 70.6374 -36.068)
		(end 70.6374 -36.9316)
		(width 0.1143)
		(layer "F.Cu")
		(net "PMU_SLP_S3#")
	)
	(segment
		(start 78.867 -38.01745)
		(end 72.68845 -38.01745)
		(width 0.1143)
		(layer "F.Cu")
		(net "PMU_SLP_S3#")
	)
	(segment
		(start 70.6628 -36.957)
		(end 70.7898 -37.084)
		(width 0.1143)
		(layer "F.Cu")
		(net "PMU_SLP_S3#")
	)
	(via
		(at 52.796694 -47.88916)
		(size 0.508)
		(drill 0.254)
		(layers "F.Cu" "B.Cu")
		(net "PMU_SLP_S3#")
	)
	(via
		(at 71.628 -37.084)
		(size 0.7112)
		(drill 0.3556)
		(layers "F.Cu" "B.Cu")
		(net "PMU_SLP_S3#")
	)
	(via
		(at 70.612 -36.0426)
		(size 0.508)
		(drill 0.254)
		(layers "F.Cu" "B.Cu")
		(net "PMU_SLP_S3#")
	)
	(via
		(at 14.480286 -58.422286)
		(size 0.508)
		(drill 0.254)
		(layers "F.Cu" "B.Cu")
		(net "PMU_SLP_S3#")
	)
	(segment
		(start 70.7644 -37.0586)
		(end 70.7644 -36.195)
		(width 0.1143)
		(layer "B.Cu")
		(net "PMU_SLP_S3#")
	)
	(segment
		(start 70.7644 -36.195)
		(end 70.612 -36.0426)
		(width 0.1143)
		(layer "B.Cu")
		(net "PMU_SLP_S3#")
	)
	(segment
		(start 59.824874 -42.09542)
		(end 58.97499 -42.09542)
		(width 0.0889)
		(layer "In4.Cu")
		(net "PMU_SLP_S3#")
	)
	(segment
		(start 58.23077 -43.530012)
		(end 57.064148 -44.696634)
		(width 0.0889)
		(layer "In4.Cu")
		(net "PMU_SLP_S3#")
	)
	(segment
		(start 58.23077 -43.528996)
		(end 58.23077 -43.530012)
		(width 0.0889)
		(layer "In4.Cu")
		(net "PMU_SLP_S3#")
	)
	(segment
		(start 56.667654 -44.696634)
		(end 53.475128 -47.88916)
		(width 0.0889)
		(layer "In4.Cu")
		(net "PMU_SLP_S3#")
	)
	(segment
		(start 69.75475 -36.92525)
		(end 64.995044 -36.92525)
		(width 0.0889)
		(layer "In4.Cu")
		(net "PMU_SLP_S3#")
	)
	(segment
		(start 58.711084 -43.048682)
		(end 58.23077 -43.528996)
		(width 0.0889)
		(layer "In4.Cu")
		(net "PMU_SLP_S3#")
	)
	(segment
		(start 70.612 -36.068)
		(end 69.75475 -36.92525)
		(width 0.0889)
		(layer "In4.Cu")
		(net "PMU_SLP_S3#")
	)
	(segment
		(start 53.475128 -47.88916)
		(end 52.796694 -47.88916)
		(width 0.0889)
		(layer "In4.Cu")
		(net "PMU_SLP_S3#")
	)
	(segment
		(start 58.97499 -42.09542)
		(end 58.711084 -42.359326)
		(width 0.0889)
		(layer "In4.Cu")
		(net "PMU_SLP_S3#")
	)
	(segment
		(start 64.995044 -36.92525)
		(end 59.824874 -42.09542)
		(width 0.0889)
		(layer "In4.Cu")
		(net "PMU_SLP_S3#")
	)
	(segment
		(start 70.612 -36.0426)
		(end 70.612 -36.068)
		(width 0.0889)
		(layer "In4.Cu")
		(net "PMU_SLP_S3#")
	)
	(segment
		(start 58.711084 -42.359326)
		(end 58.711084 -43.048682)
		(width 0.0889)
		(layer "In4.Cu")
		(net "PMU_SLP_S3#")
	)
	(segment
		(start 57.064148 -44.696634)
		(end 56.667654 -44.696634)
		(width 0.0889)
		(layer "In4.Cu")
		(net "PMU_SLP_S3#")
	)
	(segment
		(start 47.272194 -54.0766)
		(end 48.101504 -53.24729)
		(width 0.0889)
		(layer "In9.Cu")
		(net "PMU_SLP_S3#")
	)
	(segment
		(start 29.49575 -51.97475)
		(end 30.282896 -51.97475)
		(width 0.0889)
		(layer "In9.Cu")
		(net "PMU_SLP_S3#")
	)
	(segment
		(start 40.64 -53.6448)
		(end 41.0718 -54.0766)
		(width 0.0889)
		(layer "In9.Cu")
		(net "PMU_SLP_S3#")
	)
	(segment
		(start 23.00605 -50.78095)
		(end 28.30195 -50.78095)
		(width 0.0889)
		(layer "In9.Cu")
		(net "PMU_SLP_S3#")
	)
	(segment
		(start 48.101504 -48.48606)
		(end 49.58842 -46.999144)
		(width 0.0889)
		(layer "In9.Cu")
		(net "PMU_SLP_S3#")
	)
	(segment
		(start 51.723544 -46.999144)
		(end 52.61356 -47.88916)
		(width 0.0889)
		(layer "In9.Cu")
		(net "PMU_SLP_S3#")
	)
	(segment
		(start 14.480286 -58.422286)
		(end 14.480794 -58.421778)
		(width 0.0889)
		(layer "In9.Cu")
		(net "PMU_SLP_S3#")
	)
	(segment
		(start 15.365222 -58.421778)
		(end 23.00605 -50.78095)
		(width 0.0889)
		(layer "In9.Cu")
		(net "PMU_SLP_S3#")
	)
	(segment
		(start 30.282896 -51.97475)
		(end 32.486346 -54.1782)
		(width 0.0889)
		(layer "In9.Cu")
		(net "PMU_SLP_S3#")
	)
	(segment
		(start 39.37 -54.1782)
		(end 39.9034 -53.6448)
		(width 0.0889)
		(layer "In9.Cu")
		(net "PMU_SLP_S3#")
	)
	(segment
		(start 14.480794 -58.421778)
		(end 15.365222 -58.421778)
		(width 0.0889)
		(layer "In9.Cu")
		(net "PMU_SLP_S3#")
	)
	(segment
		(start 52.61356 -47.88916)
		(end 52.796694 -47.88916)
		(width 0.0889)
		(layer "In9.Cu")
		(net "PMU_SLP_S3#")
	)
	(segment
		(start 32.486346 -54.1782)
		(end 39.37 -54.1782)
		(width 0.0889)
		(layer "In9.Cu")
		(net "PMU_SLP_S3#")
	)
	(segment
		(start 39.9034 -53.6448)
		(end 40.64 -53.6448)
		(width 0.0889)
		(layer "In9.Cu")
		(net "PMU_SLP_S3#")
	)
	(segment
		(start 28.30195 -50.78095)
		(end 29.49575 -51.97475)
		(width 0.0889)
		(layer "In9.Cu")
		(net "PMU_SLP_S3#")
	)
	(segment
		(start 41.0718 -54.0766)
		(end 47.272194 -54.0766)
		(width 0.0889)
		(layer "In9.Cu")
		(net "PMU_SLP_S3#")
	)
	(segment
		(start 49.58842 -46.999144)
		(end 51.723544 -46.999144)
		(width 0.0889)
		(layer "In9.Cu")
		(net "PMU_SLP_S3#")
	)
	(segment
		(start 48.101504 -53.24729)
		(end 48.101504 -48.48606)
		(width 0.0889)
		(layer "In9.Cu")
		(net "PMU_SLP_S3#")
	)
	(segment
		(start 83.993482 -41.0718)
		(end 84.0486 -41.0718)
		(width 0.1143)
		(layer "F.Cu")
		(net "PMU_RESETBUTTON_R#")
	)
	(segment
		(start 83.647788 -41.417494)
		(end 83.993482 -41.0718)
		(width 0.1143)
		(layer "F.Cu")
		(net "PMU_RESETBUTTON_R#")
	)
	(via
		(at 84.0486 -41.0718)
		(size 0.4318)
		(drill 0.2032)
		(layers "F.Cu" "B.Cu")
		(net "PMU_RESETBUTTON_R#")
	)
	(via
		(at 75.692 -46.101)
		(size 0.7112)
		(drill 0.3556)
		(layers "F.Cu" "B.Cu")
		(net "PMU_RESETBUTTON_R#")
	)
	(segment
		(start 78.613762 -45.3898)
		(end 82.119724 -41.883838)
		(width 0.1143)
		(layer "B.Cu")
		(net "PMU_RESETBUTTON_R#")
	)
	(segment
		(start 76.4032 -45.3898)
		(end 78.613762 -45.3898)
		(width 0.1143)
		(layer "B.Cu")
		(net "PMU_RESETBUTTON_R#")
	)
	(segment
		(start 75.692 -46.101)
		(end 76.4032 -45.3898)
		(width 0.1143)
		(layer "B.Cu")
		(net "PMU_RESETBUTTON_R#")
	)
	(segment
		(start 82.119724 -41.883838)
		(end 83.236562 -41.883838)
		(width 0.1143)
		(layer "B.Cu")
		(net "PMU_RESETBUTTON_R#")
	)
	(segment
		(start 75.692 -46.101)
		(end 74.5998 -46.101)
		(width 0.1143)
		(layer "B.Cu")
		(net "PMU_RESETBUTTON_R#")
	)
	(segment
		(start 83.236562 -41.883838)
		(end 84.0486 -41.0718)
		(width 0.1143)
		(layer "B.Cu")
		(net "PMU_RESETBUTTON_R#")
	)
	(segment
		(start 80.013556 -36.069524)
		(end 80.3402 -36.069524)
		(width 0.1143)
		(layer "F.Cu")
		(net "PU_PMU_GPE#")
	)
	(segment
		(start 79.676244 -36.406836)
		(end 80.013556 -36.069524)
		(width 0.1143)
		(layer "F.Cu")
		(net "PU_PMU_GPE#")
	)
	(segment
		(start 75.362562 -35.306762)
		(end 75.945238 -35.306762)
		(width 0.1143)
		(layer "F.Cu")
		(net "PU_PMU_GPE#")
	)
	(segment
		(start 74.4728 -34.417)
		(end 75.362562 -35.306762)
		(width 0.1143)
		(layer "F.Cu")
		(net "PU_PMU_GPE#")
	)
	(segment
		(start 78.721712 -36.406836)
		(end 79.676244 -36.406836)
		(width 0.1143)
		(layer "F.Cu")
		(net "PU_PMU_GPE#")
	)
	(segment
		(start 75.945238 -35.306762)
		(end 77.621638 -35.306762)
		(width 0.1143)
		(layer "F.Cu")
		(net "PU_PMU_GPE#")
	)
	(segment
		(start 80.68437 -36.413694)
		(end 80.950308 -36.413694)
		(width 0.1143)
		(layer "F.Cu")
		(net "PU_PMU_GPE#")
	)
	(segment
		(start 80.3402 -36.069524)
		(end 80.68437 -36.413694)
		(width 0.1143)
		(layer "F.Cu")
		(net "PU_PMU_GPE#")
	)
	(segment
		(start 77.621638 -35.306762)
		(end 78.721712 -36.406836)
		(width 0.1143)
		(layer "F.Cu")
		(net "PU_PMU_GPE#")
	)
	(via
		(at 75.945238 -35.306762)
		(size 0.7112)
		(drill 0.3556)
		(layers "F.Cu" "B.Cu")
		(net "PU_PMU_GPE#")
	)
	(segment
		(start 98.171 -8.9408)
		(end 98.298 -8.8138)
		(width 0.1143)
		(layer "F.Cu")
		(net "BOARD_PRSNT#")
	)
	(segment
		(start 97.8662 -11.938)
		(end 98.171 -11.6332)
		(width 0.1143)
		(layer "F.Cu")
		(net "BOARD_PRSNT#")
	)
	(segment
		(start 98.298 -8.8138)
		(end 98.298 -6.742938)
		(width 0.1143)
		(layer "F.Cu")
		(net "BOARD_PRSNT#")
	)
	(segment
		(start 97.155 -13.6652)
		(end 97.155 -12.6492)
		(width 0.1143)
		(layer "F.Cu")
		(net "BOARD_PRSNT#")
	)
	(segment
		(start 98.298 -6.742938)
		(end 98.35007 -6.690868)
		(width 0.1143)
		(layer "F.Cu")
		(net "BOARD_PRSNT#")
	)
	(segment
		(start 98.171 -11.6332)
		(end 98.171 -8.9408)
		(width 0.1143)
		(layer "F.Cu")
		(net "BOARD_PRSNT#")
	)
	(segment
		(start 97.155 -12.6492)
		(end 97.8662 -11.938)
		(width 0.1143)
		(layer "F.Cu")
		(net "BOARD_PRSNT#")
	)
	(via
		(at 97.769934 -12.898628)
		(size 0.7112)
		(drill 0.3556)
		(layers "F.Cu" "B.Cu")
		(net "BOARD_PRSNT#")
	)
	(via
		(at 97.8662 -11.938)
		(size 0.508)
		(drill 0.254)
		(layers "F.Cu" "B.Cu")
		(net "BOARD_PRSNT#")
	)
	(segment
		(start 97.769934 -12.898628)
		(end 97.769934 -12.034266)
		(width 0.1143)
		(layer "B.Cu")
		(net "BOARD_PRSNT#")
	)
	(segment
		(start 97.769934 -12.034266)
		(end 97.8662 -11.938)
		(width 0.1143)
		(layer "B.Cu")
		(net "BOARD_PRSNT#")
	)
	(segment
		(start 141.49832 -45.708824)
		(end 141.226794 -45.98035)
		(width 0.1143)
		(layer "F.Cu")
		(net "C_NCE#")
	)
	(segment
		(start 140.081 -47.625)
		(end 140.145516 -47.560484)
		(width 0.1143)
		(layer "F.Cu")
		(net "C_NCE#")
	)
	(segment
		(start 140.145516 -47.560484)
		(end 140.145516 -46.6344)
		(width 0.1143)
		(layer "F.Cu")
		(net "C_NCE#")
	)
	(segment
		(start 141.226794 -45.98035)
		(end 140.799566 -45.98035)
		(width 0.1143)
		(layer "F.Cu")
		(net "C_NCE#")
	)
	(segment
		(start 141.49832 -45.1612)
		(end 141.49832 -45.708824)
		(width 0.1143)
		(layer "F.Cu")
		(net "C_NCE#")
	)
	(segment
		(start 140.799566 -45.98035)
		(end 140.145516 -46.6344)
		(width 0.1143)
		(layer "F.Cu")
		(net "C_NCE#")
	)
	(via
		(at 140.145516 -46.6344)
		(size 0.508)
		(drill 0.254)
		(layers "F.Cu" "B.Cu")
		(net "C_NCE#")
	)
	(segment
		(start 140.6652 -45.466)
		(end 140.6652 -46.114716)
		(width 0.1143)
		(layer "B.Cu")
		(net "C_NCE#")
	)
	(segment
		(start 140.6652 -46.114716)
		(end 140.145516 -46.6344)
		(width 0.1143)
		(layer "B.Cu")
		(net "C_NCE#")
	)
	(segment
		(start 140.0302 -47.625)
		(end 140.0302 -46.749716)
		(width 0.1143)
		(layer "B.Cu")
		(net "C_NCE#")
	)
	(segment
		(start 140.0302 -46.749716)
		(end 140.145516 -46.6344)
		(width 0.1143)
		(layer "B.Cu")
		(net "C_NCE#")
	)
	(via
		(at 199.601074 -40.386)
		(size 0.7112)
		(drill 0.3556)
		(layers "F.Cu" "B.Cu")
		(net "PORT80_R_BIT5")
	)
	(segment
		(start 200.642474 -40.005)
		(end 199.982074 -40.005)
		(width 0.127)
		(layer "B.Cu")
		(net "PORT80_R_BIT5")
	)
	(segment
		(start 198.501 -41.91)
		(end 198.4248 -41.91)
		(width 0.127)
		(layer "B.Cu")
		(net "PORT80_R_BIT5")
	)
	(segment
		(start 199.982074 -40.005)
		(end 199.601074 -40.386)
		(width 0.127)
		(layer "B.Cu")
		(net "PORT80_R_BIT5")
	)
	(segment
		(start 199.601074 -40.386)
		(end 199.601074 -40.809926)
		(width 0.127)
		(layer "B.Cu")
		(net "PORT80_R_BIT5")
	)
	(segment
		(start 199.601074 -40.809926)
		(end 198.501 -41.91)
		(width 0.127)
		(layer "B.Cu")
		(net "PORT80_R_BIT5")
	)
	(via
		(at 199.644 -43.651424)
		(size 0.7112)
		(drill 0.3556)
		(layers "F.Cu" "B.Cu")
		(net "PORT80_R_BIT7")
	)
	(segment
		(start 198.642224 -43.651424)
		(end 199.644 -43.651424)
		(width 0.127)
		(layer "B.Cu")
		(net "PORT80_R_BIT7")
	)
	(segment
		(start 200.642474 -42.816526)
		(end 200.642474 -42.6466)
		(width 0.127)
		(layer "B.Cu")
		(net "PORT80_R_BIT7")
	)
	(segment
		(start 199.644 -43.651424)
		(end 199.807576 -43.651424)
		(width 0.127)
		(layer "B.Cu")
		(net "PORT80_R_BIT7")
	)
	(segment
		(start 199.807576 -43.651424)
		(end 200.642474 -42.816526)
		(width 0.127)
		(layer "B.Cu")
		(net "PORT80_R_BIT7")
	)
	(segment
		(start 198.4248 -43.434)
		(end 198.642224 -43.651424)
		(width 0.127)
		(layer "B.Cu")
		(net "PORT80_R_BIT7")
	)
	(via
		(at 199.505062 -39.170356)
		(size 0.7112)
		(drill 0.3556)
		(layers "F.Cu" "B.Cu")
		(net "PORT80_R_BIT4")
	)
	(segment
		(start 198.4248 -41.148)
		(end 198.755 -40.8178)
		(width 0.127)
		(layer "B.Cu")
		(net "PORT80_R_BIT4")
	)
	(segment
		(start 199.991218 -38.6842)
		(end 199.505062 -39.170356)
		(width 0.127)
		(layer "B.Cu")
		(net "PORT80_R_BIT4")
	)
	(segment
		(start 198.755 -40.8178)
		(end 198.755 -39.920418)
		(width 0.127)
		(layer "B.Cu")
		(net "PORT80_R_BIT4")
	)
	(segment
		(start 200.642474 -38.6842)
		(end 199.991218 -38.6842)
		(width 0.127)
		(layer "B.Cu")
		(net "PORT80_R_BIT4")
	)
	(segment
		(start 198.755 -39.920418)
		(end 199.505062 -39.170356)
		(width 0.127)
		(layer "B.Cu")
		(net "PORT80_R_BIT4")
	)
	(via
		(at 199.601074 -41.783)
		(size 0.7112)
		(drill 0.3556)
		(layers "F.Cu" "B.Cu")
		(net "PORT80_R_BIT6")
	)
	(segment
		(start 198.712074 -42.672)
		(end 199.601074 -41.783)
		(width 0.127)
		(layer "B.Cu")
		(net "PORT80_R_BIT6")
	)
	(segment
		(start 200.642474 -41.3258)
		(end 200.058274 -41.3258)
		(width 0.127)
		(layer "B.Cu")
		(net "PORT80_R_BIT6")
	)
	(segment
		(start 200.058274 -41.3258)
		(end 199.601074 -41.783)
		(width 0.127)
		(layer "B.Cu")
		(net "PORT80_R_BIT6")
	)
	(segment
		(start 198.4248 -42.672)
		(end 198.712074 -42.672)
		(width 0.127)
		(layer "B.Cu")
		(net "PORT80_R_BIT6")
	)
	(via
		(at 199.4154 -35.5346)
		(size 0.7112)
		(drill 0.3556)
		(layers "F.Cu" "B.Cu")
		(net "PORT80_R_BIT3")
	)
	(segment
		(start 200.617074 -35.5346)
		(end 199.4154 -35.5346)
		(width 0.127)
		(layer "B.Cu")
		(net "PORT80_R_BIT3")
	)
	(segment
		(start 199.4154 -35.5346)
		(end 199.250554 -35.369754)
		(width 0.127)
		(layer "B.Cu")
		(net "PORT80_R_BIT3")
	)
	(segment
		(start 198.49211 -33.782)
		(end 197.9168 -33.782)
		(width 0.127)
		(layer "B.Cu")
		(net "PORT80_R_BIT3")
	)
	(segment
		(start 199.250554 -35.369754)
		(end 199.250554 -34.540444)
		(width 0.127)
		(layer "B.Cu")
		(net "PORT80_R_BIT3")
	)
	(segment
		(start 199.250554 -34.540444)
		(end 198.49211 -33.782)
		(width 0.127)
		(layer "B.Cu")
		(net "PORT80_R_BIT3")
	)
	(via
		(at 199.472296 -33.953704)
		(size 0.7112)
		(drill 0.3556)
		(layers "F.Cu" "B.Cu")
		(net "PORT80_R_BIT2")
	)
	(segment
		(start 199.706992 -34.1884)
		(end 199.472296 -33.953704)
		(width 0.127)
		(layer "B.Cu")
		(net "PORT80_R_BIT2")
	)
	(segment
		(start 198.411592 -32.893)
		(end 197.9168 -32.893)
		(width 0.127)
		(layer "B.Cu")
		(net "PORT80_R_BIT2")
	)
	(segment
		(start 199.472296 -33.953704)
		(end 198.411592 -32.893)
		(width 0.127)
		(layer "B.Cu")
		(net "PORT80_R_BIT2")
	)
	(segment
		(start 200.617074 -34.1884)
		(end 199.706992 -34.1884)
		(width 0.127)
		(layer "B.Cu")
		(net "PORT80_R_BIT2")
	)
	(via
		(at 199.465438 -32.734504)
		(size 0.7112)
		(drill 0.3556)
		(layers "F.Cu" "B.Cu")
		(net "PORT80_R_BIT1")
	)
	(segment
		(start 199.465438 -32.734504)
		(end 200.509378 -32.734504)
		(width 0.127)
		(layer "B.Cu")
		(net "PORT80_R_BIT1")
	)
	(segment
		(start 198.647304 -32.734504)
		(end 197.9168 -32.004)
		(width 0.127)
		(layer "B.Cu")
		(net "PORT80_R_BIT1")
	)
	(segment
		(start 199.465438 -32.734504)
		(end 198.647304 -32.734504)
		(width 0.127)
		(layer "B.Cu")
		(net "PORT80_R_BIT1")
	)
	(segment
		(start 200.509378 -32.734504)
		(end 200.617074 -32.8422)
		(width 0.127)
		(layer "B.Cu")
		(net "PORT80_R_BIT1")
	)
	(segment
		(start 134.49808 -22.9997)
		(end 134.49808 -23.9268)
		(width 0.1143)
		(layer "F.Cu")
		(net "BIOS_POST_COMPLETE_R")
	)
	(segment
		(start 134.36219 -22.86381)
		(end 134.49808 -22.9997)
		(width 0.1143)
		(layer "F.Cu")
		(net "BIOS_POST_COMPLETE_R")
	)
	(segment
		(start 134.36219 -22.85365)
		(end 134.36219 -22.86381)
		(width 0.1143)
		(layer "F.Cu")
		(net "BIOS_POST_COMPLETE_R")
	)
	(via
		(at 133.6548 -24.5364)
		(size 0.7112)
		(drill 0.3556)
		(layers "F.Cu" "B.Cu")
		(net "BIOS_POST_COMPLETE_R")
	)
	(via
		(at 134.36219 -22.85365)
		(size 0.508)
		(drill 0.254)
		(layers "F.Cu" "B.Cu")
		(net "BIOS_POST_COMPLETE_R")
	)
	(segment
		(start 133.6548 -23.56104)
		(end 133.6548 -23.622)
		(width 0.1143)
		(layer "B.Cu")
		(net "BIOS_POST_COMPLETE_R")
	)
	(segment
		(start 134.36219 -22.85365)
		(end 133.6548 -23.56104)
		(width 0.1143)
		(layer "B.Cu")
		(net "BIOS_POST_COMPLETE_R")
	)
	(segment
		(start 133.6548 -23.622)
		(end 133.6548 -24.5364)
		(width 0.1143)
		(layer "B.Cu")
		(net "BIOS_POST_COMPLETE_R")
	)
	(via
		(at 201.168 -30.34411)
		(size 0.7112)
		(drill 0.3556)
		(layers "F.Cu" "B.Cu")
		(net "PORT80_R_BIT0")
	)
	(segment
		(start 201.041 -30.47111)
		(end 201.041 -31.072074)
		(width 0.127)
		(layer "B.Cu")
		(net "PORT80_R_BIT0")
	)
	(segment
		(start 200.109074 -31.496)
		(end 199.702674 -31.9024)
		(width 0.127)
		(layer "B.Cu")
		(net "PORT80_R_BIT0")
	)
	(segment
		(start 201.168 -30.34411)
		(end 201.041 -30.47111)
		(width 0.127)
		(layer "B.Cu")
		(net "PORT80_R_BIT0")
	)
	(segment
		(start 201.041 -31.072074)
		(end 200.617074 -31.496)
		(width 0.127)
		(layer "B.Cu")
		(net "PORT80_R_BIT0")
	)
	(segment
		(start 198.7042 -31.9024)
		(end 197.9168 -31.115)
		(width 0.127)
		(layer "B.Cu")
		(net "PORT80_R_BIT0")
	)
	(segment
		(start 200.617074 -31.496)
		(end 200.109074 -31.496)
		(width 0.127)
		(layer "B.Cu")
		(net "PORT80_R_BIT0")
	)
	(segment
		(start 199.702674 -31.9024)
		(end 198.7042 -31.9024)
		(width 0.127)
		(layer "B.Cu")
		(net "PORT80_R_BIT0")
	)
	(segment
		(start 132.1308 -36.79444)
		(end 131.390898 -36.79444)
		(width 0.1143)
		(layer "F.Cu")
		(net "LPC_AD_3")
	)
	(segment
		(start 130.376168 -37.80917)
		(end 129.5146 -37.80917)
		(width 0.1143)
		(layer "F.Cu")
		(net "LPC_AD_3")
	)
	(segment
		(start 131.390898 -36.79444)
		(end 130.376168 -37.80917)
		(width 0.1143)
		(layer "F.Cu")
		(net "LPC_AD_3")
	)
	(segment
		(start 128.5748 -37.592)
		(end 128.79197 -37.80917)
		(width 0.1143)
		(layer "F.Cu")
		(net "LPC_AD_3")
	)
	(segment
		(start 128.79197 -37.80917)
		(end 129.5146 -37.80917)
		(width 0.1143)
		(layer "F.Cu")
		(net "LPC_AD_3")
	)
	(via
		(at 129.5146 -37.80917)
		(size 0.7112)
		(drill 0.3556)
		(layers "F.Cu" "B.Cu")
		(net "LPC_AD_3")
	)
	(segment
		(start 132.1308 -36.29406)
		(end 131.298442 -36.29406)
		(width 0.1143)
		(layer "F.Cu")
		(net "LPC_AD_2")
	)
	(segment
		(start 128.7018 -36.957)
		(end 130.429 -36.957)
		(width 0.1143)
		(layer "F.Cu")
		(net "LPC_AD_2")
	)
	(segment
		(start 130.635502 -36.957)
		(end 130.429 -36.957)
		(width 0.1143)
		(layer "F.Cu")
		(net "LPC_AD_2")
	)
	(segment
		(start 131.298442 -36.29406)
		(end 130.635502 -36.957)
		(width 0.1143)
		(layer "F.Cu")
		(net "LPC_AD_2")
	)
	(segment
		(start 128.5748 -36.83)
		(end 128.7018 -36.957)
		(width 0.1143)
		(layer "F.Cu")
		(net "LPC_AD_2")
	)
	(via
		(at 130.429 -36.957)
		(size 0.7112)
		(drill 0.3556)
		(layers "F.Cu" "B.Cu")
		(net "LPC_AD_2")
	)
	(segment
		(start 131.176268 -35.79368)
		(end 130.901948 -36.068)
		(width 0.1143)
		(layer "F.Cu")
		(net "LPC_AD_1")
	)
	(segment
		(start 132.1308 -35.79368)
		(end 131.176268 -35.79368)
		(width 0.1143)
		(layer "F.Cu")
		(net "LPC_AD_1")
	)
	(segment
		(start 129.5146 -36.068)
		(end 128.5748 -36.068)
		(width 0.1143)
		(layer "F.Cu")
		(net "LPC_AD_1")
	)
	(segment
		(start 130.901948 -36.068)
		(end 129.5146 -36.068)
		(width 0.1143)
		(layer "F.Cu")
		(net "LPC_AD_1")
	)
	(via
		(at 129.5146 -36.068)
		(size 0.7112)
		(drill 0.3556)
		(layers "F.Cu" "B.Cu")
		(net "LPC_AD_1")
	)
	(segment
		(start 132.1308 -35.29457)
		(end 130.5052 -35.29457)
		(width 0.1143)
		(layer "F.Cu")
		(net "LPC_AD_0")
	)
	(segment
		(start 128.587754 -35.293046)
		(end 130.503676 -35.293046)
		(width 0.1143)
		(layer "F.Cu")
		(net "LPC_AD_0")
	)
	(segment
		(start 130.503676 -35.293046)
		(end 130.5052 -35.29457)
		(width 0.1143)
		(layer "F.Cu")
		(net "LPC_AD_0")
	)
	(segment
		(start 128.5748 -35.306)
		(end 128.587754 -35.293046)
		(width 0.1143)
		(layer "F.Cu")
		(net "LPC_AD_0")
	)
	(via
		(at 130.5052 -35.29457)
		(size 0.7112)
		(drill 0.3556)
		(layers "F.Cu" "B.Cu")
		(net "LPC_AD_0")
	)
	(segment
		(start 153.3652 -43.2943)
		(end 157.860238 -43.2943)
		(width 0.127)
		(layer "F.Cu")
		(net "PORT80_BIT7")
	)
	(segment
		(start 157.860238 -43.2943)
		(end 158.7246 -42.429938)
		(width 0.127)
		(layer "F.Cu")
		(net "PORT80_BIT7")
	)
	(segment
		(start 159.766 -41.388538)
		(end 158.7246 -42.429938)
		(width 0.127)
		(layer "F.Cu")
		(net "PORT80_BIT7")
	)
	(segment
		(start 159.766 -40.386)
		(end 159.766 -41.388538)
		(width 0.127)
		(layer "F.Cu")
		(net "PORT80_BIT7")
	)
	(via
		(at 205.6638 -41.7322)
		(size 0.5588)
		(drill 0.3048)
		(layers "F.Cu" "B.Cu")
		(net "PORT80_BIT7")
	)
	(via
		(at 159.766 -40.386)
		(size 0.508)
		(drill 0.254)
		(layers "F.Cu" "B.Cu")
		(net "PORT80_BIT7")
	)
	(via
		(at 158.7246 -42.429938)
		(size 0.7112)
		(drill 0.3556)
		(layers "F.Cu" "B.Cu")
		(net "PORT80_BIT7")
	)
	(segment
		(start 205.6511 -41.7195)
		(end 205.6638 -41.7322)
		(width 0.127)
		(layer "B.Cu")
		(net "PORT80_BIT7")
	)
	(segment
		(start 203.3651 -41.7195)
		(end 205.6511 -41.7195)
		(width 0.127)
		(layer "B.Cu")
		(net "PORT80_BIT7")
	)
	(segment
		(start 202.438 -42.6466)
		(end 203.3651 -41.7195)
		(width 0.127)
		(layer "B.Cu")
		(net "PORT80_BIT7")
	)
	(segment
		(start 201.947526 -42.6466)
		(end 202.438 -42.6466)
		(width 0.127)
		(layer "B.Cu")
		(net "PORT80_BIT7")
	)
	(segment
		(start 160.18764 -40.80764)
		(end 159.766 -40.386)
		(width 0.127)
		(layer "In4.Cu")
		(net "PORT80_BIT7")
	)
	(segment
		(start 205.6638 -41.7322)
		(end 202.7936 -38.862)
		(width 0.127)
		(layer "In4.Cu")
		(net "PORT80_BIT7")
	)
	(segment
		(start 184.912 -38.862)
		(end 181.1147 -35.0647)
		(width 0.127)
		(layer "In4.Cu")
		(net "PORT80_BIT7")
	)
	(segment
		(start 172.124878 -40.80764)
		(end 160.18764 -40.80764)
		(width 0.127)
		(layer "In4.Cu")
		(net "PORT80_BIT7")
	)
	(segment
		(start 202.7936 -38.862)
		(end 184.912 -38.862)
		(width 0.127)
		(layer "In4.Cu")
		(net "PORT80_BIT7")
	)
	(segment
		(start 177.867818 -35.0647)
		(end 172.124878 -40.80764)
		(width 0.127)
		(layer "In4.Cu")
		(net "PORT80_BIT7")
	)
	(segment
		(start 181.1147 -35.0647)
		(end 177.867818 -35.0647)
		(width 0.127)
		(layer "In4.Cu")
		(net "PORT80_BIT7")
	)
	(segment
		(start 146.37893 -46.57344)
		(end 146.99742 -45.95495)
		(width 0.1143)
		(layer "F.Cu")
		(net "TEMP_1_ALERT#")
	)
	(segment
		(start 87.38235 -70.94855)
		(end 106.08945 -70.94855)
		(width 0.1143)
		(layer "F.Cu")
		(net "TEMP_1_ALERT#")
	)
	(segment
		(start 5.588 -43.0022)
		(end 6.1468 -43.561)
		(width 0.1143)
		(layer "F.Cu")
		(net "TEMP_1_ALERT#")
	)
	(segment
		(start 5.8674 -46.1772)
		(end 6.0706 -46.1772)
		(width 0.1143)
		(layer "F.Cu")
		(net "TEMP_1_ALERT#")
	)
	(segment
		(start 6.0706 -46.1772)
		(end 7.165086 -45.082714)
		(width 0.1143)
		(layer "F.Cu")
		(net "TEMP_1_ALERT#")
	)
	(segment
		(start 87.0204 -70.5866)
		(end 87.38235 -70.94855)
		(width 0.1143)
		(layer "F.Cu")
		(net "TEMP_1_ALERT#")
	)
	(segment
		(start 6.1468 -43.561)
		(end 6.985 -43.561)
		(width 0.1143)
		(layer "F.Cu")
		(net "TEMP_1_ALERT#")
	)
	(segment
		(start 7.165086 -45.082714)
		(end 7.165086 -44.488608)
		(width 0.1143)
		(layer "F.Cu")
		(net "TEMP_1_ALERT#")
	)
	(segment
		(start 6.985 -43.561)
		(end 7.165086 -43.741086)
		(width 0.1143)
		(layer "F.Cu")
		(net "TEMP_1_ALERT#")
	)
	(segment
		(start 146.99742 -45.95495)
		(end 146.99742 -45.1612)
		(width 0.1143)
		(layer "F.Cu")
		(net "TEMP_1_ALERT#")
	)
	(segment
		(start 106.08945 -70.94855)
		(end 107.442 -69.596)
		(width 0.1143)
		(layer "F.Cu")
		(net "TEMP_1_ALERT#")
	)
	(segment
		(start 146.37893 -46.5836)
		(end 146.37893 -46.57344)
		(width 0.1143)
		(layer "F.Cu")
		(net "TEMP_1_ALERT#")
	)
	(segment
		(start 7.165086 -43.741086)
		(end 7.165086 -44.488608)
		(width 0.1143)
		(layer "F.Cu")
		(net "TEMP_1_ALERT#")
	)
	(via
		(at 19.8628 -70.0024)
		(size 0.508)
		(drill 0.254)
		(layers "F.Cu" "B.Cu")
		(net "TEMP_1_ALERT#")
	)
	(via
		(at 87.0204 -70.5866)
		(size 0.508)
		(drill 0.254)
		(layers "F.Cu" "B.Cu")
		(net "TEMP_1_ALERT#")
	)
	(via
		(at 174.613824 -46.721776)
		(size 0.508)
		(drill 0.254)
		(layers "F.Cu" "B.Cu")
		(net "TEMP_1_ALERT#")
	)
	(via
		(at 172.687234 -45.560234)
		(size 0.7112)
		(drill 0.3556)
		(layers "F.Cu" "B.Cu")
		(net "TEMP_1_ALERT#")
	)
	(via
		(at 146.37893 -46.5836)
		(size 0.508)
		(drill 0.254)
		(layers "F.Cu" "B.Cu")
		(net "TEMP_1_ALERT#")
	)
	(via
		(at 107.442 -69.596)
		(size 0.508)
		(drill 0.254)
		(layers "F.Cu" "B.Cu")
		(net "TEMP_1_ALERT#")
	)
	(via
		(at 5.8674 -46.1772)
		(size 0.508)
		(drill 0.254)
		(layers "F.Cu" "B.Cu")
		(net "TEMP_1_ALERT#")
	)
	(segment
		(start 174.613824 -46.721776)
		(end 173.848776 -46.721776)
		(width 0.1143)
		(layer "B.Cu")
		(net "TEMP_1_ALERT#")
	)
	(segment
		(start 173.848776 -46.721776)
		(end 172.687234 -45.560234)
		(width 0.1143)
		(layer "B.Cu")
		(net "TEMP_1_ALERT#")
	)
	(segment
		(start 153.015442 -47.244)
		(end 154.310842 -45.9486)
		(width 0.1143)
		(layer "B.Cu")
		(net "TEMP_1_ALERT#")
	)
	(segment
		(start 154.310842 -45.9486)
		(end 161.071052 -45.9486)
		(width 0.1143)
		(layer "B.Cu")
		(net "TEMP_1_ALERT#")
	)
	(segment
		(start 147.048982 -47.253652)
		(end 149.825964 -47.253652)
		(width 0.1143)
		(layer "B.Cu")
		(net "TEMP_1_ALERT#")
	)
	(segment
		(start 172.24502 -45.11802)
		(end 172.687234 -45.560234)
		(width 0.1143)
		(layer "B.Cu")
		(net "TEMP_1_ALERT#")
	)
	(segment
		(start 161.071052 -45.9486)
		(end 161.901632 -45.11802)
		(width 0.1143)
		(layer "B.Cu")
		(net "TEMP_1_ALERT#")
	)
	(segment
		(start 146.37893 -46.5836)
		(end 147.048982 -47.253652)
		(width 0.1143)
		(layer "B.Cu")
		(net "TEMP_1_ALERT#")
	)
	(segment
		(start 149.825964 -47.253652)
		(end 149.835616 -47.244)
		(width 0.1143)
		(layer "B.Cu")
		(net "TEMP_1_ALERT#")
	)
	(segment
		(start 161.901632 -45.11802)
		(end 172.24502 -45.11802)
		(width 0.1143)
		(layer "B.Cu")
		(net "TEMP_1_ALERT#")
	)
	(segment
		(start 149.835616 -47.244)
		(end 153.015442 -47.244)
		(width 0.1143)
		(layer "B.Cu")
		(net "TEMP_1_ALERT#")
	)
	(segment
		(start 193.1543 -68.147946)
		(end 193.1543 -64.065658)
		(width 0.0889)
		(layer "In2.Cu")
		(net "TEMP_1_ALERT#")
	)
	(segment
		(start 183.7182 -47.215298)
		(end 182.116476 -45.613574)
		(width 0.0889)
		(layer "In2.Cu")
		(net "TEMP_1_ALERT#")
	)
	(segment
		(start 189.718442 -71.583804)
		(end 193.1543 -68.147946)
		(width 0.0889)
		(layer "In2.Cu")
		(net "TEMP_1_ALERT#")
	)
	(segment
		(start 11.357864 -47.42815)
		(end 12.13485 -48.205136)
		(width 0.0889)
		(layer "In2.Cu")
		(net "TEMP_1_ALERT#")
	)
	(segment
		(start 11.72845 -66.32575)
		(end 9.9314 -68.1228)
		(width 0.0889)
		(layer "In2.Cu")
		(net "TEMP_1_ALERT#")
	)
	(segment
		(start 7.11835 -47.42815)
		(end 11.357864 -47.42815)
		(width 0.0889)
		(layer "In2.Cu")
		(net "TEMP_1_ALERT#")
	)
	(segment
		(start 17.503394 -70.0024)
		(end 19.8628 -70.0024)
		(width 0.0889)
		(layer "In2.Cu")
		(net "TEMP_1_ALERT#")
	)
	(segment
		(start 193.1543 -64.065658)
		(end 183.7182 -54.629558)
		(width 0.0889)
		(layer "In2.Cu")
		(net "TEMP_1_ALERT#")
	)
	(segment
		(start 11.72845 -60.223654)
		(end 11.72845 -66.32575)
		(width 0.0889)
		(layer "In2.Cu")
		(net "TEMP_1_ALERT#")
	)
	(segment
		(start 16.780256 -70.35165)
		(end 17.154144 -70.35165)
		(width 0.0889)
		(layer "In2.Cu")
		(net "TEMP_1_ALERT#")
	)
	(segment
		(start 17.154144 -70.35165)
		(end 17.503394 -70.0024)
		(width 0.0889)
		(layer "In2.Cu")
		(net "TEMP_1_ALERT#")
	)
	(segment
		(start 128.632204 -71.583804)
		(end 189.718442 -71.583804)
		(width 0.0889)
		(layer "In2.Cu")
		(net "TEMP_1_ALERT#")
	)
	(segment
		(start 12.64285 -59.309254)
		(end 11.72845 -60.223654)
		(width 0.0889)
		(layer "In2.Cu")
		(net "TEMP_1_ALERT#")
	)
	(segment
		(start 11.02995 -70.21195)
		(end 16.640556 -70.21195)
		(width 0.0889)
		(layer "In2.Cu")
		(net "TEMP_1_ALERT#")
	)
	(segment
		(start 182.116476 -45.613574)
		(end 182.097426 -45.613574)
		(width 0.0889)
		(layer "In2.Cu")
		(net "TEMP_1_ALERT#")
	)
	(segment
		(start 5.8674 -46.1772)
		(end 7.11835 -47.42815)
		(width 0.0889)
		(layer "In2.Cu")
		(net "TEMP_1_ALERT#")
	)
	(segment
		(start 115.55349 -65.21831)
		(end 122.26671 -65.21831)
		(width 0.0889)
		(layer "In2.Cu")
		(net "TEMP_1_ALERT#")
	)
	(segment
		(start 175.8188 -45.5168)
		(end 174.613824 -46.721776)
		(width 0.0889)
		(layer "In2.Cu")
		(net "TEMP_1_ALERT#")
	)
	(segment
		(start 182.097426 -45.613574)
		(end 182.000652 -45.5168)
		(width 0.0889)
		(layer "In2.Cu")
		(net "TEMP_1_ALERT#")
	)
	(segment
		(start 183.7182 -54.629558)
		(end 183.7182 -47.215298)
		(width 0.0889)
		(layer "In2.Cu")
		(net "TEMP_1_ALERT#")
	)
	(segment
		(start 12.13485 -54.42585)
		(end 12.64285 -54.93385)
		(width 0.0889)
		(layer "In2.Cu")
		(net "TEMP_1_ALERT#")
	)
	(segment
		(start 107.442 -68.326)
		(end 108.51515 -67.25285)
		(width 0.0889)
		(layer "In2.Cu")
		(net "TEMP_1_ALERT#")
	)
	(segment
		(start 9.9314 -69.1134)
		(end 11.02995 -70.21195)
		(width 0.0889)
		(layer "In2.Cu")
		(net "TEMP_1_ALERT#")
	)
	(segment
		(start 113.51895 -67.25285)
		(end 115.55349 -65.21831)
		(width 0.0889)
		(layer "In2.Cu")
		(net "TEMP_1_ALERT#")
	)
	(segment
		(start 108.51515 -67.25285)
		(end 113.51895 -67.25285)
		(width 0.0889)
		(layer "In2.Cu")
		(net "TEMP_1_ALERT#")
	)
	(segment
		(start 107.442 -69.596)
		(end 107.442 -68.326)
		(width 0.0889)
		(layer "In2.Cu")
		(net "TEMP_1_ALERT#")
	)
	(segment
		(start 12.13485 -48.205136)
		(end 12.13485 -54.42585)
		(width 0.0889)
		(layer "In2.Cu")
		(net "TEMP_1_ALERT#")
	)
	(segment
		(start 9.9314 -68.1228)
		(end 9.9314 -69.1134)
		(width 0.0889)
		(layer "In2.Cu")
		(net "TEMP_1_ALERT#")
	)
	(segment
		(start 122.26671 -65.21831)
		(end 128.632204 -71.583804)
		(width 0.0889)
		(layer "In2.Cu")
		(net "TEMP_1_ALERT#")
	)
	(segment
		(start 12.64285 -54.93385)
		(end 12.64285 -59.309254)
		(width 0.0889)
		(layer "In2.Cu")
		(net "TEMP_1_ALERT#")
	)
	(segment
		(start 16.640556 -70.21195)
		(end 16.780256 -70.35165)
		(width 0.0889)
		(layer "In2.Cu")
		(net "TEMP_1_ALERT#")
	)
	(segment
		(start 182.000652 -45.5168)
		(end 175.8188 -45.5168)
		(width 0.0889)
		(layer "In2.Cu")
		(net "TEMP_1_ALERT#")
	)
	(segment
		(start 86.0298 -69.596)
		(end 86.0298 -67.129406)
		(width 0.0889)
		(layer "In7.Cu")
		(net "TEMP_1_ALERT#")
	)
	(segment
		(start 81.385918 -64.008)
		(end 80.903318 -63.5254)
		(width 0.0889)
		(layer "In7.Cu")
		(net "TEMP_1_ALERT#")
	)
	(segment
		(start 80.903318 -63.5254)
		(end 75.424792 -63.5254)
		(width 0.0889)
		(layer "In7.Cu")
		(net "TEMP_1_ALERT#")
	)
	(segment
		(start 75.424792 -63.5254)
		(end 71.875142 -59.97575)
		(width 0.0889)
		(layer "In7.Cu")
		(net "TEMP_1_ALERT#")
	)
	(segment
		(start 65.8876 -63.852806)
		(end 65.8876 -65.28943)
		(width 0.0889)
		(layer "In7.Cu")
		(net "TEMP_1_ALERT#")
	)
	(segment
		(start 45.88383 -68.1863)
		(end 43.74388 -70.32625)
		(width 0.0889)
		(layer "In7.Cu")
		(net "TEMP_1_ALERT#")
	)
	(segment
		(start 71.875142 -59.97575)
		(end 69.764656 -59.97575)
		(width 0.0889)
		(layer "In7.Cu")
		(net "TEMP_1_ALERT#")
	)
	(segment
		(start 86.0298 -67.129406)
		(end 82.908394 -64.008)
		(width 0.0889)
		(layer "In7.Cu")
		(net "TEMP_1_ALERT#")
	)
	(segment
		(start 43.74388 -70.32625)
		(end 20.18665 -70.32625)
		(width 0.0889)
		(layer "In7.Cu")
		(net "TEMP_1_ALERT#")
	)
	(segment
		(start 65.8876 -65.28943)
		(end 62.99073 -68.1863)
		(width 0.0889)
		(layer "In7.Cu")
		(net "TEMP_1_ALERT#")
	)
	(segment
		(start 62.99073 -68.1863)
		(end 45.88383 -68.1863)
		(width 0.0889)
		(layer "In7.Cu")
		(net "TEMP_1_ALERT#")
	)
	(segment
		(start 20.18665 -70.32625)
		(end 19.8628 -70.0024)
		(width 0.0889)
		(layer "In7.Cu")
		(net "TEMP_1_ALERT#")
	)
	(segment
		(start 82.908394 -64.008)
		(end 81.385918 -64.008)
		(width 0.0889)
		(layer "In7.Cu")
		(net "TEMP_1_ALERT#")
	)
	(segment
		(start 87.0204 -70.5866)
		(end 86.0298 -69.596)
		(width 0.0889)
		(layer "In7.Cu")
		(net "TEMP_1_ALERT#")
	)
	(segment
		(start 69.764656 -59.97575)
		(end 65.8876 -63.852806)
		(width 0.0889)
		(layer "In7.Cu")
		(net "TEMP_1_ALERT#")
	)
	(segment
		(start 155.18257 -35.29457)
		(end 153.3652 -35.29457)
		(width 0.127)
		(layer "F.Cu")
		(net "HEARTBEAT_LED")
	)
	(segment
		(start 156.954474 -33.782)
		(end 155.441904 -35.29457)
		(width 0.127)
		(layer "F.Cu")
		(net "HEARTBEAT_LED")
	)
	(segment
		(start 155.441904 -35.29457)
		(end 155.18257 -35.29457)
		(width 0.127)
		(layer "F.Cu")
		(net "HEARTBEAT_LED")
	)
	(via
		(at 155.18257 -35.29457)
		(size 0.7112)
		(drill 0.3556)
		(layers "F.Cu" "B.Cu")
		(net "HEARTBEAT_LED")
	)
	(segment
		(start 159.131 -39.3446)
		(end 159.748728 -39.3446)
		(width 0.127)
		(layer "F.Cu")
		(net "PORT80_BIT2")
	)
	(segment
		(start 161.931096 -40.095932)
		(end 162.58794 -39.439088)
		(width 0.127)
		(layer "F.Cu")
		(net "PORT80_BIT2")
	)
	(segment
		(start 159.131 -39.3446)
		(end 155.338018 -39.3446)
		(width 0.127)
		(layer "F.Cu")
		(net "PORT80_BIT2")
	)
	(segment
		(start 159.748728 -39.3446)
		(end 160.50006 -40.095932)
		(width 0.127)
		(layer "F.Cu")
		(net "PORT80_BIT2")
	)
	(segment
		(start 160.50006 -40.095932)
		(end 161.931096 -40.095932)
		(width 0.127)
		(layer "F.Cu")
		(net "PORT80_BIT2")
	)
	(segment
		(start 155.338018 -39.3446)
		(end 154.888438 -39.79418)
		(width 0.127)
		(layer "F.Cu")
		(net "PORT80_BIT2")
	)
	(segment
		(start 154.888438 -39.79418)
		(end 153.3652 -39.79418)
		(width 0.127)
		(layer "F.Cu")
		(net "PORT80_BIT2")
	)
	(via
		(at 159.131 -39.3446)
		(size 0.7112)
		(drill 0.3556)
		(layers "F.Cu" "B.Cu")
		(net "PORT80_BIT2")
	)
	(via
		(at 162.58794 -39.439088)
		(size 0.508)
		(drill 0.254)
		(layers "F.Cu" "B.Cu")
		(net "PORT80_BIT2")
	)
	(via
		(at 205.994 -35.052)
		(size 0.5588)
		(drill 0.3048)
		(layers "F.Cu" "B.Cu")
		(net "PORT80_BIT2")
	)
	(segment
		(start 205.1304 -34.1884)
		(end 205.994 -35.052)
		(width 0.127)
		(layer "B.Cu")
		(net "PORT80_BIT2")
	)
	(segment
		(start 201.922126 -34.1884)
		(end 205.1304 -34.1884)
		(width 0.127)
		(layer "B.Cu")
		(net "PORT80_BIT2")
	)
	(segment
		(start 162.58794 -39.439088)
		(end 163.126928 -38.9001)
		(width 0.127)
		(layer "In4.Cu")
		(net "PORT80_BIT2")
	)
	(segment
		(start 183.59882 -31.877)
		(end 185.20918 -31.877)
		(width 0.127)
		(layer "In4.Cu")
		(net "PORT80_BIT2")
	)
	(segment
		(start 192.137538 -30.861)
		(end 196.76618 -30.861)
		(width 0.127)
		(layer "In4.Cu")
		(net "PORT80_BIT2")
	)
	(segment
		(start 163.778438 -38.9001)
		(end 165.9509 -36.727638)
		(width 0.127)
		(layer "In4.Cu")
		(net "PORT80_BIT2")
	)
	(segment
		(start 185.47588 -32.1437)
		(end 190.854838 -32.1437)
		(width 0.127)
		(layer "In4.Cu")
		(net "PORT80_BIT2")
	)
	(segment
		(start 204.47 -33.528)
		(end 205.994 -35.052)
		(width 0.127)
		(layer "In4.Cu")
		(net "PORT80_BIT2")
	)
	(segment
		(start 163.126928 -38.9001)
		(end 163.778438 -38.9001)
		(width 0.127)
		(layer "In4.Cu")
		(net "PORT80_BIT2")
	)
	(segment
		(start 199.43318 -33.528)
		(end 204.47 -33.528)
		(width 0.127)
		(layer "In4.Cu")
		(net "PORT80_BIT2")
	)
	(segment
		(start 165.9509 -36.727638)
		(end 165.9509 -36.275772)
		(width 0.127)
		(layer "In4.Cu")
		(net "PORT80_BIT2")
	)
	(segment
		(start 169.587672 -32.639)
		(end 182.83682 -32.639)
		(width 0.127)
		(layer "In4.Cu")
		(net "PORT80_BIT2")
	)
	(segment
		(start 182.83682 -32.639)
		(end 183.59882 -31.877)
		(width 0.127)
		(layer "In4.Cu")
		(net "PORT80_BIT2")
	)
	(segment
		(start 185.20918 -31.877)
		(end 185.47588 -32.1437)
		(width 0.127)
		(layer "In4.Cu")
		(net "PORT80_BIT2")
	)
	(segment
		(start 190.854838 -32.1437)
		(end 192.137538 -30.861)
		(width 0.127)
		(layer "In4.Cu")
		(net "PORT80_BIT2")
	)
	(segment
		(start 165.9509 -36.275772)
		(end 169.587672 -32.639)
		(width 0.127)
		(layer "In4.Cu")
		(net "PORT80_BIT2")
	)
	(segment
		(start 196.76618 -30.861)
		(end 199.43318 -33.528)
		(width 0.127)
		(layer "In4.Cu")
		(net "PORT80_BIT2")
	)
	(segment
		(start 157.988 -40.4622)
		(end 157.099 -41.3512)
		(width 0.127)
		(layer "F.Cu")
		(net "PORT80_BIT5")
	)
	(segment
		(start 157.988 -40.386)
		(end 157.988 -40.4622)
		(width 0.127)
		(layer "F.Cu")
		(net "PORT80_BIT5")
	)
	(segment
		(start 156.15666 -42.29354)
		(end 153.3652 -42.29354)
		(width 0.127)
		(layer "F.Cu")
		(net "PORT80_BIT5")
	)
	(segment
		(start 157.099 -41.3512)
		(end 156.15666 -42.29354)
		(width 0.127)
		(layer "F.Cu")
		(net "PORT80_BIT5")
	)
	(via
		(at 157.988 -40.386)
		(size 0.508)
		(drill 0.254)
		(layers "F.Cu" "B.Cu")
		(net "PORT80_BIT5")
	)
	(via
		(at 205.613 -39.8526)
		(size 0.5588)
		(drill 0.3048)
		(layers "F.Cu" "B.Cu")
		(net "PORT80_BIT5")
	)
	(via
		(at 157.099 -41.3512)
		(size 0.7112)
		(drill 0.3556)
		(layers "F.Cu" "B.Cu")
		(net "PORT80_BIT5")
	)
	(segment
		(start 204.3049 -40.7543)
		(end 205.2066 -39.8526)
		(width 0.127)
		(layer "B.Cu")
		(net "PORT80_BIT5")
	)
	(segment
		(start 202.2094 -40.005)
		(end 202.9587 -40.7543)
		(width 0.127)
		(layer "B.Cu")
		(net "PORT80_BIT5")
	)
	(segment
		(start 205.2066 -39.8526)
		(end 205.613 -39.8526)
		(width 0.127)
		(layer "B.Cu")
		(net "PORT80_BIT5")
	)
	(segment
		(start 201.947526 -40.005)
		(end 202.2094 -40.005)
		(width 0.127)
		(layer "B.Cu")
		(net "PORT80_BIT5")
	)
	(segment
		(start 202.9587 -40.7543)
		(end 204.3049 -40.7543)
		(width 0.127)
		(layer "B.Cu")
		(net "PORT80_BIT5")
	)
	(segment
		(start 181.32552 -34.5567)
		(end 177.656998 -34.5567)
		(width 0.127)
		(layer "In4.Cu")
		(net "PORT80_BIT5")
	)
	(segment
		(start 185.12282 -38.354)
		(end 181.32552 -34.5567)
		(width 0.127)
		(layer "In4.Cu")
		(net "PORT80_BIT5")
	)
	(segment
		(start 177.656998 -34.5567)
		(end 171.914058 -40.29964)
		(width 0.127)
		(layer "In4.Cu")
		(net "PORT80_BIT5")
	)
	(segment
		(start 204.1144 -38.354)
		(end 185.12282 -38.354)
		(width 0.127)
		(layer "In4.Cu")
		(net "PORT80_BIT5")
	)
	(segment
		(start 160.066228 -39.6621)
		(end 158.7119 -39.6621)
		(width 0.127)
		(layer "In4.Cu")
		(net "PORT80_BIT5")
	)
	(segment
		(start 158.7119 -39.6621)
		(end 157.988 -40.386)
		(width 0.127)
		(layer "In4.Cu")
		(net "PORT80_BIT5")
	)
	(segment
		(start 171.914058 -40.29964)
		(end 160.703768 -40.29964)
		(width 0.127)
		(layer "In4.Cu")
		(net "PORT80_BIT5")
	)
	(segment
		(start 205.613 -39.8526)
		(end 204.1144 -38.354)
		(width 0.127)
		(layer "In4.Cu")
		(net "PORT80_BIT5")
	)
	(segment
		(start 160.703768 -40.29964)
		(end 160.066228 -39.6621)
		(width 0.127)
		(layer "In4.Cu")
		(net "PORT80_BIT5")
	)
	(segment
		(start 163.449 -39.37)
		(end 162.469068 -40.349932)
		(width 0.127)
		(layer "F.Cu")
		(net "PORT80_BIT3")
	)
	(segment
		(start 159.960818 -39.9161)
		(end 155.575 -39.9161)
		(width 0.127)
		(layer "F.Cu")
		(net "PORT80_BIT3")
	)
	(segment
		(start 162.469068 -40.349932)
		(end 160.39465 -40.349932)
		(width 0.127)
		(layer "F.Cu")
		(net "PORT80_BIT3")
	)
	(segment
		(start 155.575 -39.9161)
		(end 155.19654 -40.29456)
		(width 0.127)
		(layer "F.Cu")
		(net "PORT80_BIT3")
	)
	(segment
		(start 155.19654 -40.29456)
		(end 153.3652 -40.29456)
		(width 0.127)
		(layer "F.Cu")
		(net "PORT80_BIT3")
	)
	(segment
		(start 160.39465 -40.349932)
		(end 159.960818 -39.9161)
		(width 0.127)
		(layer "F.Cu")
		(net "PORT80_BIT3")
	)
	(via
		(at 206.0448 -35.9664)
		(size 0.5588)
		(drill 0.3048)
		(layers "F.Cu" "B.Cu")
		(net "PORT80_BIT3")
	)
	(via
		(at 163.449 -39.37)
		(size 0.508)
		(drill 0.254)
		(layers "F.Cu" "B.Cu")
		(net "PORT80_BIT3")
	)
	(via
		(at 155.575 -39.9161)
		(size 0.7112)
		(drill 0.3556)
		(layers "F.Cu" "B.Cu")
		(net "PORT80_BIT3")
	)
	(segment
		(start 205.613 -35.5346)
		(end 206.0448 -35.9664)
		(width 0.127)
		(layer "B.Cu")
		(net "PORT80_BIT3")
	)
	(segment
		(start 201.922126 -35.5346)
		(end 205.613 -35.5346)
		(width 0.127)
		(layer "B.Cu")
		(net "PORT80_BIT3")
	)
	(segment
		(start 185.37047 -32.3977)
		(end 190.960248 -32.3977)
		(width 0.127)
		(layer "In4.Cu")
		(net "PORT80_BIT3")
	)
	(segment
		(start 182.94223 -32.893)
		(end 183.70423 -32.131)
		(width 0.127)
		(layer "In4.Cu")
		(net "PORT80_BIT3")
	)
	(segment
		(start 196.66077 -31.115)
		(end 199.32777 -33.782)
		(width 0.127)
		(layer "In4.Cu")
		(net "PORT80_BIT3")
	)
	(segment
		(start 199.32777 -33.782)
		(end 203.8604 -33.782)
		(width 0.127)
		(layer "In4.Cu")
		(net "PORT80_BIT3")
	)
	(segment
		(start 163.449 -39.37)
		(end 163.667948 -39.37)
		(width 0.127)
		(layer "In4.Cu")
		(net "PORT80_BIT3")
	)
	(segment
		(start 166.2049 -36.833048)
		(end 166.2049 -36.381182)
		(width 0.127)
		(layer "In4.Cu")
		(net "PORT80_BIT3")
	)
	(segment
		(start 183.70423 -32.131)
		(end 185.10377 -32.131)
		(width 0.127)
		(layer "In4.Cu")
		(net "PORT80_BIT3")
	)
	(segment
		(start 190.960248 -32.3977)
		(end 192.242948 -31.115)
		(width 0.127)
		(layer "In4.Cu")
		(net "PORT80_BIT3")
	)
	(segment
		(start 185.10377 -32.131)
		(end 185.37047 -32.3977)
		(width 0.127)
		(layer "In4.Cu")
		(net "PORT80_BIT3")
	)
	(segment
		(start 169.693082 -32.893)
		(end 182.94223 -32.893)
		(width 0.127)
		(layer "In4.Cu")
		(net "PORT80_BIT3")
	)
	(segment
		(start 192.242948 -31.115)
		(end 196.66077 -31.115)
		(width 0.127)
		(layer "In4.Cu")
		(net "PORT80_BIT3")
	)
	(segment
		(start 203.8604 -33.782)
		(end 206.0448 -35.9664)
		(width 0.127)
		(layer "In4.Cu")
		(net "PORT80_BIT3")
	)
	(segment
		(start 163.667948 -39.37)
		(end 166.2049 -36.833048)
		(width 0.127)
		(layer "In4.Cu")
		(net "PORT80_BIT3")
	)
	(segment
		(start 166.2049 -36.381182)
		(end 169.693082 -32.893)
		(width 0.127)
		(layer "In4.Cu")
		(net "PORT80_BIT3")
	)
	(segment
		(start 160.668208 -39.841932)
		(end 159.599376 -38.7731)
		(width 0.127)
		(layer "F.Cu")
		(net "PORT80_BIT1")
	)
	(segment
		(start 155.2829 -38.7731)
		(end 154.7622 -39.2938)
		(width 0.127)
		(layer "F.Cu")
		(net "PORT80_BIT1")
	)
	(segment
		(start 154.7622 -39.2938)
		(end 153.3652 -39.2938)
		(width 0.127)
		(layer "F.Cu")
		(net "PORT80_BIT1")
	)
	(segment
		(start 161.247582 -39.841932)
		(end 160.668208 -39.841932)
		(width 0.127)
		(layer "F.Cu")
		(net "PORT80_BIT1")
	)
	(segment
		(start 159.599376 -38.7731)
		(end 156.845 -38.7731)
		(width 0.127)
		(layer "F.Cu")
		(net "PORT80_BIT1")
	)
	(segment
		(start 161.726626 -39.362888)
		(end 161.247582 -39.841932)
		(width 0.127)
		(layer "F.Cu")
		(net "PORT80_BIT1")
	)
	(segment
		(start 156.845 -38.7731)
		(end 155.2829 -38.7731)
		(width 0.127)
		(layer "F.Cu")
		(net "PORT80_BIT1")
	)
	(via
		(at 156.845 -38.7731)
		(size 0.7112)
		(drill 0.3556)
		(layers "F.Cu" "B.Cu")
		(net "PORT80_BIT1")
	)
	(via
		(at 161.726626 -39.362888)
		(size 0.508)
		(drill 0.254)
		(layers "F.Cu" "B.Cu")
		(net "PORT80_BIT1")
	)
	(via
		(at 205.994 -34.036)
		(size 0.5588)
		(drill 0.3048)
		(layers "F.Cu" "B.Cu")
		(net "PORT80_BIT1")
	)
	(segment
		(start 202.607926 -33.528)
		(end 201.922126 -32.8422)
		(width 0.127)
		(layer "B.Cu")
		(net "PORT80_BIT1")
	)
	(segment
		(start 205.994 -34.036)
		(end 205.486 -33.528)
		(width 0.127)
		(layer "B.Cu")
		(net "PORT80_BIT1")
	)
	(segment
		(start 205.486 -33.528)
		(end 202.607926 -33.528)
		(width 0.127)
		(layer "B.Cu")
		(net "PORT80_BIT1")
	)
	(segment
		(start 163.673028 -38.6461)
		(end 165.6969 -36.622228)
		(width 0.127)
		(layer "In4.Cu")
		(net "PORT80_BIT1")
	)
	(segment
		(start 162.443414 -38.6461)
		(end 163.673028 -38.6461)
		(width 0.127)
		(layer "In4.Cu")
		(net "PORT80_BIT1")
	)
	(segment
		(start 182.73141 -32.385)
		(end 183.49341 -31.623)
		(width 0.127)
		(layer "In4.Cu")
		(net "PORT80_BIT1")
	)
	(segment
		(start 185.31459 -31.623)
		(end 185.58129 -31.8897)
		(width 0.127)
		(layer "In4.Cu")
		(net "PORT80_BIT1")
	)
	(segment
		(start 183.49341 -31.623)
		(end 185.31459 -31.623)
		(width 0.127)
		(layer "In4.Cu")
		(net "PORT80_BIT1")
	)
	(segment
		(start 165.6969 -36.622228)
		(end 165.6969 -36.170362)
		(width 0.127)
		(layer "In4.Cu")
		(net "PORT80_BIT1")
	)
	(segment
		(start 190.749428 -31.8897)
		(end 192.032128 -30.607)
		(width 0.127)
		(layer "In4.Cu")
		(net "PORT80_BIT1")
	)
	(segment
		(start 169.482262 -32.385)
		(end 182.73141 -32.385)
		(width 0.127)
		(layer "In4.Cu")
		(net "PORT80_BIT1")
	)
	(segment
		(start 199.53859 -33.274)
		(end 205.232 -33.274)
		(width 0.127)
		(layer "In4.Cu")
		(net "PORT80_BIT1")
	)
	(segment
		(start 185.58129 -31.8897)
		(end 190.749428 -31.8897)
		(width 0.127)
		(layer "In4.Cu")
		(net "PORT80_BIT1")
	)
	(segment
		(start 205.232 -33.274)
		(end 205.994 -34.036)
		(width 0.127)
		(layer "In4.Cu")
		(net "PORT80_BIT1")
	)
	(segment
		(start 196.87159 -30.607)
		(end 199.53859 -33.274)
		(width 0.127)
		(layer "In4.Cu")
		(net "PORT80_BIT1")
	)
	(segment
		(start 161.726626 -39.362888)
		(end 162.443414 -38.6461)
		(width 0.127)
		(layer "In4.Cu")
		(net "PORT80_BIT1")
	)
	(segment
		(start 165.6969 -36.170362)
		(end 169.482262 -32.385)
		(width 0.127)
		(layer "In4.Cu")
		(net "PORT80_BIT1")
	)
	(segment
		(start 192.032128 -30.607)
		(end 196.87159 -30.607)
		(width 0.127)
		(layer "In4.Cu")
		(net "PORT80_BIT1")
	)
	(segment
		(start 158.877 -40.792146)
		(end 158.4198 -41.249346)
		(width 0.127)
		(layer "F.Cu")
		(net "PORT80_BIT6")
	)
	(segment
		(start 158.877 -40.386)
		(end 158.877 -40.792146)
		(width 0.127)
		(layer "F.Cu")
		(net "PORT80_BIT6")
	)
	(segment
		(start 158.4198 -41.249346)
		(end 156.875226 -42.79392)
		(width 0.127)
		(layer "F.Cu")
		(net "PORT80_BIT6")
	)
	(segment
		(start 156.875226 -42.79392)
		(end 153.3652 -42.79392)
		(width 0.127)
		(layer "F.Cu")
		(net "PORT80_BIT6")
	)
	(via
		(at 158.4198 -41.249346)
		(size 0.7112)
		(drill 0.3556)
		(layers "F.Cu" "B.Cu")
		(net "PORT80_BIT6")
	)
	(via
		(at 205.6384 -40.767)
		(size 0.5588)
		(drill 0.3048)
		(layers "F.Cu" "B.Cu")
		(net "PORT80_BIT6")
	)
	(via
		(at 158.877 -40.386)
		(size 0.508)
		(drill 0.254)
		(layers "F.Cu" "B.Cu")
		(net "PORT80_BIT6")
	)
	(segment
		(start 204.9272 -40.767)
		(end 205.6384 -40.767)
		(width 0.127)
		(layer "B.Cu")
		(net "PORT80_BIT6")
	)
	(segment
		(start 201.947526 -41.3258)
		(end 204.3684 -41.3258)
		(width 0.127)
		(layer "B.Cu")
		(net "PORT80_BIT6")
	)
	(segment
		(start 204.3684 -41.3258)
		(end 204.9272 -40.767)
		(width 0.127)
		(layer "B.Cu")
		(net "PORT80_BIT6")
	)
	(segment
		(start 203.4794 -38.608)
		(end 205.6384 -40.767)
		(width 0.127)
		(layer "In4.Cu")
		(net "PORT80_BIT6")
	)
	(segment
		(start 181.22011 -34.8107)
		(end 185.01741 -38.608)
		(width 0.127)
		(layer "In4.Cu")
		(net "PORT80_BIT6")
	)
	(segment
		(start 185.01741 -38.608)
		(end 203.4794 -38.608)
		(width 0.127)
		(layer "In4.Cu")
		(net "PORT80_BIT6")
	)
	(segment
		(start 160.598358 -40.55364)
		(end 172.019468 -40.55364)
		(width 0.127)
		(layer "In4.Cu")
		(net "PORT80_BIT6")
	)
	(segment
		(start 177.762408 -34.8107)
		(end 181.22011 -34.8107)
		(width 0.127)
		(layer "In4.Cu")
		(net "PORT80_BIT6")
	)
	(segment
		(start 159.960818 -39.9161)
		(end 160.598358 -40.55364)
		(width 0.127)
		(layer "In4.Cu")
		(net "PORT80_BIT6")
	)
	(segment
		(start 159.3469 -39.9161)
		(end 159.960818 -39.9161)
		(width 0.127)
		(layer "In4.Cu")
		(net "PORT80_BIT6")
	)
	(segment
		(start 158.877 -40.386)
		(end 159.3469 -39.9161)
		(width 0.127)
		(layer "In4.Cu")
		(net "PORT80_BIT6")
	)
	(segment
		(start 172.019468 -40.55364)
		(end 177.762408 -34.8107)
		(width 0.127)
		(layer "In4.Cu")
		(net "PORT80_BIT6")
	)
	(segment
		(start 157.099 -40.386)
		(end 156.765244 -40.386)
		(width 0.127)
		(layer "F.Cu")
		(net "PORT80_BIT4")
	)
	(segment
		(start 155.369768 -41.781476)
		(end 155.369768 -41.79443)
		(width 0.127)
		(layer "F.Cu")
		(net "PORT80_BIT4")
	)
	(segment
		(start 156.765244 -40.386)
		(end 155.85186 -41.299384)
		(width 0.127)
		(layer "F.Cu")
		(net "PORT80_BIT4")
	)
	(segment
		(start 155.369768 -41.79443)
		(end 153.3652 -41.79443)
		(width 0.127)
		(layer "F.Cu")
		(net "PORT80_BIT4")
	)
	(segment
		(start 155.85186 -41.299384)
		(end 155.369768 -41.781476)
		(width 0.127)
		(layer "F.Cu")
		(net "PORT80_BIT4")
	)
	(via
		(at 205.486 -37.8968)
		(size 0.5588)
		(drill 0.3048)
		(layers "F.Cu" "B.Cu")
		(net "PORT80_BIT4")
	)
	(via
		(at 155.85186 -41.299384)
		(size 0.7112)
		(drill 0.3556)
		(layers "F.Cu" "B.Cu")
		(net "PORT80_BIT4")
	)
	(via
		(at 157.099 -40.386)
		(size 0.508)
		(drill 0.254)
		(layers "F.Cu" "B.Cu")
		(net "PORT80_BIT4")
	)
	(segment
		(start 203.8604 -38.6842)
		(end 204.6478 -37.8968)
		(width 0.127)
		(layer "B.Cu")
		(net "PORT80_BIT4")
	)
	(segment
		(start 204.6478 -37.8968)
		(end 205.486 -37.8968)
		(width 0.127)
		(layer "B.Cu")
		(net "PORT80_BIT4")
	)
	(segment
		(start 201.947526 -38.6842)
		(end 203.8604 -38.6842)
		(width 0.127)
		(layer "B.Cu")
		(net "PORT80_BIT4")
	)
	(segment
		(start 165.31336 -40.04564)
		(end 166.031418 -39.327582)
		(width 0.127)
		(layer "In4.Cu")
		(net "PORT80_BIT4")
	)
	(segment
		(start 166.031418 -39.327582)
		(end 172.526706 -39.327582)
		(width 0.127)
		(layer "In4.Cu")
		(net "PORT80_BIT4")
	)
	(segment
		(start 185.20537 -38.07714)
		(end 205.30566 -38.07714)
		(width 0.127)
		(layer "In4.Cu")
		(net "PORT80_BIT4")
	)
	(segment
		(start 172.526706 -39.327582)
		(end 177.551588 -34.3027)
		(width 0.127)
		(layer "In4.Cu")
		(net "PORT80_BIT4")
	)
	(segment
		(start 205.30566 -38.07714)
		(end 205.486 -37.8968)
		(width 0.127)
		(layer "In4.Cu")
		(net "PORT80_BIT4")
	)
	(segment
		(start 160.171638 -39.4081)
		(end 160.809178 -40.04564)
		(width 0.127)
		(layer "In4.Cu")
		(net "PORT80_BIT4")
	)
	(segment
		(start 158.301182 -39.4081)
		(end 160.171638 -39.4081)
		(width 0.127)
		(layer "In4.Cu")
		(net "PORT80_BIT4")
	)
	(segment
		(start 181.43093 -34.3027)
		(end 185.20537 -38.07714)
		(width 0.127)
		(layer "In4.Cu")
		(net "PORT80_BIT4")
	)
	(segment
		(start 160.809178 -40.04564)
		(end 165.31336 -40.04564)
		(width 0.127)
		(layer "In4.Cu")
		(net "PORT80_BIT4")
	)
	(segment
		(start 157.099 -40.386)
		(end 157.323282 -40.386)
		(width 0.127)
		(layer "In4.Cu")
		(net "PORT80_BIT4")
	)
	(segment
		(start 157.323282 -40.386)
		(end 158.301182 -39.4081)
		(width 0.127)
		(layer "In4.Cu")
		(net "PORT80_BIT4")
	)
	(segment
		(start 177.551588 -34.3027)
		(end 181.43093 -34.3027)
		(width 0.127)
		(layer "In4.Cu")
		(net "PORT80_BIT4")
	)
	(segment
		(start 159.591248 -38.1)
		(end 158.369 -38.1)
		(width 0.127)
		(layer "F.Cu")
		(net "PORT80_BIT0")
	)
	(segment
		(start 158.369 -38.1)
		(end 155.194 -38.1)
		(width 0.127)
		(layer "F.Cu")
		(net "PORT80_BIT0")
	)
	(segment
		(start 160.863026 -39.372032)
		(end 159.591248 -38.1)
		(width 0.127)
		(layer "F.Cu")
		(net "PORT80_BIT0")
	)
	(segment
		(start 154.50058 -38.79342)
		(end 153.3652 -38.79342)
		(width 0.127)
		(layer "F.Cu")
		(net "PORT80_BIT0")
	)
	(segment
		(start 155.194 -38.1)
		(end 154.50058 -38.79342)
		(width 0.127)
		(layer "F.Cu")
		(net "PORT80_BIT0")
	)
	(via
		(at 205.994 -33.02)
		(size 0.5588)
		(drill 0.3048)
		(layers "F.Cu" "B.Cu")
		(net "PORT80_BIT0")
	)
	(via
		(at 158.369 -38.1)
		(size 0.7112)
		(drill 0.3556)
		(layers "F.Cu" "B.Cu")
		(net "PORT80_BIT0")
	)
	(via
		(at 160.863026 -39.372032)
		(size 0.508)
		(drill 0.254)
		(layers "F.Cu" "B.Cu")
		(net "PORT80_BIT0")
	)
	(segment
		(start 205.994 -33.02)
		(end 203.388468 -33.02)
		(width 0.127)
		(layer "B.Cu")
		(net "PORT80_BIT0")
	)
	(segment
		(start 203.388468 -33.02)
		(end 202.4507 -32.082232)
		(width 0.127)
		(layer "B.Cu")
		(net "PORT80_BIT0")
	)
	(segment
		(start 202.4507 -32.024574)
		(end 201.922126 -31.496)
		(width 0.127)
		(layer "B.Cu")
		(net "PORT80_BIT0")
	)
	(segment
		(start 202.4507 -32.082232)
		(end 202.4507 -32.024574)
		(width 0.127)
		(layer "B.Cu")
		(net "PORT80_BIT0")
	)
	(segment
		(start 182.626 -32.131)
		(end 183.388 -31.369)
		(width 0.127)
		(layer "In4.Cu")
		(net "PORT80_BIT0")
	)
	(segment
		(start 190.644018 -31.6357)
		(end 191.926718 -30.353)
		(width 0.127)
		(layer "In4.Cu")
		(net "PORT80_BIT0")
	)
	(segment
		(start 199.644 -33.02)
		(end 205.994 -33.02)
		(width 0.127)
		(layer "In4.Cu")
		(net "PORT80_BIT0")
	)
	(segment
		(start 185.6867 -31.6357)
		(end 190.644018 -31.6357)
		(width 0.127)
		(layer "In4.Cu")
		(net "PORT80_BIT0")
	)
	(segment
		(start 161.842958 -38.3921)
		(end 163.567618 -38.3921)
		(width 0.127)
		(layer "In4.Cu")
		(net "PORT80_BIT0")
	)
	(segment
		(start 160.863026 -39.372032)
		(end 161.842958 -38.3921)
		(width 0.127)
		(layer "In4.Cu")
		(net "PORT80_BIT0")
	)
	(segment
		(start 183.388 -31.369)
		(end 185.42 -31.369)
		(width 0.127)
		(layer "In4.Cu")
		(net "PORT80_BIT0")
	)
	(segment
		(start 185.42 -31.369)
		(end 185.6867 -31.6357)
		(width 0.127)
		(layer "In4.Cu")
		(net "PORT80_BIT0")
	)
	(segment
		(start 191.926718 -30.353)
		(end 196.977 -30.353)
		(width 0.127)
		(layer "In4.Cu")
		(net "PORT80_BIT0")
	)
	(segment
		(start 165.4429 -36.064952)
		(end 169.376852 -32.131)
		(width 0.127)
		(layer "In4.Cu")
		(net "PORT80_BIT0")
	)
	(segment
		(start 165.4429 -36.516818)
		(end 165.4429 -36.064952)
		(width 0.127)
		(layer "In4.Cu")
		(net "PORT80_BIT0")
	)
	(segment
		(start 196.977 -30.353)
		(end 199.644 -33.02)
		(width 0.127)
		(layer "In4.Cu")
		(net "PORT80_BIT0")
	)
	(segment
		(start 163.567618 -38.3921)
		(end 165.4429 -36.516818)
		(width 0.127)
		(layer "In4.Cu")
		(net "PORT80_BIT0")
	)
	(segment
		(start 169.376852 -32.131)
		(end 182.626 -32.131)
		(width 0.127)
		(layer "In4.Cu")
		(net "PORT80_BIT0")
	)
	(segment
		(start 161.9123 -33.7439)
		(end 161.036 -34.6202)
		(width 0.1143)
		(layer "F.Cu")
		(net "DISABLE")
	)
	(segment
		(start 159.73425 -25.790906)
		(end 160.0708 -26.127456)
		(width 0.1143)
		(layer "F.Cu")
		(net "DISABLE")
	)
	(segment
		(start 160.401 -21.126958)
		(end 160.401 -24.22525)
		(width 0.1143)
		(layer "F.Cu")
		(net "DISABLE")
	)
	(segment
		(start 157.4546 -34.6964)
		(end 154.35707 -37.79393)
		(width 0.1143)
		(layer "F.Cu")
		(net "DISABLE")
	)
	(segment
		(start 160.9598 -34.6964)
		(end 161.036 -34.6202)
		(width 0.1143)
		(layer "F.Cu")
		(net "DISABLE")
	)
	(segment
		(start 161.9123 -29.628338)
		(end 161.9123 -33.7439)
		(width 0.1143)
		(layer "F.Cu")
		(net "DISABLE")
	)
	(segment
		(start 160.0708 -26.127456)
		(end 160.0708 -27.786838)
		(width 0.1143)
		(layer "F.Cu")
		(net "DISABLE")
	)
	(segment
		(start 159.73425 -24.892)
		(end 159.73425 -25.790906)
		(width 0.1143)
		(layer "F.Cu")
		(net "DISABLE")
	)
	(segment
		(start 160.401 -24.22525)
		(end 159.73425 -24.892)
		(width 0.1143)
		(layer "F.Cu")
		(net "DISABLE")
	)
	(segment
		(start 160.02 -34.6964)
		(end 160.9598 -34.6964)
		(width 0.1143)
		(layer "F.Cu")
		(net "DISABLE")
	)
	(segment
		(start 158.490158 -21.126958)
		(end 160.401 -21.126958)
		(width 0.1143)
		(layer "F.Cu")
		(net "DISABLE")
	)
	(segment
		(start 158.115 -20.7518)
		(end 158.490158 -21.126958)
		(width 0.1143)
		(layer "F.Cu")
		(net "DISABLE")
	)
	(segment
		(start 154.35707 -37.79393)
		(end 153.3652 -37.79393)
		(width 0.1143)
		(layer "F.Cu")
		(net "DISABLE")
	)
	(segment
		(start 160.0708 -27.786838)
		(end 161.9123 -29.628338)
		(width 0.1143)
		(layer "F.Cu")
		(net "DISABLE")
	)
	(segment
		(start 160.02 -34.6964)
		(end 157.4546 -34.6964)
		(width 0.1143)
		(layer "F.Cu")
		(net "DISABLE")
	)
	(via
		(at 160.02 -34.6964)
		(size 0.7112)
		(drill 0.3556)
		(layers "F.Cu" "B.Cu")
		(net "DISABLE")
	)
	(segment
		(start 145.99793 -23.9268)
		(end 145.99793 -22.68347)
		(width 0.1143)
		(layer "F.Cu")
		(net "MSEL2")
	)
	(segment
		(start 145.99793 -22.68347)
		(end 146.05 -22.6314)
		(width 0.1143)
		(layer "F.Cu")
		(net "MSEL2")
	)
	(via
		(at 146.05 -22.6314)
		(size 0.508)
		(drill 0.254)
		(layers "F.Cu" "B.Cu")
		(net "MSEL2")
	)
	(via
		(at 146.4818 -24.4094)
		(size 0.7112)
		(drill 0.3556)
		(layers "F.Cu" "B.Cu")
		(net "MSEL2")
	)
	(segment
		(start 146.05 -22.6822)
		(end 146.05 -22.6314)
		(width 0.1143)
		(layer "B.Cu")
		(net "MSEL2")
	)
	(segment
		(start 146.4818 -23.114)
		(end 146.05 -22.6822)
		(width 0.1143)
		(layer "B.Cu")
		(net "MSEL2")
	)
	(segment
		(start 146.4818 -24.4094)
		(end 146.4818 -23.495)
		(width 0.1143)
		(layer "B.Cu")
		(net "MSEL2")
	)
	(segment
		(start 146.4818 -23.495)
		(end 146.4818 -23.114)
		(width 0.1143)
		(layer "B.Cu")
		(net "MSEL2")
	)
	(segment
		(start 145.6944 -20.2692)
		(end 145.6182 -20.3454)
		(width 0.1143)
		(layer "F.Cu")
		(net "MSEL1")
	)
	(segment
		(start 145.49755 -20.46605)
		(end 145.6182 -20.3454)
		(width 0.1143)
		(layer "F.Cu")
		(net "MSEL1")
	)
	(segment
		(start 146.558 -20.2692)
		(end 145.6944 -20.2692)
		(width 0.1143)
		(layer "F.Cu")
		(net "MSEL1")
	)
	(segment
		(start 145.49755 -23.9268)
		(end 145.49755 -20.46605)
		(width 0.1143)
		(layer "F.Cu")
		(net "MSEL1")
	)
	(via
		(at 145.6182 -20.3454)
		(size 0.7112)
		(drill 0.3556)
		(layers "F.Cu" "B.Cu")
		(net "MSEL1")
	)
	(segment
		(start 153.9621 -25.7937)
		(end 154.4828 -25.273)
		(width 0.3048)
		(layer "F.Cu")
		(net "P1V2_FPGA_A")
	)
	(segment
		(start 130.7592 -46.5836)
		(end 130.7592 -45.466)
		(width 0.3048)
		(layer "F.Cu")
		(net "P1V2_FPGA_A")
	)
	(segment
		(start 132.1308 -43.2943)
		(end 131.2037 -43.2943)
		(width 0.3048)
		(layer "F.Cu")
		(net "P1V2_FPGA_A")
	)
	(segment
		(start 167.066976 -35.433)
		(end 167.2336 -35.433)
		(width 0.3048)
		(layer "F.Cu")
		(net "P1V2_FPGA_A")
	)
	(segment
		(start 161.544 -24.765)
		(end 164.42055 -27.64155)
		(width 0.3048)
		(layer "F.Cu")
		(net "P1V2_FPGA_A")
	)
	(segment
		(start 130.81 -43.688)
		(end 130.81 -44.6532)
		(width 0.3048)
		(layer "F.Cu")
		(net "P1V2_FPGA_A")
	)
	(segment
		(start 161.036 -24.765)
		(end 161.544 -24.765)
		(width 0.3048)
		(layer "F.Cu")
		(net "P1V2_FPGA_A")
	)
	(segment
		(start 164.42055 -27.64155)
		(end 164.42055 -32.786574)
		(width 0.3048)
		(layer "F.Cu")
		(net "P1V2_FPGA_A")
	)
	(segment
		(start 154.4828 -23.622)
		(end 154.4828 -24.384)
		(width 0.3048)
		(layer "F.Cu")
		(net "P1V2_FPGA_A")
	)
	(segment
		(start 154.4828 -22.7838)
		(end 154.4828 -23.622)
		(width 0.3048)
		(layer "F.Cu")
		(net "P1V2_FPGA_A")
	)
	(segment
		(start 166.745158 -37.600382)
		(end 167.2336 -37.11194)
		(width 0.3048)
		(layer "F.Cu")
		(net "P1V2_FPGA_A")
	)
	(segment
		(start 154.4828 -25.273)
		(end 154.4828 -24.384)
		(width 0.3048)
		(layer "F.Cu")
		(net "P1V2_FPGA_A")
	)
	(segment
		(start 167.2336 -37.11194)
		(end 167.2336 -35.433)
		(width 0.3048)
		(layer "F.Cu")
		(net "P1V2_FPGA_A")
	)
	(segment
		(start 131.2037 -43.2943)
		(end 130.81 -43.688)
		(width 0.3048)
		(layer "F.Cu")
		(net "P1V2_FPGA_A")
	)
	(segment
		(start 152.273 -22.225)
		(end 153.924 -22.225)
		(width 0.3048)
		(layer "F.Cu")
		(net "P1V2_FPGA_A")
	)
	(segment
		(start 164.42055 -32.786574)
		(end 167.066976 -35.433)
		(width 0.3048)
		(layer "F.Cu")
		(net "P1V2_FPGA_A")
	)
	(segment
		(start 130.7592 -45.466)
		(end 130.7592 -44.704)
		(width 0.3048)
		(layer "F.Cu")
		(net "P1V2_FPGA_A")
	)
	(segment
		(start 130.81 -44.6532)
		(end 130.7592 -44.704)
		(width 0.3048)
		(layer "F.Cu")
		(net "P1V2_FPGA_A")
	)
	(segment
		(start 153.924 -22.225)
		(end 154.4828 -22.7838)
		(width 0.3048)
		(layer "F.Cu")
		(net "P1V2_FPGA_A")
	)
	(segment
		(start 153.3652 -25.7937)
		(end 153.9621 -25.7937)
		(width 0.3048)
		(layer "F.Cu")
		(net "P1V2_FPGA_A")
	)
	(via
		(at 161.036 -24.765)
		(size 0.508)
		(drill 0.254)
		(layers "F.Cu" "B.Cu")
		(net "P1V2_FPGA_A")
	)
	(via
		(at 137.606278 -40.144192)
		(size 0.7112)
		(drill 0.3556)
		(layers "F.Cu" "B.Cu")
		(net "P1V2_FPGA_A")
	)
	(via
		(at 166.745158 -37.600382)
		(size 0.508)
		(drill 0.254)
		(layers "F.Cu" "B.Cu")
		(net "P1V2_FPGA_A")
	)
	(via
		(at 152.273 -22.225)
		(size 0.508)
		(drill 0.254)
		(layers "F.Cu" "B.Cu")
		(net "P1V2_FPGA_A")
	)
	(via
		(at 130.7592 -46.5836)
		(size 0.508)
		(drill 0.254)
		(layers "F.Cu" "B.Cu")
		(net "P1V2_FPGA_A")
	)
	(segment
		(start 130.7592 -46.9392)
		(end 130.7592 -46.5836)
		(width 0.3048)
		(layer "B.Cu")
		(net "P1V2_FPGA_A")
	)
	(segment
		(start 137.606278 -40.144192)
		(end 132.3594 -45.39107)
		(width 0.3048)
		(layer "B.Cu")
		(net "P1V2_FPGA_A")
	)
	(segment
		(start 154.906218 -37.600382)
		(end 153.2636 -39.243)
		(width 0.3048)
		(layer "B.Cu")
		(net "P1V2_FPGA_A")
	)
	(segment
		(start 131.8768 -47.244)
		(end 131.064 -47.244)
		(width 0.3048)
		(layer "B.Cu")
		(net "P1V2_FPGA_A")
	)
	(segment
		(start 132.3594 -45.39107)
		(end 132.3594 -46.7614)
		(width 0.3048)
		(layer "B.Cu")
		(net "P1V2_FPGA_A")
	)
	(segment
		(start 166.745158 -37.600382)
		(end 154.906218 -37.600382)
		(width 0.3048)
		(layer "B.Cu")
		(net "P1V2_FPGA_A")
	)
	(segment
		(start 131.064 -47.244)
		(end 130.7592 -46.9392)
		(width 0.3048)
		(layer "B.Cu")
		(net "P1V2_FPGA_A")
	)
	(segment
		(start 153.2636 -39.243)
		(end 138.50747 -39.243)
		(width 0.3048)
		(layer "B.Cu")
		(net "P1V2_FPGA_A")
	)
	(segment
		(start 138.50747 -39.243)
		(end 137.606278 -40.144192)
		(width 0.3048)
		(layer "B.Cu")
		(net "P1V2_FPGA_A")
	)
	(segment
		(start 132.3594 -46.7614)
		(end 131.8768 -47.244)
		(width 0.3048)
		(layer "B.Cu")
		(net "P1V2_FPGA_A")
	)
	(segment
		(start 158.496 -22.225)
		(end 161.036 -24.765)
		(width 0.508)
		(layer "B.Cu")
		(net "P1V2_FPGA_A")
	)
	(segment
		(start 152.273 -22.225)
		(end 158.496 -22.225)
		(width 0.508)
		(layer "B.Cu")
		(net "P1V2_FPGA_A")
	)
	(segment
		(start 144.907 -20.32)
		(end 144.907 -21.59)
		(width 0.1143)
		(layer "F.Cu")
		(net "MSEL0")
	)
	(segment
		(start 144.3228 -19.7358)
		(end 144.907 -20.32)
		(width 0.1143)
		(layer "F.Cu")
		(net "MSEL0")
	)
	(segment
		(start 144.49806 -22.439122)
		(end 144.907 -22.030182)
		(width 0.1143)
		(layer "F.Cu")
		(net "MSEL0")
	)
	(segment
		(start 143.891 -19.7358)
		(end 144.3228 -19.7358)
		(width 0.1143)
		(layer "F.Cu")
		(net "MSEL0")
	)
	(segment
		(start 144.49806 -23.9268)
		(end 144.49806 -22.439122)
		(width 0.1143)
		(layer "F.Cu")
		(net "MSEL0")
	)
	(segment
		(start 144.907 -22.030182)
		(end 144.907 -21.59)
		(width 0.1143)
		(layer "F.Cu")
		(net "MSEL0")
	)
	(via
		(at 144.907 -21.59)
		(size 0.7112)
		(drill 0.3556)
		(layers "F.Cu" "B.Cu")
		(net "MSEL0")
	)
	(segment
		(start 137.9728 -51.9684)
		(end 137.9728 -49.8602)
		(width 0.1143)
		(layer "F.Cu")
		(net "C_NCONFIG#")
	)
	(segment
		(start 137.9728 -49.8602)
		(end 138.176 -49.657)
		(width 0.1143)
		(layer "F.Cu")
		(net "C_NCONFIG#")
	)
	(segment
		(start 141.859 -49.403)
		(end 141.958314 -49.403)
		(width 0.1143)
		(layer "F.Cu")
		(net "C_NCONFIG#")
	)
	(segment
		(start 145.06448 -46.37659)
		(end 144.99844 -46.31055)
		(width 0.1143)
		(layer "F.Cu")
		(net "C_NCONFIG#")
	)
	(segment
		(start 138.176 -49.657)
		(end 139.107926 -49.657)
		(width 0.1143)
		(layer "F.Cu")
		(net "C_NCONFIG#")
	)
	(segment
		(start 141.4272 -48.9712)
		(end 141.859 -49.403)
		(width 0.1143)
		(layer "F.Cu")
		(net "C_NCONFIG#")
	)
	(segment
		(start 144.315942 -47.045372)
		(end 144.758918 -47.045372)
		(width 0.1143)
		(layer "F.Cu")
		(net "C_NCONFIG#")
	)
	(segment
		(start 141.4272 -48.26)
		(end 141.4272 -48.9712)
		(width 0.1143)
		(layer "F.Cu")
		(net "C_NCONFIG#")
	)
	(segment
		(start 144.758918 -47.045372)
		(end 145.06448 -46.73981)
		(width 0.1143)
		(layer "F.Cu")
		(net "C_NCONFIG#")
	)
	(segment
		(start 140.335 -48.26)
		(end 139.107926 -49.487074)
		(width 0.1143)
		(layer "F.Cu")
		(net "C_NCONFIG#")
	)
	(segment
		(start 144.99844 -46.31055)
		(end 144.99844 -45.1612)
		(width 0.1143)
		(layer "F.Cu")
		(net "C_NCONFIG#")
	)
	(segment
		(start 145.06448 -46.73981)
		(end 145.06448 -46.37659)
		(width 0.1143)
		(layer "F.Cu")
		(net "C_NCONFIG#")
	)
	(segment
		(start 141.958314 -49.403)
		(end 144.315942 -47.045372)
		(width 0.1143)
		(layer "F.Cu")
		(net "C_NCONFIG#")
	)
	(segment
		(start 139.107926 -49.487074)
		(end 139.107926 -49.657)
		(width 0.1143)
		(layer "F.Cu")
		(net "C_NCONFIG#")
	)
	(segment
		(start 141.4272 -48.26)
		(end 140.335 -48.26)
		(width 0.1143)
		(layer "F.Cu")
		(net "C_NCONFIG#")
	)
	(segment
		(start 162.450526 -42.545)
		(end 163.301426 -43.3959)
		(width 0.127)
		(layer "F.Cu")
		(net "C_NSTATUS#")
	)
	(segment
		(start 147.01393 -46.5582)
		(end 147.01393 -46.31817)
		(width 0.127)
		(layer "F.Cu")
		(net "C_NSTATUS#")
	)
	(segment
		(start 147.01393 -46.31817)
		(end 147.4978 -45.8343)
		(width 0.127)
		(layer "F.Cu")
		(net "C_NSTATUS#")
	)
	(segment
		(start 147.4978 -45.8343)
		(end 147.4978 -45.1612)
		(width 0.127)
		(layer "F.Cu")
		(net "C_NSTATUS#")
	)
	(segment
		(start 167.1447 -43.3959)
		(end 167.894 -44.1452)
		(width 0.127)
		(layer "F.Cu")
		(net "C_NSTATUS#")
	)
	(segment
		(start 163.301426 -43.3959)
		(end 167.1447 -43.3959)
		(width 0.127)
		(layer "F.Cu")
		(net "C_NSTATUS#")
	)
	(via
		(at 147.01393 -46.5582)
		(size 0.508)
		(drill 0.254)
		(layers "F.Cu" "B.Cu")
		(net "C_NSTATUS#")
	)
	(via
		(at 167.894 -44.1452)
		(size 0.508)
		(drill 0.254)
		(layers "F.Cu" "B.Cu")
		(net "C_NSTATUS#")
	)
	(via
		(at 159.385 -44.2722)
		(size 0.7112)
		(drill 0.3556)
		(layers "F.Cu" "B.Cu")
		(net "C_NSTATUS#")
	)
	(segment
		(start 146.993356 -46.5582)
		(end 147.01393 -46.5582)
		(width 0.127)
		(layer "B.Cu")
		(net "C_NSTATUS#")
	)
	(segment
		(start 146.431 -45.3898)
		(end 146.431 -45.995844)
		(width 0.127)
		(layer "B.Cu")
		(net "C_NSTATUS#")
	)
	(segment
		(start 147.01393 -46.5582)
		(end 147.461732 -47.006002)
		(width 0.127)
		(layer "B.Cu")
		(net "C_NSTATUS#")
	)
	(segment
		(start 158.8262 -44.831)
		(end 159.385 -44.2722)
		(width 0.127)
		(layer "B.Cu")
		(net "C_NSTATUS#")
	)
	(segment
		(start 159.4612 -44.196)
		(end 159.385 -44.2722)
		(width 0.127)
		(layer "B.Cu")
		(net "C_NSTATUS#")
	)
	(segment
		(start 146.431 -45.995844)
		(end 146.993356 -46.5582)
		(width 0.127)
		(layer "B.Cu")
		(net "C_NSTATUS#")
	)
	(segment
		(start 167.8432 -44.196)
		(end 159.4612 -44.196)
		(width 0.127)
		(layer "B.Cu")
		(net "C_NSTATUS#")
	)
	(segment
		(start 149.733 -46.99635)
		(end 152.912826 -46.99635)
		(width 0.127)
		(layer "B.Cu")
		(net "C_NSTATUS#")
	)
	(segment
		(start 167.894 -44.1452)
		(end 167.8432 -44.196)
		(width 0.127)
		(layer "B.Cu")
		(net "C_NSTATUS#")
	)
	(segment
		(start 152.912826 -46.99635)
		(end 155.078176 -44.831)
		(width 0.127)
		(layer "B.Cu")
		(net "C_NSTATUS#")
	)
	(segment
		(start 149.723348 -47.006002)
		(end 149.733 -46.99635)
		(width 0.127)
		(layer "B.Cu")
		(net "C_NSTATUS#")
	)
	(segment
		(start 155.078176 -44.831)
		(end 158.8262 -44.831)
		(width 0.127)
		(layer "B.Cu")
		(net "C_NSTATUS#")
	)
	(segment
		(start 147.461732 -47.006002)
		(end 149.723348 -47.006002)
		(width 0.127)
		(layer "B.Cu")
		(net "C_NSTATUS#")
	)
	(segment
		(start 136.49833 -23.9268)
		(end 136.49833 -22.840442)
		(width 0.3048)
		(layer "F.Cu")
		(net "P1V2_FPGA_D")
	)
	(segment
		(start 136.7028 -21.5392)
		(end 136.779 -21.5392)
		(width 0.3048)
		(layer "F.Cu")
		(net "P1V2_FPGA_D")
	)
	(segment
		(start 136.49833 -22.840442)
		(end 136.492996 -22.835108)
		(width 0.3048)
		(layer "F.Cu")
		(net "P1V2_FPGA_D")
	)
	(segment
		(start 149.47265 -45.1866)
		(end 149.49805 -45.1612)
		(width 0.3048)
		(layer "F.Cu")
		(net "P1V2_FPGA_D")
	)
	(segment
		(start 131.3942 -39.2938)
		(end 132.1308 -39.2938)
		(width 0.3048)
		(layer "F.Cu")
		(net "P1V2_FPGA_D")
	)
	(segment
		(start 137.49782 -45.86478)
		(end 137.49782 -45.1612)
		(width 0.3048)
		(layer "F.Cu")
		(net "P1V2_FPGA_D")
	)
	(segment
		(start 150.622 -29.29382)
		(end 150.114 -29.80182)
		(width 0.3048)
		(layer "F.Cu")
		(net "P1V2_FPGA_D")
	)
	(segment
		(start 148.49856 -25.05456)
		(end 150.622 -27.178)
		(width 0.3048)
		(layer "F.Cu")
		(net "P1V2_FPGA_D")
	)
	(segment
		(start 137.051796 -22.60346)
		(end 137.051796 -21.811996)
		(width 0.508)
		(layer "F.Cu")
		(net "P1V2_FPGA_D")
	)
	(segment
		(start 151.318976 -37.120576)
		(end 151.318976 -36.840414)
		(width 0.3048)
		(layer "F.Cu")
		(net "P1V2_FPGA_D")
	)
	(segment
		(start 150.622 -29.29382)
		(end 153.3652 -29.29382)
		(width 0.3048)
		(layer "F.Cu")
		(net "P1V2_FPGA_D")
	)
	(segment
		(start 128.9812 -39.624)
		(end 131.064 -39.624)
		(width 0.3048)
		(layer "F.Cu")
		(net "P1V2_FPGA_D")
	)
	(segment
		(start 137.051796 -21.811996)
		(end 136.779 -21.5392)
		(width 0.508)
		(layer "F.Cu")
		(net "P1V2_FPGA_D")
	)
	(segment
		(start 131.064 -39.624)
		(end 131.3942 -39.2938)
		(width 0.3048)
		(layer "F.Cu")
		(net "P1V2_FPGA_D")
	)
	(segment
		(start 153.3652 -38.29431)
		(end 152.49271 -38.29431)
		(width 0.3048)
		(layer "F.Cu")
		(net "P1V2_FPGA_D")
	)
	(segment
		(start 152.49271 -38.29431)
		(end 151.318976 -37.120576)
		(width 0.3048)
		(layer "F.Cu")
		(net "P1V2_FPGA_D")
	)
	(segment
		(start 150.622 -27.178)
		(end 150.622 -29.29382)
		(width 0.3048)
		(layer "F.Cu")
		(net "P1V2_FPGA_D")
	)
	(segment
		(start 132.1308 -31.29407)
		(end 129.97307 -31.29407)
		(width 0.3048)
		(layer "F.Cu")
		(net "P1V2_FPGA_D")
	)
	(segment
		(start 128.7272 -39.37)
		(end 128.9812 -39.624)
		(width 0.3048)
		(layer "F.Cu")
		(net "P1V2_FPGA_D")
	)
	(segment
		(start 149.225 -21.6662)
		(end 148.717 -21.1582)
		(width 0.3048)
		(layer "F.Cu")
		(net "P1V2_FPGA_D")
	)
	(segment
		(start 166.624 -28.321)
		(end 167.2336 -28.321)
		(width 0.3048)
		(layer "F.Cu")
		(net "P1V2_FPGA_D")
	)
	(segment
		(start 128.1176 -41.0464)
		(end 128.1176 -46.5836)
		(width 0.3048)
		(layer "F.Cu")
		(net "P1V2_FPGA_D")
	)
	(segment
		(start 148.49856 -21.37664)
		(end 148.717 -21.1582)
		(width 0.3048)
		(layer "F.Cu")
		(net "P1V2_FPGA_D")
	)
	(segment
		(start 129.97307 -31.29407)
		(end 129.032 -30.353)
		(width 0.3048)
		(layer "F.Cu")
		(net "P1V2_FPGA_D")
	)
	(segment
		(start 128.7272 -40.4368)
		(end 128.1176 -41.0464)
		(width 0.3048)
		(layer "F.Cu")
		(net "P1V2_FPGA_D")
	)
	(segment
		(start 136.492996 -22.835108)
		(end 136.492996 -22.371812)
		(width 0.3048)
		(layer "F.Cu")
		(net "P1V2_FPGA_D")
	)
	(segment
		(start 150.114 -29.80182)
		(end 150.114 -35.635438)
		(width 0.3048)
		(layer "F.Cu")
		(net "P1V2_FPGA_D")
	)
	(segment
		(start 136.49833 -22.366478)
		(end 136.49833 -21.74367)
		(width 0.3048)
		(layer "F.Cu")
		(net "P1V2_FPGA_D")
	)
	(segment
		(start 162.179 -23.876)
		(end 166.624 -28.321)
		(width 0.3048)
		(layer "F.Cu")
		(net "P1V2_FPGA_D")
	)
	(segment
		(start 136.6901 -46.6344)
		(end 136.7282 -46.6344)
		(width 0.3048)
		(layer "F.Cu")
		(net "P1V2_FPGA_D")
	)
	(segment
		(start 136.7282 -46.6344)
		(end 137.49782 -45.86478)
		(width 0.3048)
		(layer "F.Cu")
		(net "P1V2_FPGA_D")
	)
	(segment
		(start 149.47265 -46.5582)
		(end 149.47265 -45.1866)
		(width 0.3048)
		(layer "F.Cu")
		(net "P1V2_FPGA_D")
	)
	(segment
		(start 136.492996 -22.371812)
		(end 136.49833 -22.366478)
		(width 0.3048)
		(layer "F.Cu")
		(net "P1V2_FPGA_D")
	)
	(segment
		(start 128.7272 -39.37)
		(end 128.7272 -40.4368)
		(width 0.3048)
		(layer "F.Cu")
		(net "P1V2_FPGA_D")
	)
	(segment
		(start 149.225 -22.583902)
		(end 149.225 -21.6662)
		(width 0.3048)
		(layer "F.Cu")
		(net "P1V2_FPGA_D")
	)
	(segment
		(start 150.114 -35.635438)
		(end 151.318976 -36.840414)
		(width 0.3048)
		(layer "F.Cu")
		(net "P1V2_FPGA_D")
	)
	(segment
		(start 148.49856 -23.9268)
		(end 148.49856 -21.37664)
		(width 0.3048)
		(layer "F.Cu")
		(net "P1V2_FPGA_D")
	)
	(segment
		(start 136.49833 -21.74367)
		(end 136.7028 -21.5392)
		(width 0.3048)
		(layer "F.Cu")
		(net "P1V2_FPGA_D")
	)
	(segment
		(start 148.49856 -23.9268)
		(end 148.49856 -25.05456)
		(width 0.3048)
		(layer "F.Cu")
		(net "P1V2_FPGA_D")
	)
	(via
		(at 147.8534 -35.56)
		(size 0.7112)
		(drill 0.3556)
		(layers "F.Cu" "B.Cu")
		(net "P1V2_FPGA_D")
	)
	(via
		(at 149.47265 -46.5582)
		(size 0.508)
		(drill 0.254)
		(layers "F.Cu" "B.Cu")
		(net "P1V2_FPGA_D")
	)
	(via
		(at 151.318976 -36.840414)
		(size 0.508)
		(drill 0.254)
		(layers "F.Cu" "B.Cu")
		(net "P1V2_FPGA_D")
	)
	(via
		(at 148.514308 -44.044108)
		(size 0.7112)
		(drill 0.3556)
		(layers "F.Cu" "B.Cu")
		(net "P1V2_FPGA_D")
	)
	(via
		(at 162.179 -23.876)
		(size 0.508)
		(drill 0.254)
		(layers "F.Cu" "B.Cu")
		(net "P1V2_FPGA_D")
	)
	(via
		(at 128.1176 -46.5836)
		(size 0.508)
		(drill 0.254)
		(layers "F.Cu" "B.Cu")
		(net "P1V2_FPGA_D")
	)
	(via
		(at 149.225 -22.583902)
		(size 0.508)
		(drill 0.254)
		(layers "F.Cu" "B.Cu")
		(net "P1V2_FPGA_D")
	)
	(via
		(at 137.051796 -22.60346)
		(size 0.508)
		(drill 0.254)
		(layers "F.Cu" "B.Cu")
		(net "P1V2_FPGA_D")
	)
	(via
		(at 129.032 -30.353)
		(size 0.508)
		(drill 0.254)
		(layers "F.Cu" "B.Cu")
		(net "P1V2_FPGA_D")
	)
	(via
		(at 136.6901 -46.6344)
		(size 0.508)
		(drill 0.254)
		(layers "F.Cu" "B.Cu")
		(net "P1V2_FPGA_D")
	)
	(segment
		(start 137.051796 -22.206204)
		(end 138.0236 -21.2344)
		(width 0.3048)
		(layer "B.Cu")
		(net "P1V2_FPGA_D")
	)
	(segment
		(start 128.422146 -29.743146)
		(end 129.032 -30.353)
		(width 0.3048)
		(layer "B.Cu")
		(net "P1V2_FPGA_D")
	)
	(segment
		(start 134.7978 -30.15107)
		(end 134.7978 -30.559248)
		(width 0.3048)
		(layer "B.Cu")
		(net "P1V2_FPGA_D")
	)
	(segment
		(start 124.6632 -30.070298)
		(end 124.990352 -29.743146)
		(width 0.3048)
		(layer "B.Cu")
		(net "P1V2_FPGA_D")
	)
	(segment
		(start 150.7998 -35.56)
		(end 147.8534 -35.56)
		(width 0.3048)
		(layer "B.Cu")
		(net "P1V2_FPGA_D")
	)
	(segment
		(start 135.2423 -46.382686)
		(end 135.2423 -46.826678)
		(width 0.3048)
		(layer "B.Cu")
		(net "P1V2_FPGA_D")
	)
	(segment
		(start 134.7978 -30.559248)
		(end 139.798552 -35.56)
		(width 0.3048)
		(layer "B.Cu")
		(net "P1V2_FPGA_D")
	)
	(segment
		(start 149.2758 -45.5168)
		(end 149.2758 -45.466)
		(width 0.3048)
		(layer "B.Cu")
		(net "P1V2_FPGA_D")
	)
	(segment
		(start 124.6632 -35.6362)
		(end 124.6632 -30.070298)
		(width 0.3048)
		(layer "B.Cu")
		(net "P1V2_FPGA_D")
	)
	(segment
		(start 137.4648 -45.847)
		(end 137.4648 -45.466)
		(width 0.3048)
		(layer "B.Cu")
		(net "P1V2_FPGA_D")
	)
	(segment
		(start 139.2936 -43.4594)
		(end 147.9296 -43.4594)
		(width 0.3048)
		(layer "B.Cu")
		(net "P1V2_FPGA_D")
	)
	(segment
		(start 136.6901 -46.6344)
		(end 136.1313 -46.0756)
		(width 0.3048)
		(layer "B.Cu")
		(net "P1V2_FPGA_D")
	)
	(segment
		(start 128.1176 -46.5836)
		(end 128.1176 -39.0906)
		(width 0.3048)
		(layer "B.Cu")
		(net "P1V2_FPGA_D")
	)
	(segment
		(start 151.3078 -36.829238)
		(end 151.3078 -36.068)
		(width 0.3048)
		(layer "B.Cu")
		(net "P1V2_FPGA_D")
	)
	(segment
		(start 129.3876 -47.8536)
		(end 128.1176 -46.5836)
		(width 0.3048)
		(layer "B.Cu")
		(net "P1V2_FPGA_D")
	)
	(segment
		(start 136.6901 -46.6344)
		(end 136.6901 -46.6217)
		(width 0.3048)
		(layer "B.Cu")
		(net "P1V2_FPGA_D")
	)
	(segment
		(start 139.798552 -35.56)
		(end 147.8534 -35.56)
		(width 0.3048)
		(layer "B.Cu")
		(net "P1V2_FPGA_D")
	)
	(segment
		(start 135.2423 -46.826678)
		(end 134.85495 -47.214028)
		(width 0.3048)
		(layer "B.Cu")
		(net "P1V2_FPGA_D")
	)
	(segment
		(start 147.875498 -21.2344)
		(end 149.225 -22.583902)
		(width 0.3048)
		(layer "B.Cu")
		(net "P1V2_FPGA_D")
	)
	(segment
		(start 138.0236 -21.2344)
		(end 147.875498 -21.2344)
		(width 0.3048)
		(layer "B.Cu")
		(net "P1V2_FPGA_D")
	)
	(segment
		(start 135.549386 -46.0756)
		(end 135.2423 -46.382686)
		(width 0.3048)
		(layer "B.Cu")
		(net "P1V2_FPGA_D")
	)
	(segment
		(start 128.1176 -39.0906)
		(end 124.6632 -35.6362)
		(width 0.3048)
		(layer "B.Cu")
		(net "P1V2_FPGA_D")
	)
	(segment
		(start 136.1313 -46.0756)
		(end 135.549386 -46.0756)
		(width 0.3048)
		(layer "B.Cu")
		(net "P1V2_FPGA_D")
	)
	(segment
		(start 149.47265 -45.71365)
		(end 149.2758 -45.5168)
		(width 0.3048)
		(layer "B.Cu")
		(net "P1V2_FPGA_D")
	)
	(segment
		(start 137.4648 -45.2882)
		(end 139.2936 -43.4594)
		(width 0.3048)
		(layer "B.Cu")
		(net "P1V2_FPGA_D")
	)
	(segment
		(start 147.9296 -43.4594)
		(end 148.514308 -44.044108)
		(width 0.3048)
		(layer "B.Cu")
		(net "P1V2_FPGA_D")
	)
	(segment
		(start 124.990352 -29.743146)
		(end 128.422146 -29.743146)
		(width 0.3048)
		(layer "B.Cu")
		(net "P1V2_FPGA_D")
	)
	(segment
		(start 151.3078 -36.068)
		(end 150.7998 -35.56)
		(width 0.3048)
		(layer "B.Cu")
		(net "P1V2_FPGA_D")
	)
	(segment
		(start 151.318976 -36.840414)
		(end 151.3078 -36.829238)
		(width 0.3048)
		(layer "B.Cu")
		(net "P1V2_FPGA_D")
	)
	(segment
		(start 162.179 -23.876)
		(end 162.179 -24.412448)
		(width 0.3048)
		(layer "B.Cu")
		(net "P1V2_FPGA_D")
	)
	(segment
		(start 137.4648 -45.466)
		(end 137.4648 -45.2882)
		(width 0.3048)
		(layer "B.Cu")
		(net "P1V2_FPGA_D")
	)
	(segment
		(start 148.514308 -44.044108)
		(end 149.2758 -44.8056)
		(width 0.3048)
		(layer "B.Cu")
		(net "P1V2_FPGA_D")
	)
	(segment
		(start 134.85495 -47.214028)
		(end 133.125972 -47.214028)
		(width 0.3048)
		(layer "B.Cu")
		(net "P1V2_FPGA_D")
	)
	(segment
		(start 149.225 -22.616668)
		(end 149.225 -22.583902)
		(width 0.3048)
		(layer "B.Cu")
		(net "P1V2_FPGA_D")
	)
	(segment
		(start 149.47265 -46.5582)
		(end 149.47265 -45.71365)
		(width 0.3048)
		(layer "B.Cu")
		(net "P1V2_FPGA_D")
	)
	(segment
		(start 133.125972 -47.214028)
		(end 132.4864 -47.8536)
		(width 0.3048)
		(layer "B.Cu")
		(net "P1V2_FPGA_D")
	)
	(segment
		(start 129.032 -30.353)
		(end 129.64922 -29.73578)
		(width 0.3048)
		(layer "B.Cu")
		(net "P1V2_FPGA_D")
	)
	(segment
		(start 136.6901 -46.6217)
		(end 137.4648 -45.847)
		(width 0.3048)
		(layer "B.Cu")
		(net "P1V2_FPGA_D")
	)
	(segment
		(start 132.4864 -47.8536)
		(end 129.3876 -47.8536)
		(width 0.3048)
		(layer "B.Cu")
		(net "P1V2_FPGA_D")
	)
	(segment
		(start 134.38251 -29.73578)
		(end 134.7978 -30.15107)
		(width 0.3048)
		(layer "B.Cu")
		(net "P1V2_FPGA_D")
	)
	(segment
		(start 129.64922 -29.73578)
		(end 134.38251 -29.73578)
		(width 0.3048)
		(layer "B.Cu")
		(net "P1V2_FPGA_D")
	)
	(segment
		(start 149.2758 -44.8056)
		(end 149.2758 -45.466)
		(width 0.3048)
		(layer "B.Cu")
		(net "P1V2_FPGA_D")
	)
	(segment
		(start 152.694132 -26.0858)
		(end 149.225 -22.616668)
		(width 0.3048)
		(layer "B.Cu")
		(net "P1V2_FPGA_D")
	)
	(segment
		(start 137.051796 -22.60346)
		(end 137.051796 -22.206204)
		(width 0.3048)
		(layer "B.Cu")
		(net "P1V2_FPGA_D")
	)
	(segment
		(start 160.505648 -26.0858)
		(end 152.694132 -26.0858)
		(width 0.3048)
		(layer "B.Cu")
		(net "P1V2_FPGA_D")
	)
	(segment
		(start 162.179 -24.412448)
		(end 160.505648 -26.0858)
		(width 0.3048)
		(layer "B.Cu")
		(net "P1V2_FPGA_D")
	)
	(segment
		(start 145.76298 -48.21682)
		(end 145.6944 -48.2854)
		(width 0.1143)
		(layer "F.Cu")
		(net "C_DCLK")
	)
	(segment
		(start 155.829 -50.8)
		(end 155.575 -50.546)
		(width 0.1143)
		(layer "F.Cu")
		(net "C_DCLK")
	)
	(segment
		(start 155.80487 -49.288192)
		(end 155.9687 -49.124362)
		(width 0.1143)
		(layer "F.Cu")
		(net "C_DCLK")
	)
	(segment
		(start 155.250896 -48.010318)
		(end 155.048712 -48.010318)
		(width 0.1143)
		(layer "F.Cu")
		(net "C_DCLK")
	)
	(segment
		(start 155.14955 -49.377092)
		(end 155.23845 -49.288192)
		(width 0.1143)
		(layer "F.Cu")
		(net "C_DCLK")
	)
	(segment
		(start 145.5928 -48.387)
		(end 145.6944 -48.2854)
		(width 0.1143)
		(layer "F.Cu")
		(net "C_DCLK")
	)
	(segment
		(start 144.907 -48.387)
		(end 145.5928 -48.387)
		(width 0.1143)
		(layer "F.Cu")
		(net "C_DCLK")
	)
	(segment
		(start 155.9687 -49.124362)
		(end 155.9687 -48.728122)
		(width 0.1143)
		(layer "F.Cu")
		(net "C_DCLK")
	)
	(segment
		(start 155.048712 -48.010318)
		(end 154.77363 -48.2854)
		(width 0.1143)
		(layer "F.Cu")
		(net "C_DCLK")
	)
	(segment
		(start 155.829 -51.7652)
		(end 155.829 -50.8)
		(width 0.1143)
		(layer "F.Cu")
		(net "C_DCLK")
	)
	(segment
		(start 155.267406 -50.546)
		(end 155.14955 -50.428144)
		(width 0.1143)
		(layer "F.Cu")
		(net "C_DCLK")
	)
	(segment
		(start 155.14955 -50.428144)
		(end 155.14955 -49.377092)
		(width 0.1143)
		(layer "F.Cu")
		(net "C_DCLK")
	)
	(segment
		(start 146.558 -48.21682)
		(end 145.76298 -48.21682)
		(width 0.1143)
		(layer "F.Cu")
		(net "C_DCLK")
	)
	(segment
		(start 155.23845 -49.288192)
		(end 155.80487 -49.288192)
		(width 0.1143)
		(layer "F.Cu")
		(net "C_DCLK")
	)
	(segment
		(start 155.575 -52.0192)
		(end 155.829 -51.7652)
		(width 0.1143)
		(layer "F.Cu")
		(net "C_DCLK")
	)
	(segment
		(start 155.575 -50.546)
		(end 155.267406 -50.546)
		(width 0.1143)
		(layer "F.Cu")
		(net "C_DCLK")
	)
	(segment
		(start 155.9687 -48.728122)
		(end 155.250896 -48.010318)
		(width 0.1143)
		(layer "F.Cu")
		(net "C_DCLK")
	)
	(via
		(at 145.6944 -48.2854)
		(size 0.508)
		(drill 0.254)
		(layers "F.Cu" "B.Cu")
		(net "C_DCLK")
	)
	(via
		(at 154.77363 -48.2854)
		(size 0.508)
		(drill 0.254)
		(layers "F.Cu" "B.Cu")
		(net "C_DCLK")
	)
	(segment
		(start 147.221194 -48.091852)
		(end 147.106894 -47.977552)
		(width 0.1143)
		(layer "B.Cu")
		(net "C_DCLK")
	)
	(segment
		(start 148.973794 -48.55845)
		(end 148.630894 -48.55845)
		(width 0.1143)
		(layer "B.Cu")
		(net "C_DCLK")
	)
	(segment
		(start 147.221194 -48.44415)
		(end 147.221194 -48.091852)
		(width 0.1143)
		(layer "B.Cu")
		(net "C_DCLK")
	)
	(segment
		(start 148.630894 -48.55845)
		(end 148.516594 -48.44415)
		(width 0.1143)
		(layer "B.Cu")
		(net "C_DCLK")
	)
	(segment
		(start 150.63724 -48.3616)
		(end 150.44039 -48.55845)
		(width 0.1143)
		(layer "B.Cu")
		(net "C_DCLK")
	)
	(segment
		(start 153.36139 -48.08855)
		(end 153.27884 -48.1711)
		(width 0.1143)
		(layer "B.Cu")
		(net "C_DCLK")
	)
	(segment
		(start 146.763994 -47.977552)
		(end 146.649694 -48.091852)
		(width 0.1143)
		(layer "B.Cu")
		(net "C_DCLK")
	)
	(segment
		(start 152.81529 -49.0474)
		(end 152.72639 -48.9585)
		(width 0.1143)
		(layer "B.Cu")
		(net "C_DCLK")
	)
	(segment
		(start 147.945094 -48.0695)
		(end 147.945094 -48.44415)
		(width 0.1143)
		(layer "B.Cu")
		(net "C_DCLK")
	)
	(segment
		(start 151.8539 -48.1584)
		(end 151.765 -48.2473)
		(width 0.1143)
		(layer "B.Cu")
		(net "C_DCLK")
	)
	(segment
		(start 149.659594 -48.0441)
		(end 149.593046 -47.977552)
		(width 0.1143)
		(layer "B.Cu")
		(net "C_DCLK")
	)
	(segment
		(start 148.516594 -48.0695)
		(end 148.427694 -47.9806)
		(width 0.1143)
		(layer "B.Cu")
		(net "C_DCLK")
	)
	(segment
		(start 147.945094 -48.44415)
		(end 147.830794 -48.55845)
		(width 0.1143)
		(layer "B.Cu")
		(net "C_DCLK")
	)
	(segment
		(start 145.669 -48.26)
		(end 145.6944 -48.2854)
		(width 0.1143)
		(layer "B.Cu")
		(net "C_DCLK")
	)
	(segment
		(start 149.154642 -47.977552)
		(end 149.088094 -48.0441)
		(width 0.1143)
		(layer "B.Cu")
		(net "C_DCLK")
	)
	(segment
		(start 149.593046 -47.977552)
		(end 149.154642 -47.977552)
		(width 0.1143)
		(layer "B.Cu")
		(net "C_DCLK")
	)
	(segment
		(start 150.44039 -48.55845)
		(end 149.773894 -48.55845)
		(width 0.1143)
		(layer "B.Cu")
		(net "C_DCLK")
	)
	(segment
		(start 146.535394 -48.55845)
		(end 145.96745 -48.55845)
		(width 0.1143)
		(layer "B.Cu")
		(net "C_DCLK")
	)
	(segment
		(start 152.63749 -48.1584)
		(end 151.8539 -48.1584)
		(width 0.1143)
		(layer "B.Cu")
		(net "C_DCLK")
	)
	(segment
		(start 153.76779 -48.08855)
		(end 153.36139 -48.08855)
		(width 0.1143)
		(layer "B.Cu")
		(net "C_DCLK")
	)
	(segment
		(start 154.77363 -48.2854)
		(end 154.77363 -48.9585)
		(width 0.1143)
		(layer "B.Cu")
		(net "C_DCLK")
	)
	(segment
		(start 148.427694 -47.9806)
		(end 148.033994 -47.9806)
		(width 0.1143)
		(layer "B.Cu")
		(net "C_DCLK")
	)
	(segment
		(start 154.68473 -49.0474)
		(end 153.93924 -49.0474)
		(width 0.1143)
		(layer "B.Cu")
		(net "C_DCLK")
	)
	(segment
		(start 147.335494 -48.55845)
		(end 147.221194 -48.44415)
		(width 0.1143)
		(layer "B.Cu")
		(net "C_DCLK")
	)
	(segment
		(start 153.85034 -48.9585)
		(end 153.85034 -48.1711)
		(width 0.1143)
		(layer "B.Cu")
		(net "C_DCLK")
	)
	(segment
		(start 151.765 -48.2473)
		(end 151.765 -48.46955)
		(width 0.1143)
		(layer "B.Cu")
		(net "C_DCLK")
	)
	(segment
		(start 151.765 -48.46955)
		(end 151.6761 -48.55845)
		(width 0.1143)
		(layer "B.Cu")
		(net "C_DCLK")
	)
	(segment
		(start 149.088094 -48.0441)
		(end 149.088094 -48.44415)
		(width 0.1143)
		(layer "B.Cu")
		(net "C_DCLK")
	)
	(segment
		(start 149.773894 -48.55845)
		(end 149.659594 -48.44415)
		(width 0.1143)
		(layer "B.Cu")
		(net "C_DCLK")
	)
	(segment
		(start 149.659594 -48.44415)
		(end 149.659594 -48.0441)
		(width 0.1143)
		(layer "B.Cu")
		(net "C_DCLK")
	)
	(segment
		(start 146.649694 -48.44415)
		(end 146.535394 -48.55845)
		(width 0.1143)
		(layer "B.Cu")
		(net "C_DCLK")
	)
	(segment
		(start 153.27884 -48.9585)
		(end 153.18994 -49.0474)
		(width 0.1143)
		(layer "B.Cu")
		(net "C_DCLK")
	)
	(segment
		(start 153.93924 -49.0474)
		(end 153.85034 -48.9585)
		(width 0.1143)
		(layer "B.Cu")
		(net "C_DCLK")
	)
	(segment
		(start 150.89759 -48.3616)
		(end 150.63724 -48.3616)
		(width 0.1143)
		(layer "B.Cu")
		(net "C_DCLK")
	)
	(segment
		(start 149.088094 -48.44415)
		(end 148.973794 -48.55845)
		(width 0.1143)
		(layer "B.Cu")
		(net "C_DCLK")
	)
	(segment
		(start 153.18994 -49.0474)
		(end 152.81529 -49.0474)
		(width 0.1143)
		(layer "B.Cu")
		(net "C_DCLK")
	)
	(segment
		(start 153.85034 -48.1711)
		(end 153.76779 -48.08855)
		(width 0.1143)
		(layer "B.Cu")
		(net "C_DCLK")
	)
	(segment
		(start 148.516594 -48.44415)
		(end 148.516594 -48.0695)
		(width 0.1143)
		(layer "B.Cu")
		(net "C_DCLK")
	)
	(segment
		(start 144.8562 -48.26)
		(end 145.669 -48.26)
		(width 0.1143)
		(layer "B.Cu")
		(net "C_DCLK")
	)
	(segment
		(start 151.6761 -48.55845)
		(end 151.09444 -48.55845)
		(width 0.1143)
		(layer "B.Cu")
		(net "C_DCLK")
	)
	(segment
		(start 153.27884 -48.1711)
		(end 153.27884 -48.9585)
		(width 0.1143)
		(layer "B.Cu")
		(net "C_DCLK")
	)
	(segment
		(start 148.033994 -47.9806)
		(end 147.945094 -48.0695)
		(width 0.1143)
		(layer "B.Cu")
		(net "C_DCLK")
	)
	(segment
		(start 151.09444 -48.55845)
		(end 150.89759 -48.3616)
		(width 0.1143)
		(layer "B.Cu")
		(net "C_DCLK")
	)
	(segment
		(start 152.72639 -48.9585)
		(end 152.72639 -48.2473)
		(width 0.1143)
		(layer "B.Cu")
		(net "C_DCLK")
	)
	(segment
		(start 146.649694 -48.091852)
		(end 146.649694 -48.44415)
		(width 0.1143)
		(layer "B.Cu")
		(net "C_DCLK")
	)
	(segment
		(start 154.77363 -48.9585)
		(end 154.68473 -49.0474)
		(width 0.1143)
		(layer "B.Cu")
		(net "C_DCLK")
	)
	(segment
		(start 147.106894 -47.977552)
		(end 146.763994 -47.977552)
		(width 0.1143)
		(layer "B.Cu")
		(net "C_DCLK")
	)
	(segment
		(start 147.830794 -48.55845)
		(end 147.335494 -48.55845)
		(width 0.1143)
		(layer "B.Cu")
		(net "C_DCLK")
	)
	(segment
		(start 152.72639 -48.2473)
		(end 152.63749 -48.1584)
		(width 0.1143)
		(layer "B.Cu")
		(net "C_DCLK")
	)
	(segment
		(start 145.96745 -48.55845)
		(end 145.6944 -48.2854)
		(width 0.1143)
		(layer "B.Cu")
		(net "C_DCLK")
	)
	(segment
		(start 142.748 -22.606)
		(end 143.49857 -23.35657)
		(width 0.127)
		(layer "F.Cu")
		(net "C_CONF_DONE")
	)
	(segment
		(start 143.49857 -23.35657)
		(end 143.49857 -23.9268)
		(width 0.127)
		(layer "F.Cu")
		(net "C_CONF_DONE")
	)
	(segment
		(start 143.578326 -20.337526)
		(end 143.891 -20.6502)
		(width 0.127)
		(layer "F.Cu")
		(net "C_CONF_DONE")
	)
	(segment
		(start 142.748 -20.337526)
		(end 143.578326 -20.337526)
		(width 0.127)
		(layer "F.Cu")
		(net "C_CONF_DONE")
	)
	(segment
		(start 142.748 -20.337526)
		(end 142.748 -21.59)
		(width 0.127)
		(layer "F.Cu")
		(net "C_CONF_DONE")
	)
	(segment
		(start 142.748 -21.59)
		(end 142.748 -22.606)
		(width 0.127)
		(layer "F.Cu")
		(net "C_CONF_DONE")
	)
	(segment
		(start 81.18856 -28.7782)
		(end 81.050384 -28.7782)
		(width 0.1016)
		(layer "F.Cu")
		(net "SATA2_RX_DN0")
	)
	(segment
		(start 81.097628 -29.410914)
		(end 81.3308 -29.410914)
		(width 0.1016)
		(layer "F.Cu")
		(net "SATA2_RX_DN0")
	)
	(segment
		(start 81.328768 -29.088334)
		(end 81.328768 -28.918408)
		(width 0.1016)
		(layer "F.Cu")
		(net "SATA2_RX_DN0")
	)
	(segment
		(start 81.328768 -28.918408)
		(end 81.18856 -28.7782)
		(width 0.1016)
		(layer "F.Cu")
		(net "SATA2_RX_DN0")
	)
	(segment
		(start 81.3308 -29.410914)
		(end 81.42859 -29.313124)
		(width 0.1016)
		(layer "F.Cu")
		(net "SATA2_RX_DN0")
	)
	(segment
		(start 63.627 -14.0462)
		(end 63.627 -14.7066)
		(width 0.1397)
		(layer "F.Cu")
		(net "SATA2_RX_DN0")
	)
	(segment
		(start 81.42859 -29.313124)
		(end 81.42859 -29.188156)
		(width 0.1016)
		(layer "F.Cu")
		(net "SATA2_RX_DN0")
	)
	(segment
		(start 81.42859 -29.188156)
		(end 81.328768 -29.088334)
		(width 0.1016)
		(layer "F.Cu")
		(net "SATA2_RX_DN0")
	)
	(via
		(at 81.050384 -28.7782)
		(size 0.4318)
		(drill 0.2032)
		(layers "F.Cu" "B.Cu")
		(net "SATA2_RX_DN0")
	)
	(via
		(at 63.627 -14.7066)
		(size 0.508)
		(drill 0.254)
		(layers "F.Cu" "B.Cu")
		(net "SATA2_RX_DN0")
	)
	(segment
		(start 63.8302 -14.9098)
		(end 63.627 -14.7066)
		(width 0.1143)
		(layer "In7.Cu")
		(net "SATA2_RX_DN0")
	)
	(segment
		(start 74.164444 -22.05355)
		(end 69.992494 -17.8816)
		(width 0.1143)
		(layer "In7.Cu")
		(net "SATA2_RX_DN0")
	)
	(segment
		(start 69.992494 -17.8816)
		(end 65.231772 -17.8816)
		(width 0.1143)
		(layer "In7.Cu")
		(net "SATA2_RX_DN0")
	)
	(segment
		(start 65.231772 -17.8816)
		(end 63.8302 -16.480028)
		(width 0.1143)
		(layer "In7.Cu")
		(net "SATA2_RX_DN0")
	)
	(segment
		(start 75.248516 -22.05355)
		(end 74.164444 -22.05355)
		(width 0.1143)
		(layer "In7.Cu")
		(net "SATA2_RX_DN0")
	)
	(segment
		(start 81.050384 -28.7782)
		(end 81.050384 -28.503372)
		(width 0.1143)
		(layer "In7.Cu")
		(net "SATA2_RX_DN0")
	)
	(segment
		(start 77.470254 -24.923242)
		(end 77.470254 -23.946104)
		(width 0.1143)
		(layer "In7.Cu")
		(net "SATA2_RX_DN0")
	)
	(segment
		(start 81.050384 -28.503372)
		(end 77.470254 -24.923242)
		(width 0.1143)
		(layer "In7.Cu")
		(net "SATA2_RX_DN0")
	)
	(segment
		(start 63.8302 -16.480028)
		(end 63.8302 -14.9098)
		(width 0.1143)
		(layer "In7.Cu")
		(net "SATA2_RX_DN0")
	)
	(segment
		(start 77.470254 -23.946104)
		(end 76.1492 -22.62505)
		(width 0.1143)
		(layer "In7.Cu")
		(net "SATA2_RX_DN0")
	)
	(segment
		(start 75.820016 -22.62505)
		(end 75.248516 -22.05355)
		(width 0.1143)
		(layer "In7.Cu")
		(net "SATA2_RX_DN0")
	)
	(segment
		(start 76.1492 -22.62505)
		(end 75.820016 -22.62505)
		(width 0.1143)
		(layer "In7.Cu")
		(net "SATA2_RX_DN0")
	)
	(segment
		(start 84.44103 -26.558494)
		(end 84.661502 -26.338022)
		(width 0.1397)
		(layer "F.Cu")
		(net "SATA2_TX_DP0")
	)
	(segment
		(start 84.231988 -26.558494)
		(end 84.44103 -26.558494)
		(width 0.1397)
		(layer "F.Cu")
		(net "SATA2_TX_DP0")
	)
	(via
		(at 66.548 -14.6812)
		(size 0.508)
		(drill 0.254)
		(layers "F.Cu" "B.Cu")
		(net "SATA2_TX_DP0")
	)
	(via
		(at 84.661502 -26.338022)
		(size 0.4318)
		(drill 0.2032)
		(layers "F.Cu" "B.Cu")
		(net "SATA2_TX_DP0")
	)
	(segment
		(start 66.548 -14.0462)
		(end 66.548 -14.6812)
		(width 0.1397)
		(layer "B.Cu")
		(net "SATA2_TX_DP0")
	)
	(segment
		(start 75.98537 -19.26717)
		(end 75.438 -18.7198)
		(width 0.1143)
		(layer "In7.Cu")
		(net "SATA2_TX_DP0")
	)
	(segment
		(start 82.229452 -24.1554)
		(end 80.4164 -24.1554)
		(width 0.1143)
		(layer "In7.Cu")
		(net "SATA2_TX_DP0")
	)
	(segment
		(start 76.772008 -20.053808)
		(end 76.529438 -19.811238)
		(width 0.1143)
		(layer "In7.Cu")
		(net "SATA2_TX_DP0")
	)
	(segment
		(start 78.102714 -21.384514)
		(end 78.102714 -21.082762)
		(width 0.1143)
		(layer "In7.Cu")
		(net "SATA2_TX_DP0")
	)
	(segment
		(start 75.438 -18.7198)
		(end 75.438 -18.074894)
		(width 0.1143)
		(layer "In7.Cu")
		(net "SATA2_TX_DP0")
	)
	(segment
		(start 77.07376 -20.053808)
		(end 76.772008 -20.053808)
		(width 0.1143)
		(layer "In7.Cu")
		(net "SATA2_TX_DP0")
	)
	(segment
		(start 72.894952 -15.531846)
		(end 66.7639 -15.531846)
		(width 0.1143)
		(layer "In7.Cu")
		(net "SATA2_TX_DP0")
	)
	(segment
		(start 77.558646 -20.840446)
		(end 77.316076 -20.597876)
		(width 0.1143)
		(layer "In7.Cu")
		(net "SATA2_TX_DP0")
	)
	(segment
		(start 77.316076 -20.296124)
		(end 77.07376 -20.053808)
		(width 0.1143)
		(layer "In7.Cu")
		(net "SATA2_TX_DP0")
	)
	(segment
		(start 83.29295 -25.218898)
		(end 82.229452 -24.1554)
		(width 0.1143)
		(layer "In7.Cu")
		(net "SATA2_TX_DP0")
	)
	(segment
		(start 76.529438 -19.509486)
		(end 76.287122 -19.26717)
		(width 0.1143)
		(layer "In7.Cu")
		(net "SATA2_TX_DP0")
	)
	(segment
		(start 66.7639 -15.531846)
		(end 66.3448 -15.112746)
		(width 0.1143)
		(layer "In7.Cu")
		(net "SATA2_TX_DP0")
	)
	(segment
		(start 77.860398 -20.840446)
		(end 77.558646 -20.840446)
		(width 0.1143)
		(layer "In7.Cu")
		(net "SATA2_TX_DP0")
	)
	(segment
		(start 75.438 -18.074894)
		(end 72.894952 -15.531846)
		(width 0.1143)
		(layer "In7.Cu")
		(net "SATA2_TX_DP0")
	)
	(segment
		(start 79.502 -23.241)
		(end 79.502 -22.7838)
		(width 0.1143)
		(layer "In7.Cu")
		(net "SATA2_TX_DP0")
	)
	(segment
		(start 84.661502 -26.338022)
		(end 84.456524 -26.543)
		(width 0.1143)
		(layer "In7.Cu")
		(net "SATA2_TX_DP0")
	)
	(segment
		(start 84.456524 -26.543)
		(end 83.947 -26.543)
		(width 0.1143)
		(layer "In7.Cu")
		(net "SATA2_TX_DP0")
	)
	(segment
		(start 83.29295 -25.88895)
		(end 83.29295 -25.218898)
		(width 0.1143)
		(layer "In7.Cu")
		(net "SATA2_TX_DP0")
	)
	(segment
		(start 79.502 -22.7838)
		(end 78.102714 -21.384514)
		(width 0.1143)
		(layer "In7.Cu")
		(net "SATA2_TX_DP0")
	)
	(segment
		(start 66.3448 -15.112746)
		(end 66.3448 -14.8844)
		(width 0.1143)
		(layer "In7.Cu")
		(net "SATA2_TX_DP0")
	)
	(segment
		(start 80.4164 -24.1554)
		(end 79.502 -23.241)
		(width 0.1143)
		(layer "In7.Cu")
		(net "SATA2_TX_DP0")
	)
	(segment
		(start 76.529438 -19.811238)
		(end 76.529438 -19.509486)
		(width 0.1143)
		(layer "In7.Cu")
		(net "SATA2_TX_DP0")
	)
	(segment
		(start 76.287122 -19.26717)
		(end 75.98537 -19.26717)
		(width 0.1143)
		(layer "In7.Cu")
		(net "SATA2_TX_DP0")
	)
	(segment
		(start 77.316076 -20.597876)
		(end 77.316076 -20.296124)
		(width 0.1143)
		(layer "In7.Cu")
		(net "SATA2_TX_DP0")
	)
	(segment
		(start 83.947 -26.543)
		(end 83.29295 -25.88895)
		(width 0.1143)
		(layer "In7.Cu")
		(net "SATA2_TX_DP0")
	)
	(segment
		(start 78.102714 -21.082762)
		(end 77.860398 -20.840446)
		(width 0.1143)
		(layer "In7.Cu")
		(net "SATA2_TX_DP0")
	)
	(segment
		(start 66.3448 -14.8844)
		(end 66.548 -14.6812)
		(width 0.1143)
		(layer "In7.Cu")
		(net "SATA2_TX_DP0")
	)
	(segment
		(start 84.485734 -27.300174)
		(end 84.692236 -27.093672)
		(width 0.1397)
		(layer "F.Cu")
		(net "SATA2_TX_DN0")
	)
	(segment
		(start 84.239608 -27.300174)
		(end 84.485734 -27.300174)
		(width 0.1397)
		(layer "F.Cu")
		(net "SATA2_TX_DN0")
	)
	(via
		(at 84.692236 -27.093672)
		(size 0.4318)
		(drill 0.2032)
		(layers "F.Cu" "B.Cu")
		(net "SATA2_TX_DN0")
	)
	(via
		(at 65.786 -14.6812)
		(size 0.508)
		(drill 0.254)
		(layers "F.Cu" "B.Cu")
		(net "SATA2_TX_DN0")
	)
	(segment
		(start 65.786 -14.0462)
		(end 65.786 -14.6812)
		(width 0.1397)
		(layer "B.Cu")
		(net "SATA2_TX_DN0")
	)
	(segment
		(start 66.626994 -15.862046)
		(end 66.0146 -15.249652)
		(width 0.1143)
		(layer "In7.Cu")
		(net "SATA2_TX_DN0")
	)
	(segment
		(start 66.0146 -14.9098)
		(end 65.786 -14.6812)
		(width 0.1143)
		(layer "In7.Cu")
		(net "SATA2_TX_DN0")
	)
	(segment
		(start 79.1718 -23.377906)
		(end 79.1718 -22.920706)
		(width 0.1143)
		(layer "In7.Cu")
		(net "SATA2_TX_DN0")
	)
	(segment
		(start 75.1078 -18.2118)
		(end 72.758046 -15.862046)
		(width 0.1143)
		(layer "In7.Cu")
		(net "SATA2_TX_DN0")
	)
	(segment
		(start 75.1078 -18.856706)
		(end 75.1078 -18.2118)
		(width 0.1143)
		(layer "In7.Cu")
		(net "SATA2_TX_DN0")
	)
	(segment
		(start 82.092546 -24.4856)
		(end 80.279494 -24.4856)
		(width 0.1143)
		(layer "In7.Cu")
		(net "SATA2_TX_DN0")
	)
	(segment
		(start 79.1718 -22.920706)
		(end 75.1078 -18.856706)
		(width 0.1143)
		(layer "In7.Cu")
		(net "SATA2_TX_DN0")
	)
	(segment
		(start 82.96275 -26.025856)
		(end 82.96275 -25.355804)
		(width 0.1143)
		(layer "In7.Cu")
		(net "SATA2_TX_DN0")
	)
	(segment
		(start 83.810094 -26.8732)
		(end 82.96275 -26.025856)
		(width 0.1143)
		(layer "In7.Cu")
		(net "SATA2_TX_DN0")
	)
	(segment
		(start 72.758046 -15.862046)
		(end 66.626994 -15.862046)
		(width 0.1143)
		(layer "In7.Cu")
		(net "SATA2_TX_DN0")
	)
	(segment
		(start 66.0146 -15.249652)
		(end 66.0146 -14.9098)
		(width 0.1143)
		(layer "In7.Cu")
		(net "SATA2_TX_DN0")
	)
	(segment
		(start 84.692236 -27.093672)
		(end 84.471764 -26.8732)
		(width 0.1143)
		(layer "In7.Cu")
		(net "SATA2_TX_DN0")
	)
	(segment
		(start 84.471764 -26.8732)
		(end 83.810094 -26.8732)
		(width 0.1143)
		(layer "In7.Cu")
		(net "SATA2_TX_DN0")
	)
	(segment
		(start 82.96275 -25.355804)
		(end 82.092546 -24.4856)
		(width 0.1143)
		(layer "In7.Cu")
		(net "SATA2_TX_DN0")
	)
	(segment
		(start 80.279494 -24.4856)
		(end 79.1718 -23.377906)
		(width 0.1143)
		(layer "In7.Cu")
		(net "SATA2_TX_DN0")
	)
	(segment
		(start 81.785968 -29.258006)
		(end 81.785968 -29.578554)
		(width 0.1016)
		(layer "F.Cu")
		(net "SATA2_RX_DP0")
	)
	(segment
		(start 81.531968 -29.004006)
		(end 81.785968 -29.258006)
		(width 0.1016)
		(layer "F.Cu")
		(net "SATA2_RX_DP0")
	)
	(segment
		(start 64.389 -14.0462)
		(end 64.389 -14.7066)
		(width 0.1397)
		(layer "F.Cu")
		(net "SATA2_RX_DP0")
	)
	(segment
		(start 81.531968 -28.49372)
		(end 81.531968 -29.004006)
		(width 0.1016)
		(layer "F.Cu")
		(net "SATA2_RX_DP0")
	)
	(via
		(at 64.389 -14.7066)
		(size 0.508)
		(drill 0.254)
		(layers "F.Cu" "B.Cu")
		(net "SATA2_RX_DP0")
	)
	(via
		(at 81.531968 -28.49372)
		(size 0.4318)
		(drill 0.2032)
		(layers "F.Cu" "B.Cu")
		(net "SATA2_RX_DP0")
	)
	(segment
		(start 65.368678 -17.5514)
		(end 64.972438 -17.15516)
		(width 0.1143)
		(layer "In7.Cu")
		(net "SATA2_RX_DP0")
	)
	(segment
		(start 75.385422 -21.72335)
		(end 74.30135 -21.72335)
		(width 0.1143)
		(layer "In7.Cu")
		(net "SATA2_RX_DP0")
	)
	(segment
		(start 64.972438 -17.15516)
		(end 64.972438 -16.853408)
		(width 0.1143)
		(layer "In7.Cu")
		(net "SATA2_RX_DP0")
	)
	(segment
		(start 64.1604 -16.343122)
		(end 64.1604 -14.9352)
		(width 0.1143)
		(layer "In7.Cu")
		(net "SATA2_RX_DP0")
	)
	(segment
		(start 70.1294 -17.5514)
		(end 65.368678 -17.5514)
		(width 0.1143)
		(layer "In7.Cu")
		(net "SATA2_RX_DP0")
	)
	(segment
		(start 64.42837 -16.611092)
		(end 64.1604 -16.343122)
		(width 0.1143)
		(layer "In7.Cu")
		(net "SATA2_RX_DP0")
	)
	(segment
		(start 64.730122 -16.611092)
		(end 64.42837 -16.611092)
		(width 0.1143)
		(layer "In7.Cu")
		(net "SATA2_RX_DP0")
	)
	(segment
		(start 76.286106 -22.29485)
		(end 75.956922 -22.29485)
		(width 0.1143)
		(layer "In7.Cu")
		(net "SATA2_RX_DP0")
	)
	(segment
		(start 77.800454 -23.809198)
		(end 76.286106 -22.29485)
		(width 0.1143)
		(layer "In7.Cu")
		(net "SATA2_RX_DP0")
	)
	(segment
		(start 81.507838 -28.49372)
		(end 77.800454 -24.786336)
		(width 0.1143)
		(layer "In7.Cu")
		(net "SATA2_RX_DP0")
	)
	(segment
		(start 64.972438 -16.853408)
		(end 64.730122 -16.611092)
		(width 0.1143)
		(layer "In7.Cu")
		(net "SATA2_RX_DP0")
	)
	(segment
		(start 77.800454 -24.786336)
		(end 77.800454 -23.809198)
		(width 0.1143)
		(layer "In7.Cu")
		(net "SATA2_RX_DP0")
	)
	(segment
		(start 64.1604 -14.9352)
		(end 64.389 -14.7066)
		(width 0.1143)
		(layer "In7.Cu")
		(net "SATA2_RX_DP0")
	)
	(segment
		(start 74.30135 -21.72335)
		(end 70.1294 -17.5514)
		(width 0.1143)
		(layer "In7.Cu")
		(net "SATA2_RX_DP0")
	)
	(segment
		(start 81.531968 -28.49372)
		(end 81.507838 -28.49372)
		(width 0.1143)
		(layer "In7.Cu")
		(net "SATA2_RX_DP0")
	)
	(segment
		(start 75.956922 -22.29485)
		(end 75.385422 -21.72335)
		(width 0.1143)
		(layer "In7.Cu")
		(net "SATA2_RX_DP0")
	)
	(via
		(at 61.472064 -12.02055)
		(size 0.7112)
		(drill 0.3556)
		(layers "F.Cu" "B.Cu")
		(net "PCIE1_RESET#")
	)
	(segment
		(start 58.349896 -5.814568)
		(end 58.349896 -8.680704)
		(width 0.1143)
		(layer "B.Cu")
		(net "PCIE1_RESET#")
	)
	(segment
		(start 58.33237 -8.69823)
		(end 58.33237 -9.94537)
		(width 0.1143)
		(layer "B.Cu")
		(net "PCIE1_RESET#")
	)
	(segment
		(start 60.833 -12.9032)
		(end 61.472064 -12.264136)
		(width 0.1143)
		(layer "B.Cu")
		(net "PCIE1_RESET#")
	)
	(segment
		(start 61.472064 -11.307064)
		(end 61.472064 -12.02055)
		(width 0.1143)
		(layer "B.Cu")
		(net "PCIE1_RESET#")
	)
	(segment
		(start 60.325 -10.16)
		(end 61.472064 -11.307064)
		(width 0.1143)
		(layer "B.Cu")
		(net "PCIE1_RESET#")
	)
	(segment
		(start 58.33237 -9.94537)
		(end 58.547 -10.16)
		(width 0.1143)
		(layer "B.Cu")
		(net "PCIE1_RESET#")
	)
	(segment
		(start 61.472064 -12.264136)
		(end 61.472064 -12.02055)
		(width 0.1143)
		(layer "B.Cu")
		(net "PCIE1_RESET#")
	)
	(segment
		(start 58.547 -10.16)
		(end 60.325 -10.16)
		(width 0.1143)
		(layer "B.Cu")
		(net "PCIE1_RESET#")
	)
	(segment
		(start 58.349896 -8.680704)
		(end 58.33237 -8.69823)
		(width 0.1143)
		(layer "B.Cu")
		(net "PCIE1_RESET#")
	)
	(segment
		(start 151.0538 -56.3372)
		(end 151.5999 -56.3372)
		(width 0.1143)
		(layer "F.Cu")
		(net "BMC_I2C_DATA")
	)
	(segment
		(start 32.7533 -14.1605)
		(end 33.401 -13.5128)
		(width 0.1143)
		(layer "F.Cu")
		(net "BMC_I2C_DATA")
	)
	(segment
		(start 152.97785 -48.518318)
		(end 154.15895 -49.699418)
		(width 0.1143)
		(layer "F.Cu")
		(net "BMC_I2C_DATA")
	)
	(segment
		(start 154.15895 -49.699418)
		(end 154.15895 -52.327556)
		(width 0.1143)
		(layer "F.Cu")
		(net "BMC_I2C_DATA")
	)
	(segment
		(start 152.202896 -45.28185)
		(end 152.082246 -45.1612)
		(width 0.1143)
		(layer "F.Cu")
		(net "BMC_I2C_DATA")
	)
	(segment
		(start 152.082246 -45.1612)
		(end 151.4983 -45.1612)
		(width 0.1143)
		(layer "F.Cu")
		(net "BMC_I2C_DATA")
	)
	(segment
		(start 154.365706 -55.616094)
		(end 152.6159 -57.3659)
		(width 0.1143)
		(layer "F.Cu")
		(net "BMC_I2C_DATA")
	)
	(segment
		(start 152.97785 -46.48835)
		(end 152.97785 -48.518318)
		(width 0.1143)
		(layer "F.Cu")
		(net "BMC_I2C_DATA")
	)
	(segment
		(start 150.71725 -56.67375)
		(end 151.0538 -56.3372)
		(width 0.1143)
		(layer "F.Cu")
		(net "BMC_I2C_DATA")
	)
	(segment
		(start 173.7868 -46.482)
		(end 174.0662 -46.482)
		(width 0.1143)
		(layer "F.Cu")
		(net "BMC_I2C_DATA")
	)
	(segment
		(start 34.63925 -14.11605)
		(end 35.197796 -14.674596)
		(width 0.1143)
		(layer "F.Cu")
		(net "BMC_I2C_DATA")
	)
	(segment
		(start 154.15895 -52.327556)
		(end 154.365706 -52.534312)
		(width 0.1143)
		(layer "F.Cu")
		(net "BMC_I2C_DATA")
	)
	(segment
		(start 150.842726 -57.3659)
		(end 150.71725 -57.240424)
		(width 0.1143)
		(layer "F.Cu")
		(net "BMC_I2C_DATA")
	)
	(segment
		(start 33.401 -13.5128)
		(end 34.00425 -14.11605)
		(width 0.1143)
		(layer "F.Cu")
		(net "BMC_I2C_DATA")
	)
	(segment
		(start 152.8445 -45.801026)
		(end 152.325324 -45.28185)
		(width 0.1143)
		(layer "F.Cu")
		(net "BMC_I2C_DATA")
	)
	(segment
		(start 34.00425 -14.11605)
		(end 34.63925 -14.11605)
		(width 0.1143)
		(layer "F.Cu")
		(net "BMC_I2C_DATA")
	)
	(segment
		(start 72.3138 -56.388)
		(end 73.196704 -56.388)
		(width 0.1143)
		(layer "F.Cu")
		(net "BMC_I2C_DATA")
	)
	(segment
		(start 152.8445 -46.355)
		(end 152.97785 -46.48835)
		(width 0.1143)
		(layer "F.Cu")
		(net "BMC_I2C_DATA")
	)
	(segment
		(start 154.365706 -52.534312)
		(end 154.365706 -55.616094)
		(width 0.1143)
		(layer "F.Cu")
		(net "BMC_I2C_DATA")
	)
	(segment
		(start 150.71725 -57.240424)
		(end 150.71725 -56.67375)
		(width 0.1143)
		(layer "F.Cu")
		(net "BMC_I2C_DATA")
	)
	(segment
		(start 152.8445 -46.355)
		(end 152.8445 -45.801026)
		(width 0.1143)
		(layer "F.Cu")
		(net "BMC_I2C_DATA")
	)
	(segment
		(start 35.197796 -14.674596)
		(end 35.197796 -14.712696)
		(width 0.1143)
		(layer "F.Cu")
		(net "BMC_I2C_DATA")
	)
	(segment
		(start 73.196704 -56.388)
		(end 73.965054 -57.15635)
		(width 0.1143)
		(layer "F.Cu")
		(net "BMC_I2C_DATA")
	)
	(segment
		(start 152.6159 -57.3659)
		(end 150.842726 -57.3659)
		(width 0.1143)
		(layer "F.Cu")
		(net "BMC_I2C_DATA")
	)
	(segment
		(start 32.40024 -14.1605)
		(end 32.7533 -14.1605)
		(width 0.1143)
		(layer "F.Cu")
		(net "BMC_I2C_DATA")
	)
	(segment
		(start 152.325324 -45.28185)
		(end 152.202896 -45.28185)
		(width 0.1143)
		(layer "F.Cu")
		(net "BMC_I2C_DATA")
	)
	(segment
		(start 174.0662 -46.482)
		(end 175.1076 -45.4406)
		(width 0.1143)
		(layer "F.Cu")
		(net "BMC_I2C_DATA")
	)
	(via
		(at 152.8445 -46.355)
		(size 0.508)
		(drill 0.254)
		(layers "F.Cu" "B.Cu")
		(net "BMC_I2C_DATA")
	)
	(via
		(at 73.965054 -57.15635)
		(size 0.508)
		(drill 0.254)
		(layers "F.Cu" "B.Cu")
		(net "BMC_I2C_DATA")
	)
	(via
		(at 175.1076 -45.4406)
		(size 0.508)
		(drill 0.254)
		(layers "F.Cu" "B.Cu")
		(net "BMC_I2C_DATA")
	)
	(via
		(at 35.197796 -14.712696)
		(size 0.508)
		(drill 0.254)
		(layers "F.Cu" "B.Cu")
		(net "BMC_I2C_DATA")
	)
	(via
		(at 108.3564 -69.6214)
		(size 0.508)
		(drill 0.254)
		(layers "F.Cu" "B.Cu")
		(net "BMC_I2C_DATA")
	)
	(via
		(at 155.448 -43.7515)
		(size 0.7112)
		(drill 0.3556)
		(layers "F.Cu" "B.Cu")
		(net "BMC_I2C_DATA")
	)
	(segment
		(start 155.448 -43.7515)
		(end 155.51785 -43.68165)
		(width 0.1143)
		(layer "B.Cu")
		(net "BMC_I2C_DATA")
	)
	(segment
		(start 173.34865 -43.68165)
		(end 175.1076 -45.4406)
		(width 0.1143)
		(layer "B.Cu")
		(net "BMC_I2C_DATA")
	)
	(segment
		(start 155.448 -43.7515)
		(end 152.8445 -46.355)
		(width 0.1143)
		(layer "B.Cu")
		(net "BMC_I2C_DATA")
	)
	(segment
		(start 155.51785 -43.68165)
		(end 173.34865 -43.68165)
		(width 0.1143)
		(layer "B.Cu")
		(net "BMC_I2C_DATA")
	)
	(segment
		(start 113.713768 -67.72275)
		(end 115.748308 -65.68821)
		(width 0.0889)
		(layer "In2.Cu")
		(net "BMC_I2C_DATA")
	)
	(segment
		(start 189.91326 -72.053704)
		(end 193.6242 -68.342764)
		(width 0.0889)
		(layer "In2.Cu")
		(net "BMC_I2C_DATA")
	)
	(segment
		(start 127.738886 -72.053704)
		(end 189.91326 -72.053704)
		(width 0.0889)
		(layer "In2.Cu")
		(net "BMC_I2C_DATA")
	)
	(segment
		(start 110.25505 -67.72275)
		(end 113.713768 -67.72275)
		(width 0.0889)
		(layer "In2.Cu")
		(net "BMC_I2C_DATA")
	)
	(segment
		(start 184.8104 -47.64278)
		(end 182.21452 -45.0469)
		(width 0.0889)
		(layer "In2.Cu")
		(net "BMC_I2C_DATA")
	)
	(segment
		(start 121.932446 -65.68821)
		(end 123.6091 -67.364864)
		(width 0.0889)
		(layer "In2.Cu")
		(net "BMC_I2C_DATA")
	)
	(segment
		(start 108.3564 -69.6214)
		(end 110.25505 -67.72275)
		(width 0.0889)
		(layer "In2.Cu")
		(net "BMC_I2C_DATA")
	)
	(segment
		(start 115.748308 -65.68821)
		(end 121.932446 -65.68821)
		(width 0.0889)
		(layer "In2.Cu")
		(net "BMC_I2C_DATA")
	)
	(segment
		(start 123.6091 -67.923918)
		(end 127.738886 -72.053704)
		(width 0.0889)
		(layer "In2.Cu")
		(net "BMC_I2C_DATA")
	)
	(segment
		(start 193.6242 -63.534036)
		(end 184.8104 -54.720236)
		(width 0.0889)
		(layer "In2.Cu")
		(net "BMC_I2C_DATA")
	)
	(segment
		(start 182.21452 -45.0469)
		(end 175.5013 -45.0469)
		(width 0.0889)
		(layer "In2.Cu")
		(net "BMC_I2C_DATA")
	)
	(segment
		(start 193.6242 -68.342764)
		(end 193.6242 -63.534036)
		(width 0.0889)
		(layer "In2.Cu")
		(net "BMC_I2C_DATA")
	)
	(segment
		(start 184.8104 -54.720236)
		(end 184.8104 -47.64278)
		(width 0.0889)
		(layer "In2.Cu")
		(net "BMC_I2C_DATA")
	)
	(segment
		(start 175.5013 -45.0469)
		(end 175.1076 -45.4406)
		(width 0.0889)
		(layer "In2.Cu")
		(net "BMC_I2C_DATA")
	)
	(segment
		(start 123.6091 -67.364864)
		(end 123.6091 -67.923918)
		(width 0.0889)
		(layer "In2.Cu")
		(net "BMC_I2C_DATA")
	)
	(segment
		(start 73.965054 -58.394854)
		(end 77.597 -62.0268)
		(width 0.0889)
		(layer "In7.Cu")
		(net "BMC_I2C_DATA")
	)
	(segment
		(start 82.006948 -62.5094)
		(end 86.5124 -62.5094)
		(width 0.0889)
		(layer "In7.Cu")
		(net "BMC_I2C_DATA")
	)
	(segment
		(start 81.524348 -62.0268)
		(end 82.006948 -62.5094)
		(width 0.0889)
		(layer "In7.Cu")
		(net "BMC_I2C_DATA")
	)
	(segment
		(start 73.965054 -57.15635)
		(end 73.965054 -58.394854)
		(width 0.0889)
		(layer "In7.Cu")
		(net "BMC_I2C_DATA")
	)
	(segment
		(start 77.597 -62.0268)
		(end 81.524348 -62.0268)
		(width 0.0889)
		(layer "In7.Cu")
		(net "BMC_I2C_DATA")
	)
	(segment
		(start 107.4928 -70.485)
		(end 108.3564 -69.6214)
		(width 0.0889)
		(layer "In7.Cu")
		(net "BMC_I2C_DATA")
	)
	(segment
		(start 86.5124 -62.5094)
		(end 94.488 -70.485)
		(width 0.0889)
		(layer "In7.Cu")
		(net "BMC_I2C_DATA")
	)
	(segment
		(start 94.488 -70.485)
		(end 107.4928 -70.485)
		(width 0.0889)
		(layer "In7.Cu")
		(net "BMC_I2C_DATA")
	)
	(segment
		(start 73.965054 -57.003442)
		(end 69.361812 -52.4002)
		(width 0.0889)
		(layer "In9.Cu")
		(net "BMC_I2C_DATA")
	)
	(segment
		(start 56.223408 -39.253668)
		(end 52.96154 -35.9918)
		(width 0.0889)
		(layer "In9.Cu")
		(net "BMC_I2C_DATA")
	)
	(segment
		(start 51.47945 -35.9918)
		(end 42.28592 -26.79827)
		(width 0.0889)
		(layer "In9.Cu")
		(net "BMC_I2C_DATA")
	)
	(segment
		(start 63.53175 -52.17795)
		(end 62.039754 -50.685954)
		(width 0.0889)
		(layer "In9.Cu")
		(net "BMC_I2C_DATA")
	)
	(segment
		(start 42.28592 -26.79827)
		(end 42.28592 -22.71141)
		(width 0.0889)
		(layer "In9.Cu")
		(net "BMC_I2C_DATA")
	)
	(segment
		(start 56.223408 -43.581828)
		(end 56.223408 -39.253668)
		(width 0.0889)
		(layer "In9.Cu")
		(net "BMC_I2C_DATA")
	)
	(segment
		(start 57.86755 -45.22597)
		(end 56.223408 -43.581828)
		(width 0.0889)
		(layer "In9.Cu")
		(net "BMC_I2C_DATA")
	)
	(segment
		(start 57.86755 -46.671738)
		(end 57.86755 -45.22597)
		(width 0.0889)
		(layer "In9.Cu")
		(net "BMC_I2C_DATA")
	)
	(segment
		(start 52.96154 -35.9918)
		(end 51.47945 -35.9918)
		(width 0.0889)
		(layer "In9.Cu")
		(net "BMC_I2C_DATA")
	)
	(segment
		(start 62.039754 -50.685954)
		(end 62.039754 -49.487836)
		(width 0.0889)
		(layer "In9.Cu")
		(net "BMC_I2C_DATA")
	)
	(segment
		(start 61.573918 -49.022)
		(end 60.217812 -49.022)
		(width 0.0889)
		(layer "In9.Cu")
		(net "BMC_I2C_DATA")
	)
	(segment
		(start 42.28592 -22.71141)
		(end 39.457884 -19.883374)
		(width 0.0889)
		(layer "In9.Cu")
		(net "BMC_I2C_DATA")
	)
	(segment
		(start 39.457884 -19.883374)
		(end 38.006782 -19.883374)
		(width 0.0889)
		(layer "In9.Cu")
		(net "BMC_I2C_DATA")
	)
	(segment
		(start 38.006782 -19.883374)
		(end 35.197796 -17.074388)
		(width 0.0889)
		(layer "In9.Cu")
		(net "BMC_I2C_DATA")
	)
	(segment
		(start 66.85153 -52.17795)
		(end 63.53175 -52.17795)
		(width 0.0889)
		(layer "In9.Cu")
		(net "BMC_I2C_DATA")
	)
	(segment
		(start 35.197796 -17.074388)
		(end 35.197796 -14.712696)
		(width 0.0889)
		(layer "In9.Cu")
		(net "BMC_I2C_DATA")
	)
	(segment
		(start 67.07378 -52.4002)
		(end 66.85153 -52.17795)
		(width 0.0889)
		(layer "In9.Cu")
		(net "BMC_I2C_DATA")
	)
	(segment
		(start 69.361812 -52.4002)
		(end 67.07378 -52.4002)
		(width 0.0889)
		(layer "In9.Cu")
		(net "BMC_I2C_DATA")
	)
	(segment
		(start 60.217812 -49.022)
		(end 57.86755 -46.671738)
		(width 0.0889)
		(layer "In9.Cu")
		(net "BMC_I2C_DATA")
	)
	(segment
		(start 73.965054 -57.15635)
		(end 73.965054 -57.003442)
		(width 0.0889)
		(layer "In9.Cu")
		(net "BMC_I2C_DATA")
	)
	(segment
		(start 62.039754 -49.487836)
		(end 61.573918 -49.022)
		(width 0.0889)
		(layer "In9.Cu")
		(net "BMC_I2C_DATA")
	)
	(segment
		(start 75.905868 -14.41196)
		(end 75.364086 -14.41196)
		(width 0.1143)
		(layer "F.Cu")
		(net "BMC_I2C_ALERT#")
	)
	(segment
		(start 77.052678 -13.26515)
		(end 75.905868 -14.41196)
		(width 0.1143)
		(layer "F.Cu")
		(net "BMC_I2C_ALERT#")
	)
	(segment
		(start 74.487024 -15.83055)
		(end 75.364086 -14.953488)
		(width 0.1143)
		(layer "F.Cu")
		(net "BMC_I2C_ALERT#")
	)
	(segment
		(start 78.918054 -12.35075)
		(end 78.765654 -12.50315)
		(width 0.1143)
		(layer "F.Cu")
		(net "BMC_I2C_ALERT#")
	)
	(segment
		(start 150.74265 -46.55185)
		(end 150.74265 -46.53915)
		(width 0.1143)
		(layer "F.Cu")
		(net "BMC_I2C_ALERT#")
	)
	(segment
		(start 78.765654 -12.50315)
		(end 78.73365 -12.50315)
		(width 0.1143)
		(layer "F.Cu")
		(net "BMC_I2C_ALERT#")
	)
	(segment
		(start 165.52545 -39.07155)
		(end 165.52545 -35.641534)
		(width 0.1143)
		(layer "F.Cu")
		(net "BMC_I2C_ALERT#")
	)
	(segment
		(start 78.4098 -12.827)
		(end 77.97165 -13.26515)
		(width 0.1143)
		(layer "F.Cu")
		(net "BMC_I2C_ALERT#")
	)
	(segment
		(start 163.2204 -28.448)
		(end 162.052 -27.2796)
		(width 0.1143)
		(layer "F.Cu")
		(net "BMC_I2C_ALERT#")
	)
	(segment
		(start 78.73365 -12.50315)
		(end 78.4098 -12.827)
		(width 0.1143)
		(layer "F.Cu")
		(net "BMC_I2C_ALERT#")
	)
	(segment
		(start 163.2204 -33.336484)
		(end 163.2204 -28.448)
		(width 0.1143)
		(layer "F.Cu")
		(net "BMC_I2C_ALERT#")
	)
	(segment
		(start 75.364086 -14.953488)
		(end 75.364086 -14.41196)
		(width 0.1143)
		(layer "F.Cu")
		(net "BMC_I2C_ALERT#")
	)
	(segment
		(start 77.97165 -13.26515)
		(end 77.052678 -13.26515)
		(width 0.1143)
		(layer "F.Cu")
		(net "BMC_I2C_ALERT#")
	)
	(segment
		(start 71.76135 -15.83055)
		(end 74.487024 -15.83055)
		(width 0.1143)
		(layer "F.Cu")
		(net "BMC_I2C_ALERT#")
	)
	(segment
		(start 71.6788 -15.748)
		(end 71.76135 -15.83055)
		(width 0.1143)
		(layer "F.Cu")
		(net "BMC_I2C_ALERT#")
	)
	(segment
		(start 79.9592 -12.35075)
		(end 78.918054 -12.35075)
		(width 0.1143)
		(layer "F.Cu")
		(net "BMC_I2C_ALERT#")
	)
	(segment
		(start 165.227 -39.37)
		(end 165.52545 -39.07155)
		(width 0.1143)
		(layer "F.Cu")
		(net "BMC_I2C_ALERT#")
	)
	(segment
		(start 150.74265 -46.53915)
		(end 150.49754 -46.29404)
		(width 0.1143)
		(layer "F.Cu")
		(net "BMC_I2C_ALERT#")
	)
	(segment
		(start 165.52545 -35.641534)
		(end 163.2204 -33.336484)
		(width 0.1143)
		(layer "F.Cu")
		(net "BMC_I2C_ALERT#")
	)
	(segment
		(start 150.49754 -46.29404)
		(end 150.49754 -45.1612)
		(width 0.1143)
		(layer "F.Cu")
		(net "BMC_I2C_ALERT#")
	)
	(via
		(at 112.085374 -4.32435)
		(size 0.508)
		(drill 0.254)
		(layers "F.Cu" "B.Cu")
		(net "BMC_I2C_ALERT#")
	)
	(via
		(at 79.9592 -12.35075)
		(size 0.508)
		(drill 0.254)
		(layers "F.Cu" "B.Cu")
		(net "BMC_I2C_ALERT#")
	)
	(via
		(at 162.814 -41.021)
		(size 0.7112)
		(drill 0.3556)
		(layers "F.Cu" "B.Cu")
		(net "BMC_I2C_ALERT#")
	)
	(via
		(at 165.227 -39.37)
		(size 0.508)
		(drill 0.254)
		(layers "F.Cu" "B.Cu")
		(net "BMC_I2C_ALERT#")
	)
	(via
		(at 150.74265 -46.55185)
		(size 0.508)
		(drill 0.254)
		(layers "F.Cu" "B.Cu")
		(net "BMC_I2C_ALERT#")
	)
	(via
		(at 162.052 -27.2796)
		(size 0.508)
		(drill 0.254)
		(layers "F.Cu" "B.Cu")
		(net "BMC_I2C_ALERT#")
	)
	(segment
		(start 163.576 -41.021)
		(end 162.814 -41.021)
		(width 0.1143)
		(layer "B.Cu")
		(net "BMC_I2C_ALERT#")
	)
	(segment
		(start 165.227 -39.37)
		(end 163.576 -41.021)
		(width 0.1143)
		(layer "B.Cu")
		(net "BMC_I2C_ALERT#")
	)
	(segment
		(start 128.069086 -23.907242)
		(end 128.79705 -23.179278)
		(width 0.1143)
		(layer "B.Cu")
		(net "BMC_I2C_ALERT#")
	)
	(segment
		(start 114.998246 -4.0894)
		(end 116.63553 -5.726684)
		(width 0.1143)
		(layer "B.Cu")
		(net "BMC_I2C_ALERT#")
	)
	(segment
		(start 116.63553 -6.342126)
		(end 118.618 -8.324596)
		(width 0.1143)
		(layer "B.Cu")
		(net "BMC_I2C_ALERT#")
	)
	(segment
		(start 128.79705 -21.534628)
		(end 130.246628 -20.08505)
		(width 0.1143)
		(layer "B.Cu")
		(net "BMC_I2C_ALERT#")
	)
	(segment
		(start 112.085374 -4.32435)
		(end 112.320324 -4.0894)
		(width 0.1143)
		(layer "B.Cu")
		(net "BMC_I2C_ALERT#")
	)
	(segment
		(start 112.320324 -4.0894)
		(end 114.998246 -4.0894)
		(width 0.1143)
		(layer "B.Cu")
		(net "BMC_I2C_ALERT#")
	)
	(segment
		(start 118.618 -22.352)
		(end 120.173242 -23.907242)
		(width 0.1143)
		(layer "B.Cu")
		(net "BMC_I2C_ALERT#")
	)
	(segment
		(start 118.618 -8.324596)
		(end 118.618 -22.352)
		(width 0.1143)
		(layer "B.Cu")
		(net "BMC_I2C_ALERT#")
	)
	(segment
		(start 161.688272 -20.08505)
		(end 163.740592 -22.13737)
		(width 0.1143)
		(layer "B.Cu")
		(net "BMC_I2C_ALERT#")
	)
	(segment
		(start 156.258768 -41.021)
		(end 162.814 -41.021)
		(width 0.1143)
		(layer "B.Cu")
		(net "BMC_I2C_ALERT#")
	)
	(segment
		(start 163.740592 -26.505408)
		(end 162.9664 -27.2796)
		(width 0.1143)
		(layer "B.Cu")
		(net "BMC_I2C_ALERT#")
	)
	(segment
		(start 130.246628 -20.08505)
		(end 161.688272 -20.08505)
		(width 0.1143)
		(layer "B.Cu")
		(net "BMC_I2C_ALERT#")
	)
	(segment
		(start 116.63553 -5.726684)
		(end 116.63553 -6.342126)
		(width 0.1143)
		(layer "B.Cu")
		(net "BMC_I2C_ALERT#")
	)
	(segment
		(start 150.74265 -46.55185)
		(end 150.74265 -46.537118)
		(width 0.1143)
		(layer "B.Cu")
		(net "BMC_I2C_ALERT#")
	)
	(segment
		(start 150.74265 -46.537118)
		(end 156.258768 -41.021)
		(width 0.1143)
		(layer "B.Cu")
		(net "BMC_I2C_ALERT#")
	)
	(segment
		(start 162.9664 -27.2796)
		(end 162.052 -27.2796)
		(width 0.1143)
		(layer "B.Cu")
		(net "BMC_I2C_ALERT#")
	)
	(segment
		(start 163.740592 -22.13737)
		(end 163.740592 -26.505408)
		(width 0.1143)
		(layer "B.Cu")
		(net "BMC_I2C_ALERT#")
	)
	(segment
		(start 128.79705 -23.179278)
		(end 128.79705 -21.534628)
		(width 0.1143)
		(layer "B.Cu")
		(net "BMC_I2C_ALERT#")
	)
	(segment
		(start 120.173242 -23.907242)
		(end 128.069086 -23.907242)
		(width 0.1143)
		(layer "B.Cu")
		(net "BMC_I2C_ALERT#")
	)
	(segment
		(start 90.272362 -10.541)
		(end 87.967058 -12.846304)
		(width 0.0889)
		(layer "In7.Cu")
		(net "BMC_I2C_ALERT#")
	)
	(segment
		(start 107.97032 -4.86664)
		(end 106.934 -5.90296)
		(width 0.0889)
		(layer "In7.Cu")
		(net "BMC_I2C_ALERT#")
	)
	(segment
		(start 87.967058 -12.846304)
		(end 80.448658 -12.846304)
		(width 0.0889)
		(layer "In7.Cu")
		(net "BMC_I2C_ALERT#")
	)
	(segment
		(start 80.052672 -12.444222)
		(end 79.9592 -12.35075)
		(width 0.0889)
		(layer "In7.Cu")
		(net "BMC_I2C_ALERT#")
	)
	(segment
		(start 105.196386 -13.6398)
		(end 92.48902 -13.6398)
		(width 0.0889)
		(layer "In7.Cu")
		(net "BMC_I2C_ALERT#")
	)
	(segment
		(start 111.977424 -4.32435)
		(end 111.435134 -4.86664)
		(width 0.0889)
		(layer "In7.Cu")
		(net "BMC_I2C_ALERT#")
	)
	(segment
		(start 90.7796 -10.541)
		(end 90.272362 -10.541)
		(width 0.0889)
		(layer "In7.Cu")
		(net "BMC_I2C_ALERT#")
	)
	(segment
		(start 106.934 -11.902186)
		(end 105.196386 -13.6398)
		(width 0.0889)
		(layer "In7.Cu")
		(net "BMC_I2C_ALERT#")
	)
	(segment
		(start 80.448658 -12.846304)
		(end 80.052672 -12.450318)
		(width 0.0889)
		(layer "In7.Cu")
		(net "BMC_I2C_ALERT#")
	)
	(segment
		(start 111.435134 -4.86664)
		(end 107.97032 -4.86664)
		(width 0.0889)
		(layer "In7.Cu")
		(net "BMC_I2C_ALERT#")
	)
	(segment
		(start 106.934 -5.90296)
		(end 106.934 -11.902186)
		(width 0.0889)
		(layer "In7.Cu")
		(net "BMC_I2C_ALERT#")
	)
	(segment
		(start 80.052672 -12.450318)
		(end 80.052672 -12.444222)
		(width 0.0889)
		(layer "In7.Cu")
		(net "BMC_I2C_ALERT#")
	)
	(segment
		(start 91.186254 -12.337034)
		(end 91.186254 -10.947654)
		(width 0.0889)
		(layer "In7.Cu")
		(net "BMC_I2C_ALERT#")
	)
	(segment
		(start 92.48902 -13.6398)
		(end 91.186254 -12.337034)
		(width 0.0889)
		(layer "In7.Cu")
		(net "BMC_I2C_ALERT#")
	)
	(segment
		(start 91.186254 -10.947654)
		(end 90.7796 -10.541)
		(width 0.0889)
		(layer "In7.Cu")
		(net "BMC_I2C_ALERT#")
	)
	(segment
		(start 112.085374 -4.32435)
		(end 111.977424 -4.32435)
		(width 0.0889)
		(layer "In7.Cu")
		(net "BMC_I2C_ALERT#")
	)
	(segment
		(start 146.558 -49.71669)
		(end 145.53311 -49.71669)
		(width 0.1143)
		(layer "F.Cu")
		(net "C_CSO#")
	)
	(segment
		(start 145.53311 -49.71669)
		(end 145.3134 -49.9364)
		(width 0.1143)
		(layer "F.Cu")
		(net "C_CSO#")
	)
	(segment
		(start 145.3134 -50.7619)
		(end 145.3134 -49.9364)
		(width 0.1143)
		(layer "F.Cu")
		(net "C_CSO#")
	)
	(segment
		(start 146.419316 -51.2826)
		(end 145.8341 -51.2826)
		(width 0.1143)
		(layer "F.Cu")
		(net "C_CSO#")
	)
	(segment
		(start 145.8341 -51.2826)
		(end 145.3134 -50.7619)
		(width 0.1143)
		(layer "F.Cu")
		(net "C_CSO#")
	)
	(segment
		(start 168.8846 -52.07)
		(end 168.8846 -51.710082)
		(width 0.1143)
		(layer "F.Cu")
		(net "C_CSO#")
	)
	(segment
		(start 147.4089 -52.6415)
		(end 147.4089 -52.272184)
		(width 0.1143)
		(layer "F.Cu")
		(net "C_CSO#")
	)
	(segment
		(start 168.8846 -51.710082)
		(end 169.277284 -51.317398)
		(width 0.1143)
		(layer "F.Cu")
		(net "C_CSO#")
	)
	(segment
		(start 147.4089 -52.272184)
		(end 146.419316 -51.2826)
		(width 0.1143)
		(layer "F.Cu")
		(net "C_CSO#")
	)
	(via
		(at 147.4089 -52.6415)
		(size 0.508)
		(drill 0.254)
		(layers "F.Cu" "B.Cu")
		(net "C_CSO#")
	)
	(via
		(at 169.277284 -51.317398)
		(size 0.508)
		(drill 0.254)
		(layers "F.Cu" "B.Cu")
		(net "C_CSO#")
	)
	(segment
		(start 164.606478 -51.7906)
		(end 164.606478 -51.50485)
		(width 0.1143)
		(layer "B.Cu")
		(net "C_CSO#")
	)
	(segment
		(start 162.891978 -51.50485)
		(end 162.891978 -51.816)
		(width 0.1143)
		(layer "B.Cu")
		(net "C_CSO#")
	)
	(segment
		(start 166.320978 -51.7906)
		(end 166.193978 -51.9176)
		(width 0.1143)
		(layer "B.Cu")
		(net "C_CSO#")
	)
	(segment
		(start 153.329386 -52.832)
		(end 152.735788 -53.425598)
		(width 0.1143)
		(layer "B.Cu")
		(net "C_CSO#")
	)
	(segment
		(start 166.320978 -51.50485)
		(end 166.320978 -51.7906)
		(width 0.1143)
		(layer "B.Cu")
		(net "C_CSO#")
	)
	(segment
		(start 161.863278 -51.39055)
		(end 161.748978 -51.50485)
		(width 0.1143)
		(layer "B.Cu")
		(net "C_CSO#")
	)
	(segment
		(start 157.922976 -51.17465)
		(end 156.265626 -52.832)
		(width 0.1143)
		(layer "B.Cu")
		(net "C_CSO#")
	)
	(segment
		(start 161.748978 -51.816)
		(end 161.621978 -51.943)
		(width 0.1143)
		(layer "B.Cu")
		(net "C_CSO#")
	)
	(segment
		(start 165.749478 -51.7906)
		(end 165.749478 -51.50485)
		(width 0.1143)
		(layer "B.Cu")
		(net "C_CSO#")
	)
	(segment
		(start 164.034978 -51.50485)
		(end 164.034978 -51.7906)
		(width 0.1143)
		(layer "B.Cu")
		(net "C_CSO#")
	)
	(segment
		(start 162.206178 -51.39055)
		(end 161.863278 -51.39055)
		(width 0.1143)
		(layer "B.Cu")
		(net "C_CSO#")
	)
	(segment
		(start 167.502078 -51.8668)
		(end 167.159178 -51.8668)
		(width 0.1143)
		(layer "B.Cu")
		(net "C_CSO#")
	)
	(segment
		(start 161.177478 -51.50485)
		(end 161.063178 -51.39055)
		(width 0.1143)
		(layer "B.Cu")
		(net "C_CSO#")
	)
	(segment
		(start 166.930578 -51.39055)
		(end 166.435278 -51.39055)
		(width 0.1143)
		(layer "B.Cu")
		(net "C_CSO#")
	)
	(segment
		(start 162.891978 -51.816)
		(end 162.764978 -51.943)
		(width 0.1143)
		(layer "B.Cu")
		(net "C_CSO#")
	)
	(segment
		(start 152.735788 -53.425598)
		(end 148.192998 -53.425598)
		(width 0.1143)
		(layer "B.Cu")
		(net "C_CSO#")
	)
	(segment
		(start 167.616378 -51.50485)
		(end 167.616378 -51.7525)
		(width 0.1143)
		(layer "B.Cu")
		(net "C_CSO#")
	)
	(segment
		(start 161.177478 -51.816)
		(end 161.177478 -51.50485)
		(width 0.1143)
		(layer "B.Cu")
		(net "C_CSO#")
	)
	(segment
		(start 165.876478 -51.9176)
		(end 165.749478 -51.7906)
		(width 0.1143)
		(layer "B.Cu")
		(net "C_CSO#")
	)
	(segment
		(start 161.621978 -51.943)
		(end 161.304478 -51.943)
		(width 0.1143)
		(layer "B.Cu")
		(net "C_CSO#")
	)
	(segment
		(start 164.034978 -51.7906)
		(end 163.907978 -51.9176)
		(width 0.1143)
		(layer "B.Cu")
		(net "C_CSO#")
	)
	(segment
		(start 160.478978 -51.943)
		(end 160.161478 -51.943)
		(width 0.1143)
		(layer "B.Cu")
		(net "C_CSO#")
	)
	(segment
		(start 165.635178 -51.39055)
		(end 165.292278 -51.39055)
		(width 0.1143)
		(layer "B.Cu")
		(net "C_CSO#")
	)
	(segment
		(start 164.606478 -51.50485)
		(end 164.492178 -51.39055)
		(width 0.1143)
		(layer "B.Cu")
		(net "C_CSO#")
	)
	(segment
		(start 166.193978 -51.9176)
		(end 165.876478 -51.9176)
		(width 0.1143)
		(layer "B.Cu")
		(net "C_CSO#")
	)
	(segment
		(start 164.492178 -51.39055)
		(end 164.149278 -51.39055)
		(width 0.1143)
		(layer "B.Cu")
		(net "C_CSO#")
	)
	(segment
		(start 162.320478 -51.50485)
		(end 162.206178 -51.39055)
		(width 0.1143)
		(layer "B.Cu")
		(net "C_CSO#")
	)
	(segment
		(start 167.044878 -51.50485)
		(end 166.930578 -51.39055)
		(width 0.1143)
		(layer "B.Cu")
		(net "C_CSO#")
	)
	(segment
		(start 160.034478 -51.816)
		(end 160.034478 -51.50485)
		(width 0.1143)
		(layer "B.Cu")
		(net "C_CSO#")
	)
	(segment
		(start 167.616378 -51.7525)
		(end 167.502078 -51.8668)
		(width 0.1143)
		(layer "B.Cu")
		(net "C_CSO#")
	)
	(segment
		(start 160.720278 -51.39055)
		(end 160.605978 -51.50485)
		(width 0.1143)
		(layer "B.Cu")
		(net "C_CSO#")
	)
	(segment
		(start 163.006278 -51.39055)
		(end 162.891978 -51.50485)
		(width 0.1143)
		(layer "B.Cu")
		(net "C_CSO#")
	)
	(segment
		(start 165.292278 -51.39055)
		(end 165.177978 -51.50485)
		(width 0.1143)
		(layer "B.Cu")
		(net "C_CSO#")
	)
	(segment
		(start 161.304478 -51.943)
		(end 161.177478 -51.816)
		(width 0.1143)
		(layer "B.Cu")
		(net "C_CSO#")
	)
	(segment
		(start 166.435278 -51.39055)
		(end 166.320978 -51.50485)
		(width 0.1143)
		(layer "B.Cu")
		(net "C_CSO#")
	)
	(segment
		(start 163.907978 -51.9176)
		(end 163.590478 -51.9176)
		(width 0.1143)
		(layer "B.Cu")
		(net "C_CSO#")
	)
	(segment
		(start 169.277284 -51.317398)
		(end 169.204132 -51.39055)
		(width 0.1143)
		(layer "B.Cu")
		(net "C_CSO#")
	)
	(segment
		(start 161.063178 -51.39055)
		(end 160.720278 -51.39055)
		(width 0.1143)
		(layer "B.Cu")
		(net "C_CSO#")
	)
	(segment
		(start 162.447478 -51.943)
		(end 162.320478 -51.816)
		(width 0.1143)
		(layer "B.Cu")
		(net "C_CSO#")
	)
	(segment
		(start 156.265626 -52.832)
		(end 153.329386 -52.832)
		(width 0.1143)
		(layer "B.Cu")
		(net "C_CSO#")
	)
	(segment
		(start 161.748978 -51.50485)
		(end 161.748978 -51.816)
		(width 0.1143)
		(layer "B.Cu")
		(net "C_CSO#")
	)
	(segment
		(start 159.424878 -51.39055)
		(end 159.208978 -51.17465)
		(width 0.1143)
		(layer "B.Cu")
		(net "C_CSO#")
	)
	(segment
		(start 169.204132 -51.39055)
		(end 167.730678 -51.39055)
		(width 0.1143)
		(layer "B.Cu")
		(net "C_CSO#")
	)
	(segment
		(start 160.034478 -51.50485)
		(end 159.920178 -51.39055)
		(width 0.1143)
		(layer "B.Cu")
		(net "C_CSO#")
	)
	(segment
		(start 164.149278 -51.39055)
		(end 164.034978 -51.50485)
		(width 0.1143)
		(layer "B.Cu")
		(net "C_CSO#")
	)
	(segment
		(start 163.590478 -51.9176)
		(end 163.463478 -51.7906)
		(width 0.1143)
		(layer "B.Cu")
		(net "C_CSO#")
	)
	(segment
		(start 162.764978 -51.943)
		(end 162.447478 -51.943)
		(width 0.1143)
		(layer "B.Cu")
		(net "C_CSO#")
	)
	(segment
		(start 163.463478 -51.7906)
		(end 163.463478 -51.50485)
		(width 0.1143)
		(layer "B.Cu")
		(net "C_CSO#")
	)
	(segment
		(start 162.320478 -51.816)
		(end 162.320478 -51.50485)
		(width 0.1143)
		(layer "B.Cu")
		(net "C_CSO#")
	)
	(segment
		(start 165.177978 -51.50485)
		(end 165.177978 -51.7906)
		(width 0.1143)
		(layer "B.Cu")
		(net "C_CSO#")
	)
	(segment
		(start 160.605978 -51.816)
		(end 160.478978 -51.943)
		(width 0.1143)
		(layer "B.Cu")
		(net "C_CSO#")
	)
	(segment
		(start 164.733478 -51.9176)
		(end 164.606478 -51.7906)
		(width 0.1143)
		(layer "B.Cu")
		(net "C_CSO#")
	)
	(segment
		(start 165.177978 -51.7906)
		(end 165.050978 -51.9176)
		(width 0.1143)
		(layer "B.Cu")
		(net "C_CSO#")
	)
	(segment
		(start 167.044878 -51.7525)
		(end 167.044878 -51.50485)
		(width 0.1143)
		(layer "B.Cu")
		(net "C_CSO#")
	)
	(segment
		(start 167.730678 -51.39055)
		(end 167.616378 -51.50485)
		(width 0.1143)
		(layer "B.Cu")
		(net "C_CSO#")
	)
	(segment
		(start 160.161478 -51.943)
		(end 160.034478 -51.816)
		(width 0.1143)
		(layer "B.Cu")
		(net "C_CSO#")
	)
	(segment
		(start 165.050978 -51.9176)
		(end 164.733478 -51.9176)
		(width 0.1143)
		(layer "B.Cu")
		(net "C_CSO#")
	)
	(segment
		(start 159.920178 -51.39055)
		(end 159.424878 -51.39055)
		(width 0.1143)
		(layer "B.Cu")
		(net "C_CSO#")
	)
	(segment
		(start 160.605978 -51.50485)
		(end 160.605978 -51.816)
		(width 0.1143)
		(layer "B.Cu")
		(net "C_CSO#")
	)
	(segment
		(start 163.463478 -51.50485)
		(end 163.349178 -51.39055)
		(width 0.1143)
		(layer "B.Cu")
		(net "C_CSO#")
	)
	(segment
		(start 148.192998 -53.425598)
		(end 147.4089 -52.6415)
		(width 0.1143)
		(layer "B.Cu")
		(net "C_CSO#")
	)
	(segment
		(start 163.349178 -51.39055)
		(end 163.006278 -51.39055)
		(width 0.1143)
		(layer "B.Cu")
		(net "C_CSO#")
	)
	(segment
		(start 165.749478 -51.50485)
		(end 165.635178 -51.39055)
		(width 0.1143)
		(layer "B.Cu")
		(net "C_CSO#")
	)
	(segment
		(start 167.159178 -51.8668)
		(end 167.044878 -51.7525)
		(width 0.1143)
		(layer "B.Cu")
		(net "C_CSO#")
	)
	(segment
		(start 159.208978 -51.17465)
		(end 157.922976 -51.17465)
		(width 0.1143)
		(layer "B.Cu")
		(net "C_CSO#")
	)
	(segment
		(start 86.0933 -23.8379)
		(end 86.5378 -24.2824)
		(width 0.1397)
		(layer "F.Cu")
		(net "CPU_GBE_TX_DP0")
	)
	(segment
		(start 88.743028 -27.036014)
		(end 88.743028 -27.300174)
		(width 0.1397)
		(layer "F.Cu")
		(net "CPU_GBE_TX_DP0")
	)
	(segment
		(start 89.078308 -26.700734)
		(end 88.743028 -27.036014)
		(width 0.1397)
		(layer "F.Cu")
		(net "CPU_GBE_TX_DP0")
	)
	(segment
		(start 89.078308 -25.095708)
		(end 89.078308 -26.700734)
		(width 0.1397)
		(layer "F.Cu")
		(net "CPU_GBE_TX_DP0")
	)
	(segment
		(start 88.265 -24.2824)
		(end 89.078308 -25.095708)
		(width 0.1397)
		(layer "F.Cu")
		(net "CPU_GBE_TX_DP0")
	)
	(segment
		(start 86.5378 -24.2824)
		(end 88.265 -24.2824)
		(width 0.1397)
		(layer "F.Cu")
		(net "CPU_GBE_TX_DP0")
	)
	(segment
		(start 50.2158 -13.1572)
		(end 50.2158 -13.8176)
		(width 0.1397)
		(layer "F.Cu")
		(net "CPU_GBE_TX_DP0")
	)
	(segment
		(start 85.6234 -23.8379)
		(end 86.0933 -23.8379)
		(width 0.1397)
		(layer "F.Cu")
		(net "CPU_GBE_TX_DP0")
	)
	(segment
		(start 85.5345 -23.749)
		(end 85.6234 -23.8379)
		(width 0.1397)
		(layer "F.Cu")
		(net "CPU_GBE_TX_DP0")
	)
	(via
		(at 50.2158 -13.8176)
		(size 0.508)
		(drill 0.254)
		(layers "F.Cu" "B.Cu")
		(net "CPU_GBE_TX_DP0")
	)
	(via
		(at 85.5345 -23.749)
		(size 0.4318)
		(drill 0.2032)
		(layers "F.Cu" "B.Cu")
		(net "CPU_GBE_TX_DP0")
	)
	(segment
		(start 85.179408 -23.8506)
		(end 84.207858 -22.87905)
		(width 0.1143)
		(layer "In7.Cu")
		(net "CPU_GBE_TX_DP0")
	)
	(segment
		(start 85.5345 -23.749)
		(end 85.4329 -23.8506)
		(width 0.1143)
		(layer "In7.Cu")
		(net "CPU_GBE_TX_DP0")
	)
	(segment
		(start 75.113896 -14.875002)
		(end 73.611994 -13.3731)
		(width 0.1143)
		(layer "In7.Cu")
		(net "CPU_GBE_TX_DP0")
	)
	(segment
		(start 50.0126 -14.351)
		(end 50.0126 -14.0208)
		(width 0.1143)
		(layer "In7.Cu")
		(net "CPU_GBE_TX_DP0")
	)
	(segment
		(start 73.611994 -13.3731)
		(end 57.762394 -13.3731)
		(width 0.1143)
		(layer "In7.Cu")
		(net "CPU_GBE_TX_DP0")
	)
	(segment
		(start 50.0126 -14.0208)
		(end 50.2158 -13.8176)
		(width 0.1143)
		(layer "In7.Cu")
		(net "CPU_GBE_TX_DP0")
	)
	(segment
		(start 84.207858 -22.87905)
		(end 83.816952 -22.87905)
		(width 0.1143)
		(layer "In7.Cu")
		(net "CPU_GBE_TX_DP0")
	)
	(segment
		(start 83.816952 -22.87905)
		(end 83.26755 -22.329648)
		(width 0.1143)
		(layer "In7.Cu")
		(net "CPU_GBE_TX_DP0")
	)
	(segment
		(start 77.999844 -17.665954)
		(end 77.000354 -17.665954)
		(width 0.1143)
		(layer "In7.Cu")
		(net "CPU_GBE_TX_DP0")
	)
	(segment
		(start 54.879494 -16.256)
		(end 51.9176 -16.256)
		(width 0.1143)
		(layer "In7.Cu")
		(net "CPU_GBE_TX_DP0")
	)
	(segment
		(start 83.26755 -21.92655)
		(end 81.7245 -20.3835)
		(width 0.1143)
		(layer "In7.Cu")
		(net "CPU_GBE_TX_DP0")
	)
	(segment
		(start 80.71739 -20.3835)
		(end 77.999844 -17.665954)
		(width 0.1143)
		(layer "In7.Cu")
		(net "CPU_GBE_TX_DP0")
	)
	(segment
		(start 75.113896 -15.779496)
		(end 75.113896 -14.875002)
		(width 0.1143)
		(layer "In7.Cu")
		(net "CPU_GBE_TX_DP0")
	)
	(segment
		(start 77.000354 -17.665954)
		(end 75.113896 -15.779496)
		(width 0.1143)
		(layer "In7.Cu")
		(net "CPU_GBE_TX_DP0")
	)
	(segment
		(start 57.762394 -13.3731)
		(end 54.879494 -16.256)
		(width 0.1143)
		(layer "In7.Cu")
		(net "CPU_GBE_TX_DP0")
	)
	(segment
		(start 81.7245 -20.3835)
		(end 80.71739 -20.3835)
		(width 0.1143)
		(layer "In7.Cu")
		(net "CPU_GBE_TX_DP0")
	)
	(segment
		(start 51.9176 -16.256)
		(end 50.0126 -14.351)
		(width 0.1143)
		(layer "In7.Cu")
		(net "CPU_GBE_TX_DP0")
	)
	(segment
		(start 85.4329 -23.8506)
		(end 85.179408 -23.8506)
		(width 0.1143)
		(layer "In7.Cu")
		(net "CPU_GBE_TX_DP0")
	)
	(segment
		(start 83.26755 -22.329648)
		(end 83.26755 -21.92655)
		(width 0.1143)
		(layer "In7.Cu")
		(net "CPU_GBE_TX_DP0")
	)
	(segment
		(start 65.9765 -43.960288)
		(end 65.983866 -43.952922)
		(width 0.1143)
		(layer "F.Cu")
		(net "SMB_PECI_LV_R_CLK")
	)
	(segment
		(start 66.294 -43.642788)
		(end 65.983866 -43.952922)
		(width 0.1143)
		(layer "F.Cu")
		(net "SMB_PECI_LV_R_CLK")
	)
	(segment
		(start 65.9765 -45.06976)
		(end 65.9765 -43.960288)
		(width 0.1143)
		(layer "F.Cu")
		(net "SMB_PECI_LV_R_CLK")
	)
	(segment
		(start 66.294 -42.9768)
		(end 66.294 -43.642788)
		(width 0.1143)
		(layer "F.Cu")
		(net "SMB_PECI_LV_R_CLK")
	)
	(via
		(at 65.983866 -43.952922)
		(size 0.7112)
		(drill 0.3556)
		(layers "F.Cu" "B.Cu")
		(net "SMB_PECI_LV_R_CLK")
	)
	(segment
		(start 52.2224 -13.8684)
		(end 52.1462 -13.9446)
		(width 0.1397)
		(layer "F.Cu")
		(net "CPU_GBE_RX_DN0")
	)
	(segment
		(start 88.374728 -30.378654)
		(end 88.374728 -30.352746)
		(width 0.1397)
		(layer "F.Cu")
		(net "CPU_GBE_RX_DN0")
	)
	(segment
		(start 52.2224 -13.2842)
		(end 52.2224 -13.8684)
		(width 0.1397)
		(layer "F.Cu")
		(net "CPU_GBE_RX_DN0")
	)
	(segment
		(start 88.374728 -30.352746)
		(end 88.035384 -30.013402)
		(width 0.1397)
		(layer "F.Cu")
		(net "CPU_GBE_RX_DN0")
	)
	(via
		(at 88.035384 -30.013402)
		(size 0.4318)
		(drill 0.2032)
		(layers "F.Cu" "B.Cu")
		(net "CPU_GBE_RX_DN0")
	)
	(via
		(at 52.1462 -13.9446)
		(size 0.508)
		(drill 0.254)
		(layers "F.Cu" "B.Cu")
		(net "CPU_GBE_RX_DN0")
	)
	(segment
		(start 85.979 -22.9616)
		(end 82.2706 -19.2532)
		(width 0.1143)
		(layer "In7.Cu")
		(net "CPU_GBE_RX_DN0")
	)
	(segment
		(start 87.841582 -29.8196)
		(end 86.7664 -29.8196)
		(width 0.1143)
		(layer "In7.Cu")
		(net "CPU_GBE_RX_DN0")
	)
	(segment
		(start 86.7664 -29.8196)
		(end 85.205062 -28.258262)
		(width 0.1143)
		(layer "In7.Cu")
		(net "CPU_GBE_RX_DN0")
	)
	(segment
		(start 88.035384 -30.013402)
		(end 87.841582 -29.8196)
		(width 0.1143)
		(layer "In7.Cu")
		(net "CPU_GBE_RX_DN0")
	)
	(segment
		(start 82.2706 -19.2532)
		(end 80.8482 -19.2532)
		(width 0.1143)
		(layer "In7.Cu")
		(net "CPU_GBE_RX_DN0")
	)
	(segment
		(start 75.93965 -15.421356)
		(end 75.93965 -14.52245)
		(width 0.1143)
		(layer "In7.Cu")
		(net "CPU_GBE_RX_DN0")
	)
	(segment
		(start 73.7616 -12.3444)
		(end 57.185306 -12.3444)
		(width 0.1143)
		(layer "In7.Cu")
		(net "CPU_GBE_RX_DN0")
	)
	(segment
		(start 85.979 -24.5364)
		(end 85.979 -22.9616)
		(width 0.1143)
		(layer "In7.Cu")
		(net "CPU_GBE_RX_DN0")
	)
	(segment
		(start 85.205062 -28.258262)
		(end 85.205062 -25.310338)
		(width 0.1143)
		(layer "In7.Cu")
		(net "CPU_GBE_RX_DN0")
	)
	(segment
		(start 53.203094 -15.4305)
		(end 52.4256 -14.653006)
		(width 0.1143)
		(layer "In7.Cu")
		(net "CPU_GBE_RX_DN0")
	)
	(segment
		(start 75.93965 -14.52245)
		(end 73.7616 -12.3444)
		(width 0.1143)
		(layer "In7.Cu")
		(net "CPU_GBE_RX_DN0")
	)
	(segment
		(start 54.099206 -15.4305)
		(end 53.203094 -15.4305)
		(width 0.1143)
		(layer "In7.Cu")
		(net "CPU_GBE_RX_DN0")
	)
	(segment
		(start 85.205062 -25.310338)
		(end 85.979 -24.5364)
		(width 0.1143)
		(layer "In7.Cu")
		(net "CPU_GBE_RX_DN0")
	)
	(segment
		(start 57.185306 -12.3444)
		(end 54.099206 -15.4305)
		(width 0.1143)
		(layer "In7.Cu")
		(net "CPU_GBE_RX_DN0")
	)
	(segment
		(start 77.358494 -16.8402)
		(end 75.93965 -15.421356)
		(width 0.1143)
		(layer "In7.Cu")
		(net "CPU_GBE_RX_DN0")
	)
	(segment
		(start 52.4256 -14.653006)
		(end 52.4256 -14.224)
		(width 0.1143)
		(layer "In7.Cu")
		(net "CPU_GBE_RX_DN0")
	)
	(segment
		(start 52.4256 -14.224)
		(end 52.1462 -13.9446)
		(width 0.1143)
		(layer "In7.Cu")
		(net "CPU_GBE_RX_DN0")
	)
	(segment
		(start 78.4352 -16.8402)
		(end 77.358494 -16.8402)
		(width 0.1143)
		(layer "In7.Cu")
		(net "CPU_GBE_RX_DN0")
	)
	(segment
		(start 80.8482 -19.2532)
		(end 78.4352 -16.8402)
		(width 0.1143)
		(layer "In7.Cu")
		(net "CPU_GBE_RX_DN0")
	)
	(segment
		(start 65.2018 -47.371)
		(end 65.2018 -48.114712)
		(width 0.1143)
		(layer "F.Cu")
		(net "SMB_HOST_LV_R_DATA")
	)
	(segment
		(start 65.2018 -48.114712)
		(end 65.375282 -48.288194)
		(width 0.1143)
		(layer "F.Cu")
		(net "SMB_HOST_LV_R_DATA")
	)
	(segment
		(start 64.60109 -46.77029)
		(end 65.2018 -47.371)
		(width 0.1143)
		(layer "F.Cu")
		(net "SMB_HOST_LV_R_DATA")
	)
	(segment
		(start 64.60109 -45.8216)
		(end 64.60109 -46.77029)
		(width 0.1143)
		(layer "F.Cu")
		(net "SMB_HOST_LV_R_DATA")
	)
	(via
		(at 65.375282 -48.288194)
		(size 0.7112)
		(drill 0.3556)
		(layers "F.Cu" "B.Cu")
		(net "SMB_HOST_LV_R_DATA")
	)
	(segment
		(start 130.8227 -33.533334)
		(end 130.423666 -33.533334)
		(width 0.1143)
		(layer "F.Cu")
		(net "SMB_PECI_LV_CLK")
	)
	(segment
		(start 78.646782 -17.63395)
		(end 78.720188 -17.63395)
		(width 0.1143)
		(layer "F.Cu")
		(net "SMB_PECI_LV_CLK")
	)
	(segment
		(start 86.853014 -18.245582)
		(end 87.223346 -17.87525)
		(width 0.1143)
		(layer "F.Cu")
		(net "SMB_PECI_LV_CLK")
	)
	(segment
		(start 74.34961 -16.85925)
		(end 75.12431 -17.63395)
		(width 0.1143)
		(layer "F.Cu")
		(net "SMB_PECI_LV_CLK")
	)
	(segment
		(start 130.418332 -33.528)
		(end 130.423666 -33.533334)
		(width 0.1143)
		(layer "F.Cu")
		(net "SMB_PECI_LV_CLK")
	)
	(segment
		(start 116.268246 -17.012158)
		(end 116.268246 -22.92604)
		(width 0.1143)
		(layer "F.Cu")
		(net "SMB_PECI_LV_CLK")
	)
	(segment
		(start 102.936548 -13.843)
		(end 113.099088 -13.843)
		(width 0.1143)
		(layer "F.Cu")
		(net "SMB_PECI_LV_CLK")
	)
	(segment
		(start 100.396548 -16.383)
		(end 102.936548 -13.843)
		(width 0.1143)
		(layer "F.Cu")
		(net "SMB_PECI_LV_CLK")
	)
	(segment
		(start 64.897 -42.926)
		(end 64.897 -43.77944)
		(width 0.1143)
		(layer "F.Cu")
		(net "SMB_PECI_LV_CLK")
	)
	(segment
		(start 79.980028 -18.89379)
		(end 84.364068 -18.89379)
		(width 0.1143)
		(layer "F.Cu")
		(net "SMB_PECI_LV_CLK")
	)
	(segment
		(start 87.223346 -17.87525)
		(end 88.620346 -17.87525)
		(width 0.1143)
		(layer "F.Cu")
		(net "SMB_PECI_LV_CLK")
	)
	(segment
		(start 128.5748 -32.8168)
		(end 128.5748 -33.528)
		(width 0.1143)
		(layer "F.Cu")
		(net "SMB_PECI_LV_CLK")
	)
	(segment
		(start 78.720188 -17.63395)
		(end 79.980028 -18.89379)
		(width 0.1143)
		(layer "F.Cu")
		(net "SMB_PECI_LV_CLK")
	)
	(segment
		(start 90.112596 -16.383)
		(end 100.396548 -16.383)
		(width 0.1143)
		(layer "F.Cu")
		(net "SMB_PECI_LV_CLK")
	)
	(segment
		(start 78.646528 -17.633696)
		(end 78.646782 -17.63395)
		(width 0.1143)
		(layer "F.Cu")
		(net "SMB_PECI_LV_CLK")
	)
	(segment
		(start 113.099088 -13.843)
		(end 116.268246 -17.012158)
		(width 0.1143)
		(layer "F.Cu")
		(net "SMB_PECI_LV_CLK")
	)
	(segment
		(start 75.12431 -17.63395)
		(end 78.309724 -17.63395)
		(width 0.1143)
		(layer "F.Cu")
		(net "SMB_PECI_LV_CLK")
	)
	(segment
		(start 128.5748 -33.528)
		(end 130.418332 -33.528)
		(width 0.1143)
		(layer "F.Cu")
		(net "SMB_PECI_LV_CLK")
	)
	(segment
		(start 85.012276 -18.245582)
		(end 86.853014 -18.245582)
		(width 0.1143)
		(layer "F.Cu")
		(net "SMB_PECI_LV_CLK")
	)
	(segment
		(start 66.229738 -18.56105)
		(end 67.931538 -16.85925)
		(width 0.1143)
		(layer "F.Cu")
		(net "SMB_PECI_LV_CLK")
	)
	(segment
		(start 63.5762 -18.7452)
		(end 63.76035 -18.56105)
		(width 0.1143)
		(layer "F.Cu")
		(net "SMB_PECI_LV_CLK")
	)
	(segment
		(start 66.294 -42.1132)
		(end 65.7098 -42.1132)
		(width 0.1143)
		(layer "F.Cu")
		(net "SMB_PECI_LV_CLK")
	)
	(segment
		(start 124.587 -28.829)
		(end 128.5748 -32.8168)
		(width 0.1143)
		(layer "F.Cu")
		(net "SMB_PECI_LV_CLK")
	)
	(segment
		(start 131.583176 -34.29381)
		(end 130.8227 -33.533334)
		(width 0.1143)
		(layer "F.Cu")
		(net "SMB_PECI_LV_CLK")
	)
	(segment
		(start 116.268246 -22.92604)
		(end 122.171206 -28.829)
		(width 0.1143)
		(layer "F.Cu")
		(net "SMB_PECI_LV_CLK")
	)
	(segment
		(start 84.364068 -18.89379)
		(end 85.012276 -18.245582)
		(width 0.1143)
		(layer "F.Cu")
		(net "SMB_PECI_LV_CLK")
	)
	(segment
		(start 122.171206 -28.829)
		(end 124.587 -28.829)
		(width 0.1143)
		(layer "F.Cu")
		(net "SMB_PECI_LV_CLK")
	)
	(segment
		(start 88.620346 -17.87525)
		(end 90.112596 -16.383)
		(width 0.1143)
		(layer "F.Cu")
		(net "SMB_PECI_LV_CLK")
	)
	(segment
		(start 78.309724 -17.63395)
		(end 78.309978 -17.633696)
		(width 0.1143)
		(layer "F.Cu")
		(net "SMB_PECI_LV_CLK")
	)
	(segment
		(start 78.309978 -17.633696)
		(end 78.646528 -17.633696)
		(width 0.1143)
		(layer "F.Cu")
		(net "SMB_PECI_LV_CLK")
	)
	(segment
		(start 65.7098 -42.1132)
		(end 64.897 -42.926)
		(width 0.1143)
		(layer "F.Cu")
		(net "SMB_PECI_LV_CLK")
	)
	(segment
		(start 64.897 -43.77944)
		(end 64.389 -44.28744)
		(width 0.1143)
		(layer "F.Cu")
		(net "SMB_PECI_LV_CLK")
	)
	(segment
		(start 63.76035 -18.56105)
		(end 66.229738 -18.56105)
		(width 0.1143)
		(layer "F.Cu")
		(net "SMB_PECI_LV_CLK")
	)
	(segment
		(start 132.1308 -34.29381)
		(end 131.583176 -34.29381)
		(width 0.1143)
		(layer "F.Cu")
		(net "SMB_PECI_LV_CLK")
	)
	(segment
		(start 67.931538 -16.85925)
		(end 74.34961 -16.85925)
		(width 0.1143)
		(layer "F.Cu")
		(net "SMB_PECI_LV_CLK")
	)
	(via
		(at 130.423666 -33.533334)
		(size 0.7112)
		(drill 0.3556)
		(layers "F.Cu" "B.Cu")
		(net "SMB_PECI_LV_CLK")
	)
	(via
		(at 63.5762 -18.7452)
		(size 0.508)
		(drill 0.254)
		(layers "F.Cu" "B.Cu")
		(net "SMB_PECI_LV_CLK")
	)
	(via
		(at 64.389 -44.28744)
		(size 0.508)
		(drill 0.254)
		(layers "F.Cu" "B.Cu")
		(net "SMB_PECI_LV_CLK")
	)
	(segment
		(start 64.389 -42.734484)
		(end 64.389 -44.28744)
		(width 0.0889)
		(layer "In9.Cu")
		(net "SMB_PECI_LV_CLK")
	)
	(segment
		(start 63.171832 -41.517316)
		(end 64.389 -42.734484)
		(width 0.0889)
		(layer "In9.Cu")
		(net "SMB_PECI_LV_CLK")
	)
	(segment
		(start 63.171832 -19.149568)
		(end 63.171832 -41.517316)
		(width 0.0889)
		(layer "In9.Cu")
		(net "SMB_PECI_LV_CLK")
	)
	(segment
		(start 63.5762 -18.7452)
		(end 63.171832 -19.149568)
		(width 0.0889)
		(layer "In9.Cu")
		(net "SMB_PECI_LV_CLK")
	)
	(segment
		(start 52.9844 -13.9192)
		(end 53.0098 -13.9446)
		(width 0.1397)
		(layer "F.Cu")
		(net "CPU_GBE_RX_DP0")
	)
	(segment
		(start 88.374728 -29.616654)
		(end 88.374728 -29.590746)
		(width 0.1397)
		(layer "F.Cu")
		(net "CPU_GBE_RX_DP0")
	)
	(segment
		(start 52.9844 -13.2842)
		(end 52.9844 -13.9192)
		(width 0.1397)
		(layer "F.Cu")
		(net "CPU_GBE_RX_DP0")
	)
	(segment
		(start 88.374728 -29.590746)
		(end 88.035384 -29.251402)
		(width 0.1397)
		(layer "F.Cu")
		(net "CPU_GBE_RX_DP0")
	)
	(via
		(at 53.0098 -13.9446)
		(size 0.508)
		(drill 0.254)
		(layers "F.Cu" "B.Cu")
		(net "CPU_GBE_RX_DP0")
	)
	(via
		(at 88.035384 -29.251402)
		(size 0.4318)
		(drill 0.2032)
		(layers "F.Cu" "B.Cu")
		(net "CPU_GBE_RX_DP0")
	)
	(segment
		(start 86.3092 -22.824694)
		(end 82.407506 -18.923)
		(width 0.1143)
		(layer "In7.Cu")
		(net "CPU_GBE_RX_DP0")
	)
	(segment
		(start 76.26985 -15.28445)
		(end 76.26985 -14.385544)
		(width 0.1143)
		(layer "In7.Cu")
		(net "CPU_GBE_RX_DP0")
	)
	(segment
		(start 57.0484 -12.0142)
		(end 53.9623 -15.1003)
		(width 0.1143)
		(layer "In7.Cu")
		(net "CPU_GBE_RX_DP0")
	)
	(segment
		(start 78.572106 -16.51)
		(end 77.4954 -16.51)
		(width 0.1143)
		(layer "In7.Cu")
		(net "CPU_GBE_RX_DP0")
	)
	(segment
		(start 53.34 -15.1003)
		(end 52.7558 -14.5161)
		(width 0.1143)
		(layer "In7.Cu")
		(net "CPU_GBE_RX_DP0")
	)
	(segment
		(start 87.797386 -29.4894)
		(end 86.903306 -29.4894)
		(width 0.1143)
		(layer "In7.Cu")
		(net "CPU_GBE_RX_DP0")
	)
	(segment
		(start 88.035384 -29.251402)
		(end 87.797386 -29.4894)
		(width 0.1143)
		(layer "In7.Cu")
		(net "CPU_GBE_RX_DP0")
	)
	(segment
		(start 80.985106 -18.923)
		(end 78.572106 -16.51)
		(width 0.1143)
		(layer "In7.Cu")
		(net "CPU_GBE_RX_DP0")
	)
	(segment
		(start 85.535262 -28.121356)
		(end 85.535262 -25.447244)
		(width 0.1143)
		(layer "In7.Cu")
		(net "CPU_GBE_RX_DP0")
	)
	(segment
		(start 73.898506 -12.0142)
		(end 57.0484 -12.0142)
		(width 0.1143)
		(layer "In7.Cu")
		(net "CPU_GBE_RX_DP0")
	)
	(segment
		(start 86.903306 -29.4894)
		(end 85.535262 -28.121356)
		(width 0.1143)
		(layer "In7.Cu")
		(net "CPU_GBE_RX_DP0")
	)
	(segment
		(start 77.4954 -16.51)
		(end 76.26985 -15.28445)
		(width 0.1143)
		(layer "In7.Cu")
		(net "CPU_GBE_RX_DP0")
	)
	(segment
		(start 52.7558 -14.5161)
		(end 52.7558 -14.1986)
		(width 0.1143)
		(layer "In7.Cu")
		(net "CPU_GBE_RX_DP0")
	)
	(segment
		(start 53.9623 -15.1003)
		(end 53.34 -15.1003)
		(width 0.1143)
		(layer "In7.Cu")
		(net "CPU_GBE_RX_DP0")
	)
	(segment
		(start 86.3092 -24.673306)
		(end 86.3092 -22.824694)
		(width 0.1143)
		(layer "In7.Cu")
		(net "CPU_GBE_RX_DP0")
	)
	(segment
		(start 52.7558 -14.1986)
		(end 53.0098 -13.9446)
		(width 0.1143)
		(layer "In7.Cu")
		(net "CPU_GBE_RX_DP0")
	)
	(segment
		(start 76.26985 -14.385544)
		(end 73.898506 -12.0142)
		(width 0.1143)
		(layer "In7.Cu")
		(net "CPU_GBE_RX_DP0")
	)
	(segment
		(start 82.407506 -18.923)
		(end 80.985106 -18.923)
		(width 0.1143)
		(layer "In7.Cu")
		(net "CPU_GBE_RX_DP0")
	)
	(segment
		(start 85.535262 -25.447244)
		(end 86.3092 -24.673306)
		(width 0.1143)
		(layer "In7.Cu")
		(net "CPU_GBE_RX_DP0")
	)
	(segment
		(start 149.01037 -47.33417)
		(end 148.5392 -46.863)
		(width 0.1143)
		(layer "F.Cu")
		(net "C_ASDO")
	)
	(segment
		(start 154.65425 -50.76825)
		(end 154.813 -50.927)
		(width 0.1143)
		(layer "F.Cu")
		(net "C_ASDO")
	)
	(segment
		(start 153.8224 -47.4091)
		(end 153.8224 -48.662336)
		(width 0.1143)
		(layer "F.Cu")
		(net "C_ASDO")
	)
	(segment
		(start 154.88285 -50.99685)
		(end 154.813 -50.927)
		(width 0.1143)
		(layer "F.Cu")
		(net "C_ASDO")
	)
	(segment
		(start 148.5392 -46.863)
		(end 148.5392 -46.5582)
		(width 0.1143)
		(layer "F.Cu")
		(net "C_ASDO")
	)
	(segment
		(start 154.055064 -48.895)
		(end 154.56535 -48.895)
		(width 0.1143)
		(layer "F.Cu")
		(net "C_ASDO")
	)
	(segment
		(start 154.56535 -48.895)
		(end 154.65425 -48.9839)
		(width 0.1143)
		(layer "F.Cu")
		(net "C_ASDO")
	)
	(segment
		(start 154.88285 -54.8513)
		(end 154.88285 -50.99685)
		(width 0.1143)
		(layer "F.Cu")
		(net "C_ASDO")
	)
	(segment
		(start 154.65425 -48.9839)
		(end 154.65425 -50.76825)
		(width 0.1143)
		(layer "F.Cu")
		(net "C_ASDO")
	)
	(segment
		(start 154.97175 -54.9402)
		(end 154.88285 -54.8513)
		(width 0.1143)
		(layer "F.Cu")
		(net "C_ASDO")
	)
	(segment
		(start 153.8224 -48.662336)
		(end 154.055064 -48.895)
		(width 0.1143)
		(layer "F.Cu")
		(net "C_ASDO")
	)
	(segment
		(start 149.01037 -47.5107)
		(end 149.01037 -47.33417)
		(width 0.1143)
		(layer "F.Cu")
		(net "C_ASDO")
	)
	(segment
		(start 155.575 -54.9402)
		(end 154.97175 -54.9402)
		(width 0.1143)
		(layer "F.Cu")
		(net "C_ASDO")
	)
	(via
		(at 153.8224 -47.4091)
		(size 0.508)
		(drill 0.254)
		(layers "F.Cu" "B.Cu")
		(net "C_ASDO")
	)
	(via
		(at 148.5392 -46.5582)
		(size 0.508)
		(drill 0.254)
		(layers "F.Cu" "B.Cu")
		(net "C_ASDO")
	)
	(segment
		(start 151.4602 -45.72)
		(end 151.2824 -45.72)
		(width 0.0889)
		(layer "In7.Cu")
		(net "C_ASDO")
	)
	(segment
		(start 149.7711 -45.6819)
		(end 149.7711 -46.0375)
		(width 0.0889)
		(layer "In7.Cu")
		(net "C_ASDO")
	)
	(segment
		(start 150.1267 -46.0375)
		(end 150.1267 -45.6819)
		(width 0.0889)
		(layer "In7.Cu")
		(net "C_ASDO")
	)
	(segment
		(start 151.1935 -46.0375)
		(end 151.1046 -46.1264)
		(width 0.0889)
		(layer "In7.Cu")
		(net "C_ASDO")
	)
	(segment
		(start 149.3266 -45.593)
		(end 143.8529 -45.593)
		(width 0.0889)
		(layer "In7.Cu")
		(net "C_ASDO")
	)
	(segment
		(start 149.86 -45.593)
		(end 149.7711 -45.6819)
		(width 0.0889)
		(layer "In7.Cu")
		(net "C_ASDO")
	)
	(segment
		(start 150.8379 -46.0375)
		(end 150.8379 -45.6819)
		(width 0.0889)
		(layer "In7.Cu")
		(net "C_ASDO")
	)
	(segment
		(start 143.8529 -45.593)
		(end 143.764 -45.6819)
		(width 0.0889)
		(layer "In7.Cu")
		(net "C_ASDO")
	)
	(segment
		(start 150.8379 -45.6819)
		(end 150.749 -45.593)
		(width 0.0889)
		(layer "In7.Cu")
		(net "C_ASDO")
	)
	(segment
		(start 151.1046 -46.1264)
		(end 150.9268 -46.1264)
		(width 0.0889)
		(layer "In7.Cu")
		(net "C_ASDO")
	)
	(segment
		(start 152.959816 -47.4091)
		(end 151.5491 -45.998384)
		(width 0.0889)
		(layer "In7.Cu")
		(net "C_ASDO")
	)
	(segment
		(start 149.4155 -45.6819)
		(end 149.3266 -45.593)
		(width 0.0889)
		(layer "In7.Cu")
		(net "C_ASDO")
	)
	(segment
		(start 151.5491 -45.8089)
		(end 151.4602 -45.72)
		(width 0.0889)
		(layer "In7.Cu")
		(net "C_ASDO")
	)
	(segment
		(start 150.4823 -45.6819)
		(end 150.4823 -46.0375)
		(width 0.0889)
		(layer "In7.Cu")
		(net "C_ASDO")
	)
	(segment
		(start 150.9268 -46.1264)
		(end 150.8379 -46.0375)
		(width 0.0889)
		(layer "In7.Cu")
		(net "C_ASDO")
	)
	(segment
		(start 149.7711 -46.0375)
		(end 149.6822 -46.1264)
		(width 0.0889)
		(layer "In7.Cu")
		(net "C_ASDO")
	)
	(segment
		(start 150.3934 -46.1264)
		(end 150.2156 -46.1264)
		(width 0.0889)
		(layer "In7.Cu")
		(net "C_ASDO")
	)
	(segment
		(start 151.5491 -45.998384)
		(end 151.5491 -45.8089)
		(width 0.0889)
		(layer "In7.Cu")
		(net "C_ASDO")
	)
	(segment
		(start 149.4155 -46.0375)
		(end 149.4155 -45.6819)
		(width 0.0889)
		(layer "In7.Cu")
		(net "C_ASDO")
	)
	(segment
		(start 148.11375 -46.13275)
		(end 148.5392 -46.5582)
		(width 0.0889)
		(layer "In7.Cu")
		(net "C_ASDO")
	)
	(segment
		(start 150.0378 -45.593)
		(end 149.86 -45.593)
		(width 0.0889)
		(layer "In7.Cu")
		(net "C_ASDO")
	)
	(segment
		(start 143.764 -45.6819)
		(end 143.764 -46.04385)
		(width 0.0889)
		(layer "In7.Cu")
		(net "C_ASDO")
	)
	(segment
		(start 150.2156 -46.1264)
		(end 150.1267 -46.0375)
		(width 0.0889)
		(layer "In7.Cu")
		(net "C_ASDO")
	)
	(segment
		(start 149.6822 -46.1264)
		(end 149.5044 -46.1264)
		(width 0.0889)
		(layer "In7.Cu")
		(net "C_ASDO")
	)
	(segment
		(start 150.4823 -46.0375)
		(end 150.3934 -46.1264)
		(width 0.0889)
		(layer "In7.Cu")
		(net "C_ASDO")
	)
	(segment
		(start 143.764 -46.04385)
		(end 143.8529 -46.13275)
		(width 0.0889)
		(layer "In7.Cu")
		(net "C_ASDO")
	)
	(segment
		(start 150.1267 -45.6819)
		(end 150.0378 -45.593)
		(width 0.0889)
		(layer "In7.Cu")
		(net "C_ASDO")
	)
	(segment
		(start 151.1935 -45.8089)
		(end 151.1935 -46.0375)
		(width 0.0889)
		(layer "In7.Cu")
		(net "C_ASDO")
	)
	(segment
		(start 143.8529 -46.13275)
		(end 148.11375 -46.13275)
		(width 0.0889)
		(layer "In7.Cu")
		(net "C_ASDO")
	)
	(segment
		(start 149.5044 -46.1264)
		(end 149.4155 -46.0375)
		(width 0.0889)
		(layer "In7.Cu")
		(net "C_ASDO")
	)
	(segment
		(start 150.5712 -45.593)
		(end 150.4823 -45.6819)
		(width 0.0889)
		(layer "In7.Cu")
		(net "C_ASDO")
	)
	(segment
		(start 151.2824 -45.72)
		(end 151.1935 -45.8089)
		(width 0.0889)
		(layer "In7.Cu")
		(net "C_ASDO")
	)
	(segment
		(start 153.8224 -47.4091)
		(end 152.959816 -47.4091)
		(width 0.0889)
		(layer "In7.Cu")
		(net "C_ASDO")
	)
	(segment
		(start 150.749 -45.593)
		(end 150.5712 -45.593)
		(width 0.0889)
		(layer "In7.Cu")
		(net "C_ASDO")
	)
	(segment
		(start 70.26275 -46.4058)
		(end 70.05955 -46.2026)
		(width 0.1143)
		(layer "F.Cu")
		(net "SMB_PECI_LV_R_DATA")
	)
	(segment
		(start 68.843906 -46.246542)
		(end 68.828158 -46.246542)
		(width 0.1143)
		(layer "F.Cu")
		(net "SMB_PECI_LV_R_DATA")
	)
	(segment
		(start 70.05955 -46.2026)
		(end 68.887848 -46.2026)
		(width 0.1143)
		(layer "F.Cu")
		(net "SMB_PECI_LV_R_DATA")
	)
	(segment
		(start 70.2818 -46.4058)
		(end 70.26275 -46.4058)
		(width 0.1143)
		(layer "F.Cu")
		(net "SMB_PECI_LV_R_DATA")
	)
	(segment
		(start 68.799964 -46.246542)
		(end 68.828158 -46.246542)
		(width 0.1143)
		(layer "F.Cu")
		(net "SMB_PECI_LV_R_DATA")
	)
	(segment
		(start 68.887848 -46.2026)
		(end 68.843906 -46.246542)
		(width 0.1143)
		(layer "F.Cu")
		(net "SMB_PECI_LV_R_DATA")
	)
	(segment
		(start 68.676266 -46.37024)
		(end 68.799964 -46.246542)
		(width 0.1143)
		(layer "F.Cu")
		(net "SMB_PECI_LV_R_DATA")
	)
	(segment
		(start 67.6275 -46.37024)
		(end 68.676266 -46.37024)
		(width 0.1143)
		(layer "F.Cu")
		(net "SMB_PECI_LV_R_DATA")
	)
	(via
		(at 68.828158 -46.246542)
		(size 0.7112)
		(drill 0.3556)
		(layers "F.Cu" "B.Cu")
		(net "SMB_PECI_LV_R_DATA")
	)
	(segment
		(start 7.93115 -45.912024)
		(end 7.030974 -46.8122)
		(width 0.1143)
		(layer "F.Cu")
		(net "SMB_HOST_LV_CLK")
	)
	(segment
		(start 65.405 -67.853306)
		(end 65.405 -67.72783)
		(width 0.1143)
		(layer "F.Cu")
		(net "SMB_HOST_LV_CLK")
	)
	(segment
		(start 8.509 -45.2374)
		(end 7.93115 -45.81525)
		(width 0.1143)
		(layer "F.Cu")
		(net "SMB_HOST_LV_CLK")
	)
	(segment
		(start 62.0522 -49.0728)
		(end 62.484 -49.0728)
		(width 0.1143)
		(layer "F.Cu")
		(net "SMB_HOST_LV_CLK")
	)
	(segment
		(start 79.471774 -72.486774)
		(end 76.5048 -69.5198)
		(width 0.1143)
		(layer "F.Cu")
		(net "SMB_HOST_LV_CLK")
	)
	(segment
		(start 74.705464 -69.5198)
		(end 73.740264 -70.485)
		(width 0.1143)
		(layer "F.Cu")
		(net "SMB_HOST_LV_CLK")
	)
	(segment
		(start 76.5048 -69.5198)
		(end 74.705464 -69.5198)
		(width 0.1143)
		(layer "F.Cu")
		(net "SMB_HOST_LV_CLK")
	)
	(segment
		(start 183.9976 -45.3136)
		(end 183.9976 -44.71035)
		(width 0.1143)
		(layer "F.Cu")
		(net "SMB_HOST_LV_CLK")
	)
	(segment
		(start 81.650332 -71.755)
		(end 80.918558 -72.486774)
		(width 0.1143)
		(layer "F.Cu")
		(net "SMB_HOST_LV_CLK")
	)
	(segment
		(start 119.550942 -68.43141)
		(end 120.326658 -68.43141)
		(width 0.1143)
		(layer "F.Cu")
		(net "SMB_HOST_LV_CLK")
	)
	(segment
		(start 198.755 -8.510778)
		(end 198.755 -8.840978)
		(width 0.1143)
		(layer "F.Cu")
		(net "SMB_HOST_LV_CLK")
	)
	(segment
		(start 183.642 -45.6692)
		(end 183.9976 -45.3136)
		(width 0.1143)
		(layer "F.Cu")
		(net "SMB_HOST_LV_CLK")
	)
	(segment
		(start 197.612 -7.951978)
		(end 198.1962 -7.951978)
		(width 0.1143)
		(layer "F.Cu")
		(net "SMB_HOST_LV_CLK")
	)
	(segment
		(start 118.237 -64.8208)
		(end 118.237 -67.117468)
		(width 0.1143)
		(layer "F.Cu")
		(net "SMB_HOST_LV_CLK")
	)
	(segment
		(start 182.14975 -44.71035)
		(end 183.9976 -44.71035)
		(width 0.1143)
		(layer "F.Cu")
		(net "SMB_HOST_LV_CLK")
	)
	(segment
		(start 181.569868 -44.130468)
		(end 177.846482 -40.407082)
		(width 0.1143)
		(layer "F.Cu")
		(net "SMB_HOST_LV_CLK")
	)
	(segment
		(start 177.846482 -30.317948)
		(end 177.53838 -30.009846)
		(width 0.1143)
		(layer "F.Cu")
		(net "SMB_HOST_LV_CLK")
	)
	(segment
		(start 68.036694 -70.485)
		(end 65.405 -67.853306)
		(width 0.1143)
		(layer "F.Cu")
		(net "SMB_HOST_LV_CLK")
	)
	(segment
		(start 7.030974 -46.8122)
		(end 4.8514 -46.8122)
		(width 0.1143)
		(layer "F.Cu")
		(net "SMB_HOST_LV_CLK")
	)
	(segment
		(start 7.93115 -45.81525)
		(end 7.93115 -45.912024)
		(width 0.1143)
		(layer "F.Cu")
		(net "SMB_HOST_LV_CLK")
	)
	(segment
		(start 120.326658 -68.43141)
		(end 120.777 -67.981068)
		(width 0.1143)
		(layer "F.Cu")
		(net "SMB_HOST_LV_CLK")
	)
	(segment
		(start 120.777 -67.981068)
		(end 120.777 -67.5386)
		(width 0.1143)
		(layer "F.Cu")
		(net "SMB_HOST_LV_CLK")
	)
	(segment
		(start 4.8514 -46.8122)
		(end 4.699 -46.6598)
		(width 0.1143)
		(layer "F.Cu")
		(net "SMB_HOST_LV_CLK")
	)
	(segment
		(start 60.9854 -48.514)
		(end 61.4934 -48.514)
		(width 0.1143)
		(layer "F.Cu")
		(net "SMB_HOST_LV_CLK")
	)
	(segment
		(start 198.1962 -7.951978)
		(end 198.755 -8.510778)
		(width 0.1143)
		(layer "F.Cu")
		(net "SMB_HOST_LV_CLK")
	)
	(segment
		(start 73.740264 -70.485)
		(end 68.036694 -70.485)
		(width 0.1143)
		(layer "F.Cu")
		(net "SMB_HOST_LV_CLK")
	)
	(segment
		(start 61.4934 -48.514)
		(end 62.0522 -49.0728)
		(width 0.1143)
		(layer "F.Cu")
		(net "SMB_HOST_LV_CLK")
	)
	(segment
		(start 177.846482 -40.407082)
		(end 177.846482 -30.317948)
		(width 0.1143)
		(layer "F.Cu")
		(net "SMB_HOST_LV_CLK")
	)
	(segment
		(start 81.6864 -71.755)
		(end 81.650332 -71.755)
		(width 0.1143)
		(layer "F.Cu")
		(net "SMB_HOST_LV_CLK")
	)
	(segment
		(start 181.569868 -44.130468)
		(end 182.14975 -44.71035)
		(width 0.1143)
		(layer "F.Cu")
		(net "SMB_HOST_LV_CLK")
	)
	(segment
		(start 118.237 -67.117468)
		(end 119.550942 -68.43141)
		(width 0.1143)
		(layer "F.Cu")
		(net "SMB_HOST_LV_CLK")
	)
	(segment
		(start 80.918558 -72.486774)
		(end 79.471774 -72.486774)
		(width 0.1143)
		(layer "F.Cu")
		(net "SMB_HOST_LV_CLK")
	)
	(via
		(at 117.856 -69.9008)
		(size 0.508)
		(drill 0.254)
		(layers "F.Cu" "B.Cu")
		(net "SMB_HOST_LV_CLK")
	)
	(via
		(at 120.777 -67.5386)
		(size 0.508)
		(drill 0.254)
		(layers "F.Cu" "B.Cu")
		(net "SMB_HOST_LV_CLK")
	)
	(via
		(at 197.612 -7.951978)
		(size 0.508)
		(drill 0.254)
		(layers "F.Cu" "B.Cu")
		(net "SMB_HOST_LV_CLK")
	)
	(via
		(at 38.989 -53.34)
		(size 0.508)
		(drill 0.254)
		(layers "F.Cu" "B.Cu")
		(net "SMB_HOST_LV_CLK")
	)
	(via
		(at 177.53838 -30.009846)
		(size 0.508)
		(drill 0.254)
		(layers "F.Cu" "B.Cu")
		(net "SMB_HOST_LV_CLK")
	)
	(via
		(at 181.569868 -44.130468)
		(size 0.7112)
		(drill 0.3556)
		(layers "F.Cu" "B.Cu")
		(net "SMB_HOST_LV_CLK")
	)
	(via
		(at 65.405 -67.72783)
		(size 0.508)
		(drill 0.254)
		(layers "F.Cu" "B.Cu")
		(net "SMB_HOST_LV_CLK")
	)
	(via
		(at 183.9976 -44.71035)
		(size 0.508)
		(drill 0.254)
		(layers "F.Cu" "B.Cu")
		(net "SMB_HOST_LV_CLK")
	)
	(via
		(at 8.509 -45.2374)
		(size 0.508)
		(drill 0.254)
		(layers "F.Cu" "B.Cu")
		(net "SMB_HOST_LV_CLK")
	)
	(via
		(at 60.9854 -48.514)
		(size 0.508)
		(drill 0.254)
		(layers "F.Cu" "B.Cu")
		(net "SMB_HOST_LV_CLK")
	)
	(via
		(at 81.6864 -71.755)
		(size 0.508)
		(drill 0.254)
		(layers "F.Cu" "B.Cu")
		(net "SMB_HOST_LV_CLK")
	)
	(segment
		(start 64.9097 -66.6877)
		(end 65.405 -67.183)
		(width 0.1143)
		(layer "B.Cu")
		(net "SMB_HOST_LV_CLK")
	)
	(segment
		(start 65.405 -67.183)
		(end 65.405 -67.72783)
		(width 0.1143)
		(layer "B.Cu")
		(net "SMB_HOST_LV_CLK")
	)
	(segment
		(start 38.5572 -50.3682)
		(end 38.37305 -50.55235)
		(width 0.1143)
		(layer "B.Cu")
		(net "SMB_HOST_LV_CLK")
	)
	(segment
		(start 75.1332 -57.912)
		(end 74.93 -57.912)
		(width 0.1143)
		(layer "B.Cu")
		(net "SMB_HOST_LV_CLK")
	)
	(segment
		(start 196.85 -5.1054)
		(end 196.85 -7.189978)
		(width 0.1143)
		(layer "B.Cu")
		(net "SMB_HOST_LV_CLK")
	)
	(segment
		(start 196.85 -7.189978)
		(end 197.612 -7.951978)
		(width 0.1143)
		(layer "B.Cu")
		(net "SMB_HOST_LV_CLK")
	)
	(segment
		(start 60.9854 -48.514)
		(end 61.98235 -49.51095)
		(width 0.1143)
		(layer "B.Cu")
		(net "SMB_HOST_LV_CLK")
	)
	(segment
		(start 118.999 -65.5828)
		(end 118.999 -65.7606)
		(width 0.1143)
		(layer "B.Cu")
		(net "SMB_HOST_LV_CLK")
	)
	(segment
		(start 81.6864 -71.501)
		(end 81.6864 -71.755)
		(width 0.1143)
		(layer "B.Cu")
		(net "SMB_HOST_LV_CLK")
	)
	(segment
		(start 61.98235 -49.51095)
		(end 61.98235 -54.71922)
		(width 0.1143)
		(layer "B.Cu")
		(net "SMB_HOST_LV_CLK")
	)
	(segment
		(start 117.856 -70.470268)
		(end 116.336064 -71.990204)
		(width 0.1143)
		(layer "B.Cu")
		(net "SMB_HOST_LV_CLK")
	)
	(segment
		(start 64.9097 -57.64657)
		(end 64.9097 -66.6877)
		(width 0.1143)
		(layer "B.Cu")
		(net "SMB_HOST_LV_CLK")
	)
	(segment
		(start 38.37305 -51.70805)
		(end 38.88105 -52.21605)
		(width 0.1143)
		(layer "B.Cu")
		(net "SMB_HOST_LV_CLK")
	)
	(segment
		(start 82.42935 -70.289674)
		(end 82.42935 -70.75805)
		(width 0.1143)
		(layer "B.Cu")
		(net "SMB_HOST_LV_CLK")
	)
	(segment
		(start 75.761088 -66.004694)
		(end 75.815444 -66.05905)
		(width 0.1143)
		(layer "B.Cu")
		(net "SMB_HOST_LV_CLK")
	)
	(segment
		(start 118.999 -65.7606)
		(end 120.777 -67.5386)
		(width 0.1143)
		(layer "B.Cu")
		(net "SMB_HOST_LV_CLK")
	)
	(segment
		(start 81.921604 -71.990204)
		(end 81.6864 -71.755)
		(width 0.1143)
		(layer "B.Cu")
		(net "SMB_HOST_LV_CLK")
	)
	(segment
		(start 82.42935 -70.75805)
		(end 81.6864 -71.501)
		(width 0.1143)
		(layer "B.Cu")
		(net "SMB_HOST_LV_CLK")
	)
	(segment
		(start 38.88105 -52.21605)
		(end 38.88105 -53.23205)
		(width 0.1143)
		(layer "B.Cu")
		(net "SMB_HOST_LV_CLK")
	)
	(segment
		(start 38.88105 -53.23205)
		(end 38.989 -53.34)
		(width 0.1143)
		(layer "B.Cu")
		(net "SMB_HOST_LV_CLK")
	)
	(segment
		(start 73.97115 -58.87085)
		(end 73.97115 -64.839088)
		(width 0.1143)
		(layer "B.Cu")
		(net "SMB_HOST_LV_CLK")
	)
	(segment
		(start 38.37305 -50.55235)
		(end 38.37305 -51.70805)
		(width 0.1143)
		(layer "B.Cu")
		(net "SMB_HOST_LV_CLK")
	)
	(segment
		(start 73.97115 -64.839088)
		(end 75.136756 -66.004694)
		(width 0.1143)
		(layer "B.Cu")
		(net "SMB_HOST_LV_CLK")
	)
	(segment
		(start 117.856 -69.9008)
		(end 117.856 -70.470268)
		(width 0.1143)
		(layer "B.Cu")
		(net "SMB_HOST_LV_CLK")
	)
	(segment
		(start 78.198726 -66.05905)
		(end 82.42935 -70.289674)
		(width 0.1143)
		(layer "B.Cu")
		(net "SMB_HOST_LV_CLK")
	)
	(segment
		(start 116.336064 -71.990204)
		(end 81.921604 -71.990204)
		(width 0.1143)
		(layer "B.Cu")
		(net "SMB_HOST_LV_CLK")
	)
	(segment
		(start 61.98235 -54.71922)
		(end 64.9097 -57.64657)
		(width 0.1143)
		(layer "B.Cu")
		(net "SMB_HOST_LV_CLK")
	)
	(segment
		(start 74.93 -57.912)
		(end 73.97115 -58.87085)
		(width 0.1143)
		(layer "B.Cu")
		(net "SMB_HOST_LV_CLK")
	)
	(segment
		(start 120.777 -67.5386)
		(end 120.777 -68.326)
		(width 0.1143)
		(layer "B.Cu")
		(net "SMB_HOST_LV_CLK")
	)
	(segment
		(start 75.815444 -66.05905)
		(end 78.198726 -66.05905)
		(width 0.1143)
		(layer "B.Cu")
		(net "SMB_HOST_LV_CLK")
	)
	(segment
		(start 75.136756 -66.004694)
		(end 75.761088 -66.004694)
		(width 0.1143)
		(layer "B.Cu")
		(net "SMB_HOST_LV_CLK")
	)
	(segment
		(start 37.8968 -52.8066)
		(end 38.4556 -52.8066)
		(width 0.0889)
		(layer "In2.Cu")
		(net "SMB_HOST_LV_CLK")
	)
	(segment
		(start 117.856 -69.9008)
		(end 118.364 -70.4088)
		(width 0.0889)
		(layer "In2.Cu")
		(net "SMB_HOST_LV_CLK")
	)
	(segment
		(start 120.195594 -70.4088)
		(end 120.777 -69.827394)
		(width 0.0889)
		(layer "In2.Cu")
		(net "SMB_HOST_LV_CLK")
	)
	(segment
		(start 29.292042 -50.704242)
		(end 30.808676 -50.704242)
		(width 0.0889)
		(layer "In2.Cu")
		(net "SMB_HOST_LV_CLK")
	)
	(segment
		(start 118.364 -70.4088)
		(end 120.195594 -70.4088)
		(width 0.0889)
		(layer "In2.Cu")
		(net "SMB_HOST_LV_CLK")
	)
	(segment
		(start 8.509 -45.2374)
		(end 9.1567 -45.8851)
		(width 0.0889)
		(layer "In2.Cu")
		(net "SMB_HOST_LV_CLK")
	)
	(segment
		(start 30.808676 -50.704242)
		(end 33.708086 -53.603652)
		(width 0.0889)
		(layer "In2.Cu")
		(net "SMB_HOST_LV_CLK")
	)
	(segment
		(start 24.4729 -45.8851)
		(end 29.292042 -50.704242)
		(width 0.0889)
		(layer "In2.Cu")
		(net "SMB_HOST_LV_CLK")
	)
	(segment
		(start 120.777 -69.827394)
		(end 120.777 -67.5386)
		(width 0.0889)
		(layer "In2.Cu")
		(net "SMB_HOST_LV_CLK")
	)
	(segment
		(start 9.1567 -45.8851)
		(end 24.4729 -45.8851)
		(width 0.0889)
		(layer "In2.Cu")
		(net "SMB_HOST_LV_CLK")
	)
	(segment
		(start 33.708086 -53.603652)
		(end 37.099748 -53.603652)
		(width 0.0889)
		(layer "In2.Cu")
		(net "SMB_HOST_LV_CLK")
	)
	(segment
		(start 38.4556 -52.8066)
		(end 38.989 -53.34)
		(width 0.0889)
		(layer "In2.Cu")
		(net "SMB_HOST_LV_CLK")
	)
	(segment
		(start 37.099748 -53.603652)
		(end 37.8968 -52.8066)
		(width 0.0889)
		(layer "In2.Cu")
		(net "SMB_HOST_LV_CLK")
	)
	(segment
		(start 43.214544 -52.213256)
		(end 47.71009 -52.213256)
		(width 0.0889)
		(layer "In4.Cu")
		(net "SMB_HOST_LV_CLK")
	)
	(segment
		(start 42.65295 -52.77485)
		(end 43.214544 -52.213256)
		(width 0.0889)
		(layer "In4.Cu")
		(net "SMB_HOST_LV_CLK")
	)
	(segment
		(start 48.506634 -53.0098)
		(end 54.301898 -53.0098)
		(width 0.0889)
		(layer "In4.Cu")
		(net "SMB_HOST_LV_CLK")
	)
	(segment
		(start 58.797698 -48.514)
		(end 60.9854 -48.514)
		(width 0.0889)
		(layer "In4.Cu")
		(net "SMB_HOST_LV_CLK")
	)
	(segment
		(start 47.71009 -52.213256)
		(end 48.506634 -53.0098)
		(width 0.0889)
		(layer "In4.Cu")
		(net "SMB_HOST_LV_CLK")
	)
	(segment
		(start 38.989 -53.34)
		(end 39.55415 -52.77485)
		(width 0.0889)
		(layer "In4.Cu")
		(net "SMB_HOST_LV_CLK")
	)
	(segment
		(start 39.55415 -52.77485)
		(end 42.65295 -52.77485)
		(width 0.0889)
		(layer "In4.Cu")
		(net "SMB_HOST_LV_CLK")
	)
	(segment
		(start 54.301898 -53.0098)
		(end 58.797698 -48.514)
		(width 0.0889)
		(layer "In4.Cu")
		(net "SMB_HOST_LV_CLK")
	)
	(segment
		(start 189.57925 -50.09515)
		(end 189.57925 -48.657256)
		(width 0.0889)
		(layer "In7.Cu")
		(net "SMB_HOST_LV_CLK")
	)
	(segment
		(start 117.856 -69.9008)
		(end 119.285004 -71.329804)
		(width 0.0889)
		(layer "In7.Cu")
		(net "SMB_HOST_LV_CLK")
	)
	(segment
		(start 187.668154 -46.74616)
		(end 186.03341 -46.74616)
		(width 0.0889)
		(layer "In7.Cu")
		(net "SMB_HOST_LV_CLK")
	)
	(segment
		(start 189.696344 -71.329804)
		(end 193.049398 -67.97675)
		(width 0.0889)
		(layer "In7.Cu")
		(net "SMB_HOST_LV_CLK")
	)
	(segment
		(start 119.285004 -71.329804)
		(end 189.696344 -71.329804)
		(width 0.0889)
		(layer "In7.Cu")
		(net "SMB_HOST_LV_CLK")
	)
	(segment
		(start 186.7154 -56.797702)
		(end 186.7154 -52.959)
		(width 0.0889)
		(layer "In7.Cu")
		(net "SMB_HOST_LV_CLK")
	)
	(segment
		(start 193.049398 -63.1317)
		(end 186.7154 -56.797702)
		(width 0.0889)
		(layer "In7.Cu")
		(net "SMB_HOST_LV_CLK")
	)
	(segment
		(start 186.03341 -46.74616)
		(end 183.9976 -44.71035)
		(width 0.0889)
		(layer "In7.Cu")
		(net "SMB_HOST_LV_CLK")
	)
	(segment
		(start 193.049398 -67.97675)
		(end 193.049398 -63.1317)
		(width 0.0889)
		(layer "In7.Cu")
		(net "SMB_HOST_LV_CLK")
	)
	(segment
		(start 186.7154 -52.959)
		(end 189.57925 -50.09515)
		(width 0.0889)
		(layer "In7.Cu")
		(net "SMB_HOST_LV_CLK")
	)
	(segment
		(start 189.57925 -48.657256)
		(end 187.668154 -46.74616)
		(width 0.0889)
		(layer "In7.Cu")
		(net "SMB_HOST_LV_CLK")
	)
	(segment
		(start 177.5714 -29.972)
		(end 177.5714 -29.976826)
		(width 0.0889)
		(layer "In9.Cu")
		(net "SMB_HOST_LV_CLK")
	)
	(segment
		(start 181.356 -26.1874)
		(end 177.5714 -29.972)
		(width 0.0889)
		(layer "In9.Cu")
		(net "SMB_HOST_LV_CLK")
	)
	(segment
		(start 197.612 -13.174218)
		(end 188.904118 -21.8821)
		(width 0.0889)
		(layer "In9.Cu")
		(net "SMB_HOST_LV_CLK")
	)
	(segment
		(start 188.904118 -21.8821)
		(end 183.277764 -21.8821)
		(width 0.0889)
		(layer "In9.Cu")
		(net "SMB_HOST_LV_CLK")
	)
	(segment
		(start 183.277764 -21.8821)
		(end 181.356 -23.803864)
		(width 0.0889)
		(layer "In9.Cu")
		(net "SMB_HOST_LV_CLK")
	)
	(segment
		(start 181.356 -23.803864)
		(end 181.356 -26.1874)
		(width 0.0889)
		(layer "In9.Cu")
		(net "SMB_HOST_LV_CLK")
	)
	(segment
		(start 197.612 -7.951978)
		(end 197.612 -13.174218)
		(width 0.0889)
		(layer "In9.Cu")
		(net "SMB_HOST_LV_CLK")
	)
	(segment
		(start 177.5714 -29.976826)
		(end 177.53838 -30.009846)
		(width 0.0889)
		(layer "In9.Cu")
		(net "SMB_HOST_LV_CLK")
	)
	(segment
		(start 85.637116 -24.2062)
		(end 85.97646 -24.2062)
		(width 0.1397)
		(layer "F.Cu")
		(net "CPU_GBE_TX_DN0")
	)
	(segment
		(start 86.39556 -24.6253)
		(end 88.12276 -24.6253)
		(width 0.1397)
		(layer "F.Cu")
		(net "CPU_GBE_TX_DN0")
	)
	(segment
		(start 85.97646 -24.2062)
		(end 86.39556 -24.6253)
		(width 0.1397)
		(layer "F.Cu")
		(net "CPU_GBE_TX_DN0")
	)
	(segment
		(start 88.735408 -25.237948)
		(end 88.735408 -26.558494)
		(width 0.1397)
		(layer "F.Cu")
		(net "CPU_GBE_TX_DN0")
	)
	(segment
		(start 85.5345 -24.308816)
		(end 85.637116 -24.2062)
		(width 0.1397)
		(layer "F.Cu")
		(net "CPU_GBE_TX_DN0")
	)
	(segment
		(start 88.12276 -24.6253)
		(end 88.735408 -25.237948)
		(width 0.1397)
		(layer "F.Cu")
		(net "CPU_GBE_TX_DN0")
	)
	(segment
		(start 49.4538 -13.1572)
		(end 49.4538 -13.8176)
		(width 0.1397)
		(layer "F.Cu")
		(net "CPU_GBE_TX_DN0")
	)
	(via
		(at 85.5345 -24.308816)
		(size 0.4318)
		(drill 0.2032)
		(layers "F.Cu" "B.Cu")
		(net "CPU_GBE_TX_DN0")
	)
	(via
		(at 49.4538 -13.8176)
		(size 0.508)
		(drill 0.254)
		(layers "F.Cu" "B.Cu")
		(net "CPU_GBE_TX_DN0")
	)
	(segment
		(start 57.8993 -13.7033)
		(end 55.0164 -16.5862)
		(width 0.1143)
		(layer "In7.Cu")
		(net "CPU_GBE_TX_DN0")
	)
	(segment
		(start 85.5345 -24.308816)
		(end 85.406484 -24.1808)
		(width 0.1143)
		(layer "In7.Cu")
		(net "CPU_GBE_TX_DN0")
	)
	(segment
		(start 81.587594 -20.7137)
		(end 80.580484 -20.7137)
		(width 0.1143)
		(layer "In7.Cu")
		(net "CPU_GBE_TX_DN0")
	)
	(segment
		(start 74.783696 -15.011908)
		(end 73.475088 -13.7033)
		(width 0.1143)
		(layer "In7.Cu")
		(net "CPU_GBE_TX_DN0")
	)
	(segment
		(start 51.780694 -16.5862)
		(end 49.6824 -14.487906)
		(width 0.1143)
		(layer "In7.Cu")
		(net "CPU_GBE_TX_DN0")
	)
	(segment
		(start 49.6824 -14.0462)
		(end 49.4538 -13.8176)
		(width 0.1143)
		(layer "In7.Cu")
		(net "CPU_GBE_TX_DN0")
	)
	(segment
		(start 85.406484 -24.1808)
		(end 85.042502 -24.1808)
		(width 0.1143)
		(layer "In7.Cu")
		(net "CPU_GBE_TX_DN0")
	)
	(segment
		(start 82.93735 -22.063456)
		(end 81.587594 -20.7137)
		(width 0.1143)
		(layer "In7.Cu")
		(net "CPU_GBE_TX_DN0")
	)
	(segment
		(start 49.6824 -14.487906)
		(end 49.6824 -14.0462)
		(width 0.1143)
		(layer "In7.Cu")
		(net "CPU_GBE_TX_DN0")
	)
	(segment
		(start 76.863448 -17.996154)
		(end 74.783696 -15.916402)
		(width 0.1143)
		(layer "In7.Cu")
		(net "CPU_GBE_TX_DN0")
	)
	(segment
		(start 84.070952 -23.20925)
		(end 83.680046 -23.20925)
		(width 0.1143)
		(layer "In7.Cu")
		(net "CPU_GBE_TX_DN0")
	)
	(segment
		(start 73.475088 -13.7033)
		(end 57.8993 -13.7033)
		(width 0.1143)
		(layer "In7.Cu")
		(net "CPU_GBE_TX_DN0")
	)
	(segment
		(start 85.042502 -24.1808)
		(end 84.070952 -23.20925)
		(width 0.1143)
		(layer "In7.Cu")
		(net "CPU_GBE_TX_DN0")
	)
	(segment
		(start 74.783696 -15.916402)
		(end 74.783696 -15.011908)
		(width 0.1143)
		(layer "In7.Cu")
		(net "CPU_GBE_TX_DN0")
	)
	(segment
		(start 83.680046 -23.20925)
		(end 82.93735 -22.466554)
		(width 0.1143)
		(layer "In7.Cu")
		(net "CPU_GBE_TX_DN0")
	)
	(segment
		(start 80.580484 -20.7137)
		(end 77.862938 -17.996154)
		(width 0.1143)
		(layer "In7.Cu")
		(net "CPU_GBE_TX_DN0")
	)
	(segment
		(start 82.93735 -22.466554)
		(end 82.93735 -22.063456)
		(width 0.1143)
		(layer "In7.Cu")
		(net "CPU_GBE_TX_DN0")
	)
	(segment
		(start 77.862938 -17.996154)
		(end 76.863448 -17.996154)
		(width 0.1143)
		(layer "In7.Cu")
		(net "CPU_GBE_TX_DN0")
	)
	(segment
		(start 55.0164 -16.5862)
		(end 51.780694 -16.5862)
		(width 0.1143)
		(layer "In7.Cu")
		(net "CPU_GBE_TX_DN0")
	)
	(segment
		(start 115.772946 -17.21739)
		(end 115.772946 -23.131526)
		(width 0.1143)
		(layer "F.Cu")
		(net "SMB_PECI_LV_DATA")
	)
	(segment
		(start 88.066372 -19.129756)
		(end 90.317828 -16.8783)
		(width 0.1143)
		(layer "F.Cu")
		(net "SMB_PECI_LV_DATA")
	)
	(segment
		(start 128.059434 -34.805366)
		(end 128.5748 -34.29)
		(width 0.1143)
		(layer "F.Cu")
		(net "SMB_PECI_LV_DATA")
	)
	(segment
		(start 129.573528 -34.425128)
		(end 129.54 -34.3916)
		(width 0.1143)
		(layer "F.Cu")
		(net "SMB_PECI_LV_DATA")
	)
	(segment
		(start 74.62901 -17.839182)
		(end 74.62901 -17.839436)
		(width 0.1143)
		(layer "F.Cu")
		(net "SMB_PECI_LV_DATA")
	)
	(segment
		(start 64.5795 -19.13255)
		(end 67.58305 -19.13255)
		(width 0.1143)
		(layer "F.Cu")
		(net "SMB_PECI_LV_DATA")
	)
	(segment
		(start 132.12572 -34.78911)
		(end 131.377944 -34.78911)
		(width 0.1143)
		(layer "F.Cu")
		(net "SMB_PECI_LV_DATA")
	)
	(segment
		(start 129.464308 -34.3916)
		(end 129.54 -34.3916)
		(width 0.1143)
		(layer "F.Cu")
		(net "SMB_PECI_LV_DATA")
	)
	(segment
		(start 74.918824 -18.12925)
		(end 78.514956 -18.12925)
		(width 0.1143)
		(layer "F.Cu")
		(net "SMB_PECI_LV_DATA")
	)
	(segment
		(start 116.063014 -23.42134)
		(end 127.44704 -34.805366)
		(width 0.1143)
		(layer "F.Cu")
		(net "SMB_PECI_LV_DATA")
	)
	(segment
		(start 74.144378 -17.35455)
		(end 74.62901 -17.839182)
		(width 0.1143)
		(layer "F.Cu")
		(net "SMB_PECI_LV_DATA")
	)
	(segment
		(start 78.514956 -18.12925)
		(end 79.774796 -19.38909)
		(width 0.1143)
		(layer "F.Cu")
		(net "SMB_PECI_LV_DATA")
	)
	(segment
		(start 132.1308 -34.79419)
		(end 132.12572 -34.78911)
		(width 0.1143)
		(layer "F.Cu")
		(net "SMB_PECI_LV_DATA")
	)
	(segment
		(start 112.893856 -14.3383)
		(end 115.772946 -17.21739)
		(width 0.1143)
		(layer "F.Cu")
		(net "SMB_PECI_LV_DATA")
	)
	(segment
		(start 74.62901 -17.839436)
		(end 74.918824 -18.12925)
		(width 0.1143)
		(layer "F.Cu")
		(net "SMB_PECI_LV_DATA")
	)
	(segment
		(start 131.377944 -34.78911)
		(end 131.013962 -34.425128)
		(width 0.1143)
		(layer "F.Cu")
		(net "SMB_PECI_LV_DATA")
	)
	(segment
		(start 131.013962 -34.425128)
		(end 129.573528 -34.425128)
		(width 0.1143)
		(layer "F.Cu")
		(net "SMB_PECI_LV_DATA")
	)
	(segment
		(start 70.2818 -47.2694)
		(end 70.2818 -48.05426)
		(width 0.1143)
		(layer "F.Cu")
		(net "SMB_PECI_LV_DATA")
	)
	(segment
		(start 67.58305 -19.13255)
		(end 69.36105 -17.35455)
		(width 0.1143)
		(layer "F.Cu")
		(net "SMB_PECI_LV_DATA")
	)
	(segment
		(start 116.06276 -23.42134)
		(end 116.063014 -23.42134)
		(width 0.1143)
		(layer "F.Cu")
		(net "SMB_PECI_LV_DATA")
	)
	(segment
		(start 103.14178 -14.3383)
		(end 112.893856 -14.3383)
		(width 0.1143)
		(layer "F.Cu")
		(net "SMB_PECI_LV_DATA")
	)
	(segment
		(start 64.4398 -19.27225)
		(end 64.5795 -19.13255)
		(width 0.1143)
		(layer "F.Cu")
		(net "SMB_PECI_LV_DATA")
	)
	(segment
		(start 69.36105 -17.35455)
		(end 74.144378 -17.35455)
		(width 0.1143)
		(layer "F.Cu")
		(net "SMB_PECI_LV_DATA")
	)
	(segment
		(start 100.60178 -16.8783)
		(end 103.14178 -14.3383)
		(width 0.1143)
		(layer "F.Cu")
		(net "SMB_PECI_LV_DATA")
	)
	(segment
		(start 85.712046 -19.38909)
		(end 85.97138 -19.129756)
		(width 0.1143)
		(layer "F.Cu")
		(net "SMB_PECI_LV_DATA")
	)
	(segment
		(start 79.774796 -19.38909)
		(end 85.712046 -19.38909)
		(width 0.1143)
		(layer "F.Cu")
		(net "SMB_PECI_LV_DATA")
	)
	(segment
		(start 128.5748 -34.29)
		(end 129.362708 -34.29)
		(width 0.1143)
		(layer "F.Cu")
		(net "SMB_PECI_LV_DATA")
	)
	(segment
		(start 90.317828 -16.8783)
		(end 100.60178 -16.8783)
		(width 0.1143)
		(layer "F.Cu")
		(net "SMB_PECI_LV_DATA")
	)
	(segment
		(start 85.97138 -19.129756)
		(end 88.066372 -19.129756)
		(width 0.1143)
		(layer "F.Cu")
		(net "SMB_PECI_LV_DATA")
	)
	(segment
		(start 129.362708 -34.29)
		(end 129.464308 -34.3916)
		(width 0.1143)
		(layer "F.Cu")
		(net "SMB_PECI_LV_DATA")
	)
	(segment
		(start 127.44704 -34.805366)
		(end 128.059434 -34.805366)
		(width 0.1143)
		(layer "F.Cu")
		(net "SMB_PECI_LV_DATA")
	)
	(segment
		(start 115.772946 -23.131526)
		(end 116.06276 -23.42134)
		(width 0.1143)
		(layer "F.Cu")
		(net "SMB_PECI_LV_DATA")
	)
	(segment
		(start 70.2818 -48.05426)
		(end 70.33514 -48.1076)
		(width 0.1143)
		(layer "F.Cu")
		(net "SMB_PECI_LV_DATA")
	)
	(via
		(at 70.33514 -48.1076)
		(size 0.508)
		(drill 0.254)
		(layers "F.Cu" "B.Cu")
		(net "SMB_PECI_LV_DATA")
	)
	(via
		(at 64.4398 -19.27225)
		(size 0.508)
		(drill 0.254)
		(layers "F.Cu" "B.Cu")
		(net "SMB_PECI_LV_DATA")
	)
	(via
		(at 129.54 -34.3916)
		(size 0.7112)
		(drill 0.3556)
		(layers "F.Cu" "B.Cu")
		(net "SMB_PECI_LV_DATA")
	)
	(segment
		(start 70.33514 -48.1076)
		(end 70.33514 -47.928022)
		(width 0.0889)
		(layer "In9.Cu")
		(net "SMB_PECI_LV_DATA")
	)
	(segment
		(start 65.903348 -42.919396)
		(end 64.111632 -41.12768)
		(width 0.0889)
		(layer "In9.Cu")
		(net "SMB_PECI_LV_DATA")
	)
	(segment
		(start 65.903348 -44.059348)
		(end 65.903348 -42.919396)
		(width 0.0889)
		(layer "In9.Cu")
		(net "SMB_PECI_LV_DATA")
	)
	(segment
		(start 68.6943 -46.8503)
		(end 65.903348 -44.059348)
		(width 0.0889)
		(layer "In9.Cu")
		(net "SMB_PECI_LV_DATA")
	)
	(segment
		(start 69.257418 -46.8503)
		(end 68.6943 -46.8503)
		(width 0.0889)
		(layer "In9.Cu")
		(net "SMB_PECI_LV_DATA")
	)
	(segment
		(start 64.111632 -19.600418)
		(end 64.4398 -19.27225)
		(width 0.0889)
		(layer "In9.Cu")
		(net "SMB_PECI_LV_DATA")
	)
	(segment
		(start 64.111632 -41.12768)
		(end 64.111632 -19.600418)
		(width 0.0889)
		(layer "In9.Cu")
		(net "SMB_PECI_LV_DATA")
	)
	(segment
		(start 70.33514 -47.928022)
		(end 69.257418 -46.8503)
		(width 0.0889)
		(layer "In9.Cu")
		(net "SMB_PECI_LV_DATA")
	)
	(segment
		(start 184.8612 -45.212)
		(end 184.8612 -44.8564)
		(width 0.1143)
		(layer "F.Cu")
		(net "SMB_HOST_LV_DATA")
	)
	(segment
		(start 184.8612 -44.8564)
		(end 184.21985 -44.21505)
		(width 0.1143)
		(layer "F.Cu")
		(net "SMB_HOST_LV_DATA")
	)
	(segment
		(start 82.3341 -71.2597)
		(end 82.5754 -71.501)
		(width 0.1143)
		(layer "F.Cu")
		(net "SMB_HOST_LV_DATA")
	)
	(segment
		(start 66.167 -67.914774)
		(end 68.235576 -69.98335)
		(width 0.1143)
		(layer "F.Cu")
		(net "SMB_HOST_LV_DATA")
	)
	(segment
		(start 120.53189 -68.92671)
		(end 121.666 -67.7926)
		(width 0.1143)
		(layer "F.Cu")
		(net "SMB_HOST_LV_DATA")
	)
	(segment
		(start 8.4201 -46.123606)
		(end 7.236206 -47.3075)
		(width 0.1143)
		(layer "F.Cu")
		(net "SMB_HOST_LV_DATA")
	)
	(segment
		(start 182.49265 -44.21505)
		(end 180.309266 -42.031666)
		(width 0.1143)
		(layer "F.Cu")
		(net "SMB_HOST_LV_DATA")
	)
	(segment
		(start 196.723 -8.383778)
		(end 196.723 -7.951978)
		(width 0.1143)
		(layer "F.Cu")
		(net "SMB_HOST_LV_DATA")
	)
	(segment
		(start 80.713326 -71.991474)
		(end 81.4451 -71.2597)
		(width 0.1143)
		(layer "F.Cu")
		(net "SMB_HOST_LV_DATA")
	)
	(segment
		(start 184.404 -45.6692)
		(end 184.8612 -45.212)
		(width 0.1143)
		(layer "F.Cu")
		(net "SMB_HOST_LV_DATA")
	)
	(segment
		(start 68.235576 -69.98335)
		(end 73.541382 -69.98335)
		(width 0.1143)
		(layer "F.Cu")
		(net "SMB_HOST_LV_DATA")
	)
	(segment
		(start 121.666 -67.7926)
		(end 121.666 -67.5386)
		(width 0.1143)
		(layer "F.Cu")
		(net "SMB_HOST_LV_DATA")
	)
	(segment
		(start 180.309266 -42.031666)
		(end 178.342036 -40.064436)
		(width 0.1143)
		(layer "F.Cu")
		(net "SMB_HOST_LV_DATA")
	)
	(segment
		(start 81.4451 -71.2597)
		(end 82.3341 -71.2597)
		(width 0.1143)
		(layer "F.Cu")
		(net "SMB_HOST_LV_DATA")
	)
	(segment
		(start 74.500232 -69.0245)
		(end 76.710032 -69.0245)
		(width 0.1143)
		(layer "F.Cu")
		(net "SMB_HOST_LV_DATA")
	)
	(segment
		(start 66.167 -67.21602)
		(end 66.167 -67.914774)
		(width 0.1143)
		(layer "F.Cu")
		(net "SMB_HOST_LV_DATA")
	)
	(segment
		(start 178.342036 -29.883608)
		(end 177.607214 -29.148786)
		(width 0.1143)
		(layer "F.Cu")
		(net "SMB_HOST_LV_DATA")
	)
	(segment
		(start 197.993 -8.840978)
		(end 197.1802 -8.840978)
		(width 0.1143)
		(layer "F.Cu")
		(net "SMB_HOST_LV_DATA")
	)
	(segment
		(start 76.710032 -69.0245)
		(end 79.677006 -71.991474)
		(width 0.1143)
		(layer "F.Cu")
		(net "SMB_HOST_LV_DATA")
	)
	(segment
		(start 117.475 -67.056)
		(end 119.34571 -68.92671)
		(width 0.1143)
		(layer "F.Cu")
		(net "SMB_HOST_LV_DATA")
	)
	(segment
		(start 73.541382 -69.98335)
		(end 74.500232 -69.0245)
		(width 0.1143)
		(layer "F.Cu")
		(net "SMB_HOST_LV_DATA")
	)
	(segment
		(start 4.26085 -46.985936)
		(end 4.26085 -45.31995)
		(width 0.1143)
		(layer "F.Cu")
		(net "SMB_HOST_LV_DATA")
	)
	(segment
		(start 64.3382 -47.371)
		(end 64.3382 -48.217836)
		(width 0.1143)
		(layer "F.Cu")
		(net "SMB_HOST_LV_DATA")
	)
	(segment
		(start 119.34571 -68.92671)
		(end 120.53189 -68.92671)
		(width 0.1143)
		(layer "F.Cu")
		(net "SMB_HOST_LV_DATA")
	)
	(segment
		(start 197.1802 -8.840978)
		(end 196.723 -8.383778)
		(width 0.1143)
		(layer "F.Cu")
		(net "SMB_HOST_LV_DATA")
	)
	(segment
		(start 178.342036 -40.064436)
		(end 178.342036 -29.883608)
		(width 0.1143)
		(layer "F.Cu")
		(net "SMB_HOST_LV_DATA")
	)
	(segment
		(start 117.475 -64.8208)
		(end 117.475 -67.056)
		(width 0.1143)
		(layer "F.Cu")
		(net "SMB_HOST_LV_DATA")
	)
	(segment
		(start 4.26085 -45.31995)
		(end 4.699 -44.8818)
		(width 0.1143)
		(layer "F.Cu")
		(net "SMB_HOST_LV_DATA")
	)
	(segment
		(start 184.21985 -44.21505)
		(end 182.49265 -44.21505)
		(width 0.1143)
		(layer "F.Cu")
		(net "SMB_HOST_LV_DATA")
	)
	(segment
		(start 79.677006 -71.991474)
		(end 80.713326 -71.991474)
		(width 0.1143)
		(layer "F.Cu")
		(net "SMB_HOST_LV_DATA")
	)
	(segment
		(start 8.4201 -46.101)
		(end 8.4201 -46.123606)
		(width 0.1143)
		(layer "F.Cu")
		(net "SMB_HOST_LV_DATA")
	)
	(segment
		(start 7.236206 -47.3075)
		(end 4.582414 -47.3075)
		(width 0.1143)
		(layer "F.Cu")
		(net "SMB_HOST_LV_DATA")
	)
	(segment
		(start 4.582414 -47.3075)
		(end 4.26085 -46.985936)
		(width 0.1143)
		(layer "F.Cu")
		(net "SMB_HOST_LV_DATA")
	)
	(via
		(at 66.167 -67.21602)
		(size 0.508)
		(drill 0.254)
		(layers "F.Cu" "B.Cu")
		(net "SMB_HOST_LV_DATA")
	)
	(via
		(at 184.8612 -44.8564)
		(size 0.508)
		(drill 0.254)
		(layers "F.Cu" "B.Cu")
		(net "SMB_HOST_LV_DATA")
	)
	(via
		(at 82.5754 -71.501)
		(size 0.508)
		(drill 0.254)
		(layers "F.Cu" "B.Cu")
		(net "SMB_HOST_LV_DATA")
	)
	(via
		(at 38.1 -53.3654)
		(size 0.508)
		(drill 0.254)
		(layers "F.Cu" "B.Cu")
		(net "SMB_HOST_LV_DATA")
	)
	(via
		(at 8.4201 -46.101)
		(size 0.508)
		(drill 0.254)
		(layers "F.Cu" "B.Cu")
		(net "SMB_HOST_LV_DATA")
	)
	(via
		(at 177.607214 -29.148786)
		(size 0.508)
		(drill 0.254)
		(layers "F.Cu" "B.Cu")
		(net "SMB_HOST_LV_DATA")
	)
	(via
		(at 116.9416 -69.9008)
		(size 0.508)
		(drill 0.254)
		(layers "F.Cu" "B.Cu")
		(net "SMB_HOST_LV_DATA")
	)
	(via
		(at 64.3382 -48.217836)
		(size 0.508)
		(drill 0.254)
		(layers "F.Cu" "B.Cu")
		(net "SMB_HOST_LV_DATA")
	)
	(via
		(at 121.666 -67.5386)
		(size 0.508)
		(drill 0.254)
		(layers "F.Cu" "B.Cu")
		(net "SMB_HOST_LV_DATA")
	)
	(via
		(at 196.723 -7.951978)
		(size 0.508)
		(drill 0.254)
		(layers "F.Cu" "B.Cu")
		(net "SMB_HOST_LV_DATA")
	)
	(via
		(at 180.309266 -42.031666)
		(size 0.7112)
		(drill 0.3556)
		(layers "F.Cu" "B.Cu")
		(net "SMB_HOST_LV_DATA")
	)
	(segment
		(start 116.9416 -70.684136)
		(end 116.130832 -71.494904)
		(width 0.1143)
		(layer "B.Cu")
		(net "SMB_HOST_LV_DATA")
	)
	(segment
		(start 119.888 -65.7606)
		(end 121.666 -67.5386)
		(width 0.1143)
		(layer "B.Cu")
		(net "SMB_HOST_LV_DATA")
	)
	(segment
		(start 121.666 -67.5386)
		(end 121.666 -68.326)
		(width 0.1143)
		(layer "B.Cu")
		(net "SMB_HOST_LV_DATA")
	)
	(segment
		(start 63.49365 -52.705)
		(end 62.47765 -53.721)
		(width 0.1143)
		(layer "B.Cu")
		(net "SMB_HOST_LV_DATA")
	)
	(segment
		(start 65.19545 -50.20945)
		(end 65.19545 -52.07)
		(width 0.1143)
		(layer "B.Cu")
		(net "SMB_HOST_LV_DATA")
	)
	(segment
		(start 82.92465 -70.963282)
		(end 82.92465 -70.084442)
		(width 0.1143)
		(layer "B.Cu")
		(net "SMB_HOST_LV_DATA")
	)
	(segment
		(start 38.5572 -49.6062)
		(end 38.23335 -49.93005)
		(width 0.1143)
		(layer "B.Cu")
		(net "SMB_HOST_LV_DATA")
	)
	(segment
		(start 64.56045 -52.705)
		(end 63.49365 -52.705)
		(width 0.1143)
		(layer "B.Cu")
		(net "SMB_HOST_LV_DATA")
	)
	(segment
		(start 65.405 -66.45402)
		(end 66.167 -67.21602)
		(width 0.1143)
		(layer "B.Cu")
		(net "SMB_HOST_LV_DATA")
	)
	(segment
		(start 119.888 -65.5828)
		(end 119.888 -65.7606)
		(width 0.1143)
		(layer "B.Cu")
		(net "SMB_HOST_LV_DATA")
	)
	(segment
		(start 116.9416 -69.9008)
		(end 116.9416 -70.684136)
		(width 0.1143)
		(layer "B.Cu")
		(net "SMB_HOST_LV_DATA")
	)
	(segment
		(start 37.87775 -50.253646)
		(end 37.87775 -51.913282)
		(width 0.1143)
		(layer "B.Cu")
		(net "SMB_HOST_LV_DATA")
	)
	(segment
		(start 38.201346 -49.93005)
		(end 37.87775 -50.253646)
		(width 0.1143)
		(layer "B.Cu")
		(net "SMB_HOST_LV_DATA")
	)
	(segment
		(start 65.405 -57.441338)
		(end 65.405 -66.45402)
		(width 0.1143)
		(layer "B.Cu")
		(net "SMB_HOST_LV_DATA")
	)
	(segment
		(start 82.5754 -71.501)
		(end 82.5754 -71.494904)
		(width 0.1143)
		(layer "B.Cu")
		(net "SMB_HOST_LV_DATA")
	)
	(segment
		(start 62.47765 -54.513988)
		(end 65.405 -57.441338)
		(width 0.1143)
		(layer "B.Cu")
		(net "SMB_HOST_LV_DATA")
	)
	(segment
		(start 74.46645 -59.34075)
		(end 75.1332 -58.674)
		(width 0.1143)
		(layer "B.Cu")
		(net "SMB_HOST_LV_DATA")
	)
	(segment
		(start 197.804024 -8.415528)
		(end 197.18655 -8.415528)
		(width 0.1143)
		(layer "B.Cu")
		(net "SMB_HOST_LV_DATA")
	)
	(segment
		(start 38.38575 -52.421282)
		(end 38.38575 -53.07965)
		(width 0.1143)
		(layer "B.Cu")
		(net "SMB_HOST_LV_DATA")
	)
	(segment
		(start 197.612 -5.1054)
		(end 197.612 -7.113778)
		(width 0.1143)
		(layer "B.Cu")
		(net "SMB_HOST_LV_DATA")
	)
	(segment
		(start 62.47765 -53.721)
		(end 62.47765 -54.513988)
		(width 0.1143)
		(layer "B.Cu")
		(net "SMB_HOST_LV_DATA")
	)
	(segment
		(start 38.23335 -49.93005)
		(end 38.201346 -49.93005)
		(width 0.1143)
		(layer "B.Cu")
		(net "SMB_HOST_LV_DATA")
	)
	(segment
		(start 75.96632 -65.509394)
		(end 75.341988 -65.509394)
		(width 0.1143)
		(layer "B.Cu")
		(net "SMB_HOST_LV_DATA")
	)
	(segment
		(start 78.403958 -65.56375)
		(end 76.020676 -65.56375)
		(width 0.1143)
		(layer "B.Cu")
		(net "SMB_HOST_LV_DATA")
	)
	(segment
		(start 197.18655 -8.415528)
		(end 196.723 -7.951978)
		(width 0.1143)
		(layer "B.Cu")
		(net "SMB_HOST_LV_DATA")
	)
	(segment
		(start 76.020676 -65.56375)
		(end 75.96632 -65.509394)
		(width 0.1143)
		(layer "B.Cu")
		(net "SMB_HOST_LV_DATA")
	)
	(segment
		(start 65.19545 -52.07)
		(end 64.56045 -52.705)
		(width 0.1143)
		(layer "B.Cu")
		(net "SMB_HOST_LV_DATA")
	)
	(segment
		(start 197.612 -7.113778)
		(end 198.07555 -7.577328)
		(width 0.1143)
		(layer "B.Cu")
		(net "SMB_HOST_LV_DATA")
	)
	(segment
		(start 198.07555 -7.577328)
		(end 198.07555 -8.144002)
		(width 0.1143)
		(layer "B.Cu")
		(net "SMB_HOST_LV_DATA")
	)
	(segment
		(start 82.5754 -71.494904)
		(end 82.5754 -71.312532)
		(width 0.1143)
		(layer "B.Cu")
		(net "SMB_HOST_LV_DATA")
	)
	(segment
		(start 82.92465 -70.084442)
		(end 78.403958 -65.56375)
		(width 0.1143)
		(layer "B.Cu")
		(net "SMB_HOST_LV_DATA")
	)
	(segment
		(start 38.38575 -53.07965)
		(end 38.1 -53.3654)
		(width 0.1143)
		(layer "B.Cu")
		(net "SMB_HOST_LV_DATA")
	)
	(segment
		(start 116.130832 -71.494904)
		(end 82.5754 -71.494904)
		(width 0.1143)
		(layer "B.Cu")
		(net "SMB_HOST_LV_DATA")
	)
	(segment
		(start 82.5754 -71.312532)
		(end 82.92465 -70.963282)
		(width 0.1143)
		(layer "B.Cu")
		(net "SMB_HOST_LV_DATA")
	)
	(segment
		(start 64.3382 -48.217836)
		(end 64.3382 -49.3522)
		(width 0.1143)
		(layer "B.Cu")
		(net "SMB_HOST_LV_DATA")
	)
	(segment
		(start 75.341988 -65.509394)
		(end 74.46645 -64.633856)
		(width 0.1143)
		(layer "B.Cu")
		(net "SMB_HOST_LV_DATA")
	)
	(segment
		(start 74.46645 -64.633856)
		(end 74.46645 -59.34075)
		(width 0.1143)
		(layer "B.Cu")
		(net "SMB_HOST_LV_DATA")
	)
	(segment
		(start 64.3382 -49.3522)
		(end 65.19545 -50.20945)
		(width 0.1143)
		(layer "B.Cu")
		(net "SMB_HOST_LV_DATA")
	)
	(segment
		(start 37.87775 -51.913282)
		(end 38.38575 -52.421282)
		(width 0.1143)
		(layer "B.Cu")
		(net "SMB_HOST_LV_DATA")
	)
	(segment
		(start 198.07555 -8.144002)
		(end 197.804024 -8.415528)
		(width 0.1143)
		(layer "B.Cu")
		(net "SMB_HOST_LV_DATA")
	)
	(segment
		(start 8.6741 -46.355)
		(end 8.4201 -46.101)
		(width 0.0889)
		(layer "In2.Cu")
		(net "SMB_HOST_LV_DATA")
	)
	(segment
		(start 121.666 -69.603112)
		(end 121.666 -67.5386)
		(width 0.0889)
		(layer "In2.Cu")
		(net "SMB_HOST_LV_DATA")
	)
	(segment
		(start 37.391848 -54.073552)
		(end 33.513268 -54.073552)
		(width 0.0889)
		(layer "In2.Cu")
		(net "SMB_HOST_LV_DATA")
	)
	(segment
		(start 116.9416 -69.9008)
		(end 117.983 -70.9422)
		(width 0.0889)
		(layer "In2.Cu")
		(net "SMB_HOST_LV_DATA")
	)
	(segment
		(start 117.983 -70.9422)
		(end 120.326912 -70.9422)
		(width 0.0889)
		(layer "In2.Cu")
		(net "SMB_HOST_LV_DATA")
	)
	(segment
		(start 29.097224 -51.174142)
		(end 24.278082 -46.355)
		(width 0.0889)
		(layer "In2.Cu")
		(net "SMB_HOST_LV_DATA")
	)
	(segment
		(start 120.326912 -70.9422)
		(end 121.666 -69.603112)
		(width 0.0889)
		(layer "In2.Cu")
		(net "SMB_HOST_LV_DATA")
	)
	(segment
		(start 24.278082 -46.355)
		(end 8.6741 -46.355)
		(width 0.0889)
		(layer "In2.Cu")
		(net "SMB_HOST_LV_DATA")
	)
	(segment
		(start 30.613858 -51.174142)
		(end 29.097224 -51.174142)
		(width 0.0889)
		(layer "In2.Cu")
		(net "SMB_HOST_LV_DATA")
	)
	(segment
		(start 38.1 -53.3654)
		(end 37.391848 -54.073552)
		(width 0.0889)
		(layer "In2.Cu")
		(net "SMB_HOST_LV_DATA")
	)
	(segment
		(start 33.513268 -54.073552)
		(end 30.613858 -51.174142)
		(width 0.0889)
		(layer "In2.Cu")
		(net "SMB_HOST_LV_DATA")
	)
	(segment
		(start 61.3156 -49.1744)
		(end 61.976 -48.514)
		(width 0.0889)
		(layer "In4.Cu")
		(net "SMB_HOST_LV_DATA")
	)
	(segment
		(start 58.179716 -49.7967)
		(end 59.884056 -49.7967)
		(width 0.0889)
		(layer "In4.Cu")
		(net "SMB_HOST_LV_DATA")
	)
	(segment
		(start 60.506356 -49.1744)
		(end 61.3156 -49.1744)
		(width 0.0889)
		(layer "In4.Cu")
		(net "SMB_HOST_LV_DATA")
	)
	(segment
		(start 59.884056 -49.7967)
		(end 60.506356 -49.1744)
		(width 0.0889)
		(layer "In4.Cu")
		(net "SMB_HOST_LV_DATA")
	)
	(segment
		(start 39.202868 -53.79085)
		(end 39.710868 -53.28285)
		(width 0.0889)
		(layer "In4.Cu")
		(net "SMB_HOST_LV_DATA")
	)
	(segment
		(start 38.1 -53.3654)
		(end 38.52545 -53.79085)
		(width 0.0889)
		(layer "In4.Cu")
		(net "SMB_HOST_LV_DATA")
	)
	(segment
		(start 41.21785 -53.28285)
		(end 41.59885 -53.66385)
		(width 0.0889)
		(layer "In4.Cu")
		(net "SMB_HOST_LV_DATA")
	)
	(segment
		(start 47.684944 -53.66385)
		(end 47.697644 -53.65115)
		(width 0.0889)
		(layer "In4.Cu")
		(net "SMB_HOST_LV_DATA")
	)
	(segment
		(start 61.976 -48.514)
		(end 64.042036 -48.514)
		(width 0.0889)
		(layer "In4.Cu")
		(net "SMB_HOST_LV_DATA")
	)
	(segment
		(start 47.697644 -53.65115)
		(end 54.325266 -53.65115)
		(width 0.0889)
		(layer "In4.Cu")
		(net "SMB_HOST_LV_DATA")
	)
	(segment
		(start 54.325266 -53.65115)
		(end 58.179716 -49.7967)
		(width 0.0889)
		(layer "In4.Cu")
		(net "SMB_HOST_LV_DATA")
	)
	(segment
		(start 64.042036 -48.514)
		(end 64.3382 -48.217836)
		(width 0.0889)
		(layer "In4.Cu")
		(net "SMB_HOST_LV_DATA")
	)
	(segment
		(start 41.59885 -53.66385)
		(end 47.684944 -53.66385)
		(width 0.0889)
		(layer "In4.Cu")
		(net "SMB_HOST_LV_DATA")
	)
	(segment
		(start 39.710868 -53.28285)
		(end 41.21785 -53.28285)
		(width 0.0889)
		(layer "In4.Cu")
		(net "SMB_HOST_LV_DATA")
	)
	(segment
		(start 38.52545 -53.79085)
		(end 39.202868 -53.79085)
		(width 0.0889)
		(layer "In4.Cu")
		(net "SMB_HOST_LV_DATA")
	)
	(segment
		(start 187.1853 -56.602884)
		(end 187.1853 -53.153818)
		(width 0.0889)
		(layer "In7.Cu")
		(net "SMB_HOST_LV_DATA")
	)
	(segment
		(start 116.9416 -69.9008)
		(end 118.840504 -71.799704)
		(width 0.0889)
		(layer "In7.Cu")
		(net "SMB_HOST_LV_DATA")
	)
	(segment
		(start 187.1853 -53.153818)
		(end 190.04915 -50.289968)
		(width 0.0889)
		(layer "In7.Cu")
		(net "SMB_HOST_LV_DATA")
	)
	(segment
		(start 186.227974 -46.276006)
		(end 184.8612 -44.909232)
		(width 0.0889)
		(layer "In7.Cu")
		(net "SMB_HOST_LV_DATA")
	)
	(segment
		(start 190.04915 -50.289968)
		(end 190.04915 -48.462438)
		(width 0.0889)
		(layer "In7.Cu")
		(net "SMB_HOST_LV_DATA")
	)
	(segment
		(start 190.04915 -48.462438)
		(end 187.862718 -46.276006)
		(width 0.0889)
		(layer "In7.Cu")
		(net "SMB_HOST_LV_DATA")
	)
	(segment
		(start 187.862718 -46.276006)
		(end 186.227974 -46.276006)
		(width 0.0889)
		(layer "In7.Cu")
		(net "SMB_HOST_LV_DATA")
	)
	(segment
		(start 193.519298 -62.936882)
		(end 187.1853 -56.602884)
		(width 0.0889)
		(layer "In7.Cu")
		(net "SMB_HOST_LV_DATA")
	)
	(segment
		(start 189.891162 -71.799704)
		(end 193.519298 -68.171568)
		(width 0.0889)
		(layer "In7.Cu")
		(net "SMB_HOST_LV_DATA")
	)
	(segment
		(start 118.840504 -71.799704)
		(end 189.891162 -71.799704)
		(width 0.0889)
		(layer "In7.Cu")
		(net "SMB_HOST_LV_DATA")
	)
	(segment
		(start 184.8612 -44.909232)
		(end 184.8612 -44.8564)
		(width 0.0889)
		(layer "In7.Cu")
		(net "SMB_HOST_LV_DATA")
	)
	(segment
		(start 193.519298 -68.171568)
		(end 193.519298 -62.936882)
		(width 0.0889)
		(layer "In7.Cu")
		(net "SMB_HOST_LV_DATA")
	)
	(segment
		(start 188.595 -21.4122)
		(end 183.082946 -21.4122)
		(width 0.0889)
		(layer "In9.Cu")
		(net "SMB_HOST_LV_DATA")
	)
	(segment
		(start 196.723 -13.2842)
		(end 188.595 -21.4122)
		(width 0.0889)
		(layer "In9.Cu")
		(net "SMB_HOST_LV_DATA")
	)
	(segment
		(start 180.8861 -23.609046)
		(end 180.8861 -25.8699)
		(width 0.0889)
		(layer "In9.Cu")
		(net "SMB_HOST_LV_DATA")
	)
	(segment
		(start 183.082946 -21.4122)
		(end 180.8861 -23.609046)
		(width 0.0889)
		(layer "In9.Cu")
		(net "SMB_HOST_LV_DATA")
	)
	(segment
		(start 196.723 -7.951978)
		(end 196.723 -13.2842)
		(width 0.0889)
		(layer "In9.Cu")
		(net "SMB_HOST_LV_DATA")
	)
	(segment
		(start 180.8861 -25.8699)
		(end 177.607214 -29.148786)
		(width 0.0889)
		(layer "In9.Cu")
		(net "SMB_HOST_LV_DATA")
	)
	(segment
		(start 62.484 -48.2092)
		(end 62.484 -47.2694)
		(width 0.1143)
		(layer "F.Cu")
		(net "SMB_HOST_LV_R_CLK")
	)
	(segment
		(start 62.484 -47.218854)
		(end 62.60211 -47.100744)
		(width 0.1143)
		(layer "F.Cu")
		(net "SMB_HOST_LV_R_CLK")
	)
	(segment
		(start 62.484 -47.2694)
		(end 62.484 -47.218854)
		(width 0.1143)
		(layer "F.Cu")
		(net "SMB_HOST_LV_R_CLK")
	)
	(segment
		(start 62.60211 -47.100744)
		(end 62.60211 -45.8216)
		(width 0.1143)
		(layer "F.Cu")
		(net "SMB_HOST_LV_R_CLK")
	)
	(via
		(at 62.484 -47.2694)
		(size 0.7112)
		(drill 0.3556)
		(layers "F.Cu" "B.Cu")
		(net "SMB_HOST_LV_R_CLK")
	)
	(segment
		(start 151.2189 -49.0347)
		(end 151.2189 -47.93615)
		(width 0.1143)
		(layer "F.Cu")
		(net "C_DATA0")
	)
	(segment
		(start 168.8846 -52.832)
		(end 169.6466 -52.832)
		(width 0.1143)
		(layer "F.Cu")
		(net "C_DATA0")
	)
	(segment
		(start 149.9616 -49.21631)
		(end 151.03729 -49.21631)
		(width 0.1143)
		(layer "F.Cu")
		(net "C_DATA0")
	)
	(segment
		(start 169.6466 -52.832)
		(end 169.672 -52.8574)
		(width 0.1143)
		(layer "F.Cu")
		(net "C_DATA0")
	)
	(segment
		(start 151.2189 -47.93615)
		(end 150.9649 -47.68215)
		(width 0.1143)
		(layer "F.Cu")
		(net "C_DATA0")
	)
	(segment
		(start 169.857928 -51.95697)
		(end 169.857928 -52.671472)
		(width 0.1143)
		(layer "F.Cu")
		(net "C_DATA0")
	)
	(segment
		(start 151.03729 -49.21631)
		(end 151.2189 -49.0347)
		(width 0.1143)
		(layer "F.Cu")
		(net "C_DATA0")
	)
	(segment
		(start 169.857928 -52.671472)
		(end 169.672 -52.8574)
		(width 0.1143)
		(layer "F.Cu")
		(net "C_DATA0")
	)
	(via
		(at 150.9649 -47.68215)
		(size 0.508)
		(drill 0.254)
		(layers "F.Cu" "B.Cu")
		(net "C_DATA0")
	)
	(via
		(at 170.9674 -45.58157)
		(size 0.508)
		(drill 0.254)
		(layers "F.Cu" "B.Cu")
		(net "C_DATA0")
	)
	(via
		(at 169.857928 -51.95697)
		(size 0.508)
		(drill 0.254)
		(layers "F.Cu" "B.Cu")
		(net "C_DATA0")
	)
	(segment
		(start 163.261294 -46.669452)
		(end 170.277028 -45.89399)
		(width 0.1143)
		(layer "B.Cu")
		(net "C_DATA0")
	)
	(segment
		(start 150.9649 -47.68215)
		(end 153.068782 -47.532036)
		(width 0.1143)
		(layer "B.Cu")
		(net "C_DATA0")
	)
	(segment
		(start 161.883852 -46.669452)
		(end 163.261294 -46.669452)
		(width 0.1143)
		(layer "B.Cu")
		(net "C_DATA0")
	)
	(segment
		(start 170.277028 -45.89399)
		(end 170.70197 -45.847)
		(width 0.1143)
		(layer "B.Cu")
		(net "C_DATA0")
	)
	(segment
		(start 154.849322 -46.677834)
		(end 158.623 -46.482)
		(width 0.1143)
		(layer "B.Cu")
		(net "C_DATA0")
	)
	(segment
		(start 153.068782 -47.532036)
		(end 153.767282 -46.833536)
		(width 0.1143)
		(layer "B.Cu")
		(net "C_DATA0")
	)
	(segment
		(start 153.767282 -46.833536)
		(end 154.849322 -46.677834)
		(width 0.1143)
		(layer "B.Cu")
		(net "C_DATA0")
	)
	(segment
		(start 158.623 -46.482)
		(end 161.883852 -46.669452)
		(width 0.1143)
		(layer "B.Cu")
		(net "C_DATA0")
	)
	(segment
		(start 170.70197 -45.847)
		(end 170.9674 -45.58157)
		(width 0.1143)
		(layer "B.Cu")
		(net "C_DATA0")
	)
	(segment
		(start 170.222418 -48.586898)
		(end 169.857928 -51.95697)
		(width 0.0889)
		(layer "In9.Cu")
		(net "C_DATA0")
	)
	(segment
		(start 170.9674 -45.58157)
		(end 170.312334 -48.091598)
		(width 0.0889)
		(layer "In9.Cu")
		(net "C_DATA0")
	)
	(segment
		(start 170.312334 -48.091598)
		(end 170.222418 -48.586898)
		(width 0.0889)
		(layer "In9.Cu")
		(net "C_DATA0")
	)
	(segment
		(start 163.2204 -47.3456)
		(end 163.2204 -47.9806)
		(width 0.1143)
		(layer "F.Cu")
		(net "JTAG_PLD_TDO")
	)
	(segment
		(start 163.2204 -47.9806)
		(end 163.3474 -48.1076)
		(width 0.1143)
		(layer "F.Cu")
		(net "JTAG_PLD_TDO")
	)
	(segment
		(start 141.99743 -45.93717)
		(end 141.99743 -45.1612)
		(width 0.1143)
		(layer "F.Cu")
		(net "JTAG_PLD_TDO")
	)
	(segment
		(start 141.3256 -46.609)
		(end 141.99743 -45.93717)
		(width 0.1143)
		(layer "F.Cu")
		(net "JTAG_PLD_TDO")
	)
	(segment
		(start 141.097 -46.609)
		(end 141.3256 -46.609)
		(width 0.1143)
		(layer "F.Cu")
		(net "JTAG_PLD_TDO")
	)
	(segment
		(start 163.3474 -48.895)
		(end 163.3474 -48.1076)
		(width 0.1143)
		(layer "F.Cu")
		(net "JTAG_PLD_TDO")
	)
	(via
		(at 159.0294 -47.3456)
		(size 0.7112)
		(drill 0.3556)
		(layers "F.Cu" "B.Cu")
		(net "JTAG_PLD_TDO")
	)
	(via
		(at 141.097 -46.609)
		(size 0.508)
		(drill 0.254)
		(layers "F.Cu" "B.Cu")
		(net "JTAG_PLD_TDO")
	)
	(via
		(at 163.2204 -47.3456)
		(size 0.508)
		(drill 0.254)
		(layers "F.Cu" "B.Cu")
		(net "JTAG_PLD_TDO")
	)
	(segment
		(start 154.951176 -49.30775)
		(end 151.716486 -49.30775)
		(width 0.1143)
		(layer "B.Cu")
		(net "JTAG_PLD_TDO")
	)
	(segment
		(start 163.2204 -47.3456)
		(end 159.0294 -47.3456)
		(width 0.1143)
		(layer "B.Cu")
		(net "JTAG_PLD_TDO")
	)
	(segment
		(start 141.097 -47.043086)
		(end 141.097 -46.609)
		(width 0.1143)
		(layer "B.Cu")
		(net "JTAG_PLD_TDO")
	)
	(segment
		(start 156.913326 -47.3456)
		(end 154.951176 -49.30775)
		(width 0.1143)
		(layer "B.Cu")
		(net "JTAG_PLD_TDO")
	)
	(segment
		(start 159.0294 -47.3456)
		(end 156.913326 -47.3456)
		(width 0.1143)
		(layer "B.Cu")
		(net "JTAG_PLD_TDO")
	)
	(segment
		(start 143.006064 -48.95215)
		(end 141.097 -47.043086)
		(width 0.1143)
		(layer "B.Cu")
		(net "JTAG_PLD_TDO")
	)
	(segment
		(start 145.04162 -49.05375)
		(end 144.94002 -48.95215)
		(width 0.1143)
		(layer "B.Cu")
		(net "JTAG_PLD_TDO")
	)
	(segment
		(start 144.94002 -48.95215)
		(end 143.006064 -48.95215)
		(width 0.1143)
		(layer "B.Cu")
		(net "JTAG_PLD_TDO")
	)
	(segment
		(start 151.462486 -49.05375)
		(end 145.04162 -49.05375)
		(width 0.1143)
		(layer "B.Cu")
		(net "JTAG_PLD_TDO")
	)
	(segment
		(start 151.716486 -49.30775)
		(end 151.462486 -49.05375)
		(width 0.1143)
		(layer "B.Cu")
		(net "JTAG_PLD_TDO")
	)
	(segment
		(start 204.7748 -25.527)
		(end 203.42225 -24.17445)
		(width 0.1143)
		(layer "F.Cu")
		(net "JTAG_PLD_TCK")
	)
	(segment
		(start 204.7748 -26.162)
		(end 204.7748 -25.527)
		(width 0.1143)
		(layer "F.Cu")
		(net "JTAG_PLD_TCK")
	)
	(segment
		(start 201.684128 -17.276572)
		(end 201.684128 -17.026128)
		(width 0.1143)
		(layer "F.Cu")
		(net "JTAG_PLD_TCK")
	)
	(segment
		(start 160.2867 -44.45)
		(end 160.5026 -44.6659)
		(width 0.1143)
		(layer "F.Cu")
		(net "JTAG_PLD_TCK")
	)
	(segment
		(start 143.99768 -45.1612)
		(end 144.00276 -45.15612)
		(width 0.1143)
		(layer "F.Cu")
		(net "JTAG_PLD_TCK")
	)
	(segment
		(start 203.42225 -24.17445)
		(end 203.42225 -19.014694)
		(width 0.1143)
		(layer "F.Cu")
		(net "JTAG_PLD_TCK")
	)
	(segment
		(start 159.7406 -44.45)
		(end 160.2867 -44.45)
		(width 0.1143)
		(layer "F.Cu")
		(net "JTAG_PLD_TCK")
	)
	(segment
		(start 143.991838 -46.58487)
		(end 143.99768 -46.579028)
		(width 0.1143)
		(layer "F.Cu")
		(net "JTAG_PLD_TCK")
	)
	(segment
		(start 203.42225 -19.014694)
		(end 201.684128 -17.276572)
		(width 0.1143)
		(layer "F.Cu")
		(net "JTAG_PLD_TCK")
	)
	(segment
		(start 159.40405 -44.78655)
		(end 159.7406 -44.45)
		(width 0.1143)
		(layer "F.Cu")
		(net "JTAG_PLD_TCK")
	)
	(segment
		(start 152.407874 -44.78655)
		(end 159.40405 -44.78655)
		(width 0.1143)
		(layer "F.Cu")
		(net "JTAG_PLD_TCK")
	)
	(segment
		(start 144.00276 -44.608496)
		(end 144.269206 -44.34205)
		(width 0.1143)
		(layer "F.Cu")
		(net "JTAG_PLD_TCK")
	)
	(segment
		(start 143.99768 -46.579028)
		(end 143.99768 -45.1612)
		(width 0.1143)
		(layer "F.Cu")
		(net "JTAG_PLD_TCK")
	)
	(segment
		(start 144.00276 -45.15612)
		(end 144.00276 -44.608496)
		(width 0.1143)
		(layer "F.Cu")
		(net "JTAG_PLD_TCK")
	)
	(segment
		(start 144.269206 -44.34205)
		(end 151.963374 -44.34205)
		(width 0.1143)
		(layer "F.Cu")
		(net "JTAG_PLD_TCK")
	)
	(segment
		(start 151.963374 -44.34205)
		(end 152.407874 -44.78655)
		(width 0.1143)
		(layer "F.Cu")
		(net "JTAG_PLD_TCK")
	)
	(via
		(at 143.991838 -46.58487)
		(size 0.508)
		(drill 0.254)
		(layers "F.Cu" "B.Cu")
		(net "JTAG_PLD_TCK")
	)
	(via
		(at 160.5026 -44.6659)
		(size 0.508)
		(drill 0.254)
		(layers "F.Cu" "B.Cu")
		(net "JTAG_PLD_TCK")
	)
	(segment
		(start 144.8562 -47.498)
		(end 144.8562 -47.449232)
		(width 0.1143)
		(layer "B.Cu")
		(net "JTAG_PLD_TCK")
	)
	(segment
		(start 143.991838 -46.304962)
		(end 143.991838 -46.58487)
		(width 0.1143)
		(layer "B.Cu")
		(net "JTAG_PLD_TCK")
	)
	(segment
		(start 144.8308 -45.466)
		(end 143.991838 -46.304962)
		(width 0.1143)
		(layer "B.Cu")
		(net "JTAG_PLD_TCK")
	)
	(segment
		(start 144.8562 -47.449232)
		(end 143.991838 -46.58487)
		(width 0.1143)
		(layer "B.Cu")
		(net "JTAG_PLD_TCK")
	)
	(segment
		(start 160.5026 -44.6659)
		(end 160.5026 -45.1612)
		(width 0.0889)
		(layer "In9.Cu")
		(net "JTAG_PLD_TCK")
	)
	(segment
		(start 183.2356 -35.39363)
		(end 183.2356 -27.607006)
		(width 0.0889)
		(layer "In9.Cu")
		(net "JTAG_PLD_TCK")
	)
	(segment
		(start 163.670742 -43.3578)
		(end 168.8846 -43.3578)
		(width 0.0889)
		(layer "In9.Cu")
		(net "JTAG_PLD_TCK")
	)
	(segment
		(start 188.269372 -24.511)
		(end 195.754244 -17.026128)
		(width 0.0889)
		(layer "In9.Cu")
		(net "JTAG_PLD_TCK")
	)
	(segment
		(start 183.2356 -27.607006)
		(end 186.331606 -24.511)
		(width 0.0889)
		(layer "In9.Cu")
		(net "JTAG_PLD_TCK")
	)
	(segment
		(start 178.90998 -39.71925)
		(end 183.2356 -35.39363)
		(width 0.0889)
		(layer "In9.Cu")
		(net "JTAG_PLD_TCK")
	)
	(segment
		(start 172.52315 -39.71925)
		(end 178.90998 -39.71925)
		(width 0.0889)
		(layer "In9.Cu")
		(net "JTAG_PLD_TCK")
	)
	(segment
		(start 168.8846 -43.3578)
		(end 172.52315 -39.71925)
		(width 0.0889)
		(layer "In9.Cu")
		(net "JTAG_PLD_TCK")
	)
	(segment
		(start 160.97885 -45.63745)
		(end 161.391092 -45.63745)
		(width 0.0889)
		(layer "In9.Cu")
		(net "JTAG_PLD_TCK")
	)
	(segment
		(start 160.5026 -45.1612)
		(end 160.97885 -45.63745)
		(width 0.0889)
		(layer "In9.Cu")
		(net "JTAG_PLD_TCK")
	)
	(segment
		(start 195.754244 -17.026128)
		(end 201.684128 -17.026128)
		(width 0.0889)
		(layer "In9.Cu")
		(net "JTAG_PLD_TCK")
	)
	(segment
		(start 186.331606 -24.511)
		(end 188.269372 -24.511)
		(width 0.0889)
		(layer "In9.Cu")
		(net "JTAG_PLD_TCK")
	)
	(segment
		(start 161.391092 -45.63745)
		(end 163.670742 -43.3578)
		(width 0.0889)
		(layer "In9.Cu")
		(net "JTAG_PLD_TCK")
	)
	(segment
		(start 142.7226 -46.50359)
		(end 142.99819 -46.228)
		(width 0.1143)
		(layer "F.Cu")
		(net "JTAG_PLD_TMS")
	)
	(segment
		(start 152.16886 -43.84675)
		(end 143.60525 -43.84675)
		(width 0.1143)
		(layer "F.Cu")
		(net "JTAG_PLD_TMS")
	)
	(segment
		(start 142.99819 -44.45381)
		(end 142.99819 -45.1612)
		(width 0.1143)
		(layer "F.Cu")
		(net "JTAG_PLD_TMS")
	)
	(segment
		(start 142.99819 -46.228)
		(end 142.99819 -45.1612)
		(width 0.1143)
		(layer "F.Cu")
		(net "JTAG_PLD_TMS")
	)
	(segment
		(start 159.135318 -43.9547)
		(end 158.798768 -44.29125)
		(width 0.1143)
		(layer "F.Cu")
		(net "JTAG_PLD_TMS")
	)
	(segment
		(start 163.476686 -44.6786)
		(end 163.88715 -45.089064)
		(width 0.1143)
		(layer "F.Cu")
		(net "JTAG_PLD_TMS")
	)
	(segment
		(start 160.5661 -43.9547)
		(end 159.135318 -43.9547)
		(width 0.1143)
		(layer "F.Cu")
		(net "JTAG_PLD_TMS")
	)
	(segment
		(start 142.7226 -46.6344)
		(end 142.7226 -46.50359)
		(width 0.1143)
		(layer "F.Cu")
		(net "JTAG_PLD_TMS")
	)
	(segment
		(start 204.41285 -18.552922)
		(end 204.41285 -22.75205)
		(width 0.1143)
		(layer "F.Cu")
		(net "JTAG_PLD_TMS")
	)
	(segment
		(start 143.60525 -43.84675)
		(end 142.99819 -44.45381)
		(width 0.1143)
		(layer "F.Cu")
		(net "JTAG_PLD_TMS")
	)
	(segment
		(start 142.2908 -47.0662)
		(end 142.7226 -46.6344)
		(width 0.1143)
		(layer "F.Cu")
		(net "JTAG_PLD_TMS")
	)
	(segment
		(start 161.685224 -44.6786)
		(end 163.476686 -44.6786)
		(width 0.1143)
		(layer "F.Cu")
		(net "JTAG_PLD_TMS")
	)
	(segment
		(start 142.2908 -47.4472)
		(end 142.2908 -47.0662)
		(width 0.1143)
		(layer "F.Cu")
		(net "JTAG_PLD_TMS")
	)
	(segment
		(start 161.225992 -45.137832)
		(end 161.225992 -44.614592)
		(width 0.1143)
		(layer "F.Cu")
		(net "JTAG_PLD_TMS")
	)
	(segment
		(start 152.61336 -44.29125)
		(end 152.16886 -43.84675)
		(width 0.1143)
		(layer "F.Cu")
		(net "JTAG_PLD_TMS")
	)
	(segment
		(start 204.41285 -22.75205)
		(end 204.7748 -23.114)
		(width 0.1143)
		(layer "F.Cu")
		(net "JTAG_PLD_TMS")
	)
	(segment
		(start 203.2 -13.97)
		(end 203.2 -17.340072)
		(width 0.1143)
		(layer "F.Cu")
		(net "JTAG_PLD_TMS")
	)
	(segment
		(start 163.88715 -45.089064)
		(end 163.88715 -45.09135)
		(width 0.1143)
		(layer "F.Cu")
		(net "JTAG_PLD_TMS")
	)
	(segment
		(start 203.2 -17.340072)
		(end 204.41285 -18.552922)
		(width 0.1143)
		(layer "F.Cu")
		(net "JTAG_PLD_TMS")
	)
	(segment
		(start 163.88715 -45.09135)
		(end 164.211 -45.4152)
		(width 0.1143)
		(layer "F.Cu")
		(net "JTAG_PLD_TMS")
	)
	(segment
		(start 161.225992 -44.614592)
		(end 160.5661 -43.9547)
		(width 0.1143)
		(layer "F.Cu")
		(net "JTAG_PLD_TMS")
	)
	(segment
		(start 201.684128 -11.946128)
		(end 201.684128 -12.454128)
		(width 0.1143)
		(layer "F.Cu")
		(net "JTAG_PLD_TMS")
	)
	(segment
		(start 161.225992 -45.137832)
		(end 161.685224 -44.6786)
		(width 0.1143)
		(layer "F.Cu")
		(net "JTAG_PLD_TMS")
	)
	(segment
		(start 158.798768 -44.29125)
		(end 152.61336 -44.29125)
		(width 0.1143)
		(layer "F.Cu")
		(net "JTAG_PLD_TMS")
	)
	(segment
		(start 201.684128 -12.454128)
		(end 203.2 -13.97)
		(width 0.1143)
		(layer "F.Cu")
		(net "JTAG_PLD_TMS")
	)
	(via
		(at 161.225992 -45.137832)
		(size 0.508)
		(drill 0.254)
		(layers "F.Cu" "B.Cu")
		(net "JTAG_PLD_TMS")
	)
	(via
		(at 142.7226 -46.6344)
		(size 0.508)
		(drill 0.254)
		(layers "F.Cu" "B.Cu")
		(net "JTAG_PLD_TMS")
	)
	(segment
		(start 142.7226 -46.7614)
		(end 142.3162 -47.1678)
		(width 0.1143)
		(layer "B.Cu")
		(net "JTAG_PLD_TMS")
	)
	(segment
		(start 142.3162 -47.1678)
		(end 142.3162 -47.498)
		(width 0.1143)
		(layer "B.Cu")
		(net "JTAG_PLD_TMS")
	)
	(segment
		(start 142.7226 -46.6344)
		(end 142.7226 -46.7614)
		(width 0.1143)
		(layer "B.Cu")
		(net "JTAG_PLD_TMS")
	)
	(segment
		(start 182.7657 -35.198812)
		(end 182.7657 -25.460706)
		(width 0.0889)
		(layer "In9.Cu")
		(net "JTAG_PLD_TMS")
	)
	(segment
		(start 189.306454 -22.8092)
		(end 195.559426 -16.556228)
		(width 0.0889)
		(layer "In9.Cu")
		(net "JTAG_PLD_TMS")
	)
	(segment
		(start 189.3062 -22.8092)
		(end 189.306454 -22.8092)
		(width 0.0889)
		(layer "In9.Cu")
		(net "JTAG_PLD_TMS")
	)
	(segment
		(start 165.478206 -39.9034)
		(end 166.679118 -39.9034)
		(width 0.0889)
		(layer "In9.Cu")
		(net "JTAG_PLD_TMS")
	)
	(segment
		(start 182.7657 -25.460706)
		(end 184.604406 -23.622)
		(width 0.0889)
		(layer "In9.Cu")
		(net "JTAG_PLD_TMS")
	)
	(segment
		(start 195.559426 -16.556228)
		(end 197.074028 -16.556228)
		(width 0.0889)
		(layer "In9.Cu")
		(net "JTAG_PLD_TMS")
	)
	(segment
		(start 167.333168 -39.24935)
		(end 178.715162 -39.24935)
		(width 0.0889)
		(layer "In9.Cu")
		(net "JTAG_PLD_TMS")
	)
	(segment
		(start 166.679118 -39.9034)
		(end 167.333168 -39.24935)
		(width 0.0889)
		(layer "In9.Cu")
		(net "JTAG_PLD_TMS")
	)
	(segment
		(start 188.493654 -23.622)
		(end 189.3062 -22.8092)
		(width 0.0889)
		(layer "In9.Cu")
		(net "JTAG_PLD_TMS")
	)
	(segment
		(start 184.604406 -23.622)
		(end 188.493654 -23.622)
		(width 0.0889)
		(layer "In9.Cu")
		(net "JTAG_PLD_TMS")
	)
	(segment
		(start 178.715162 -39.24935)
		(end 182.7657 -35.198812)
		(width 0.0889)
		(layer "In9.Cu")
		(net "JTAG_PLD_TMS")
	)
	(segment
		(start 161.225992 -44.155614)
		(end 165.478206 -39.9034)
		(width 0.0889)
		(layer "In9.Cu")
		(net "JTAG_PLD_TMS")
	)
	(segment
		(start 161.225992 -45.137832)
		(end 161.225992 -44.155614)
		(width 0.0889)
		(layer "In9.Cu")
		(net "JTAG_PLD_TMS")
	)
	(segment
		(start 197.074028 -16.556228)
		(end 201.684128 -11.946128)
		(width 0.0889)
		(layer "In9.Cu")
		(net "JTAG_PLD_TMS")
	)
	(segment
		(start 206.2353 -25.61336)
		(end 206.2353 -11.9253)
		(width 0.1143)
		(layer "F.Cu")
		(net "JTAG_PLD_TDI")
	)
	(segment
		(start 204.7748 -27.686)
		(end 204.7748 -27.07386)
		(width 0.1143)
		(layer "F.Cu")
		(net "JTAG_PLD_TDI")
	)
	(segment
		(start 203.073 -8.255)
		(end 201.684128 -6.866128)
		(width 0.1143)
		(layer "F.Cu")
		(net "JTAG_PLD_TDI")
	)
	(segment
		(start 204.851 -10.541)
		(end 203.581 -10.541)
		(width 0.1143)
		(layer "F.Cu")
		(net "JTAG_PLD_TDI")
	)
	(segment
		(start 203.073 -10.033)
		(end 203.073 -8.255)
		(width 0.1143)
		(layer "F.Cu")
		(net "JTAG_PLD_TDI")
	)
	(segment
		(start 144.49806 -46.42993)
		(end 144.62633 -46.5582)
		(width 0.1143)
		(layer "F.Cu")
		(net "JTAG_PLD_TDI")
	)
	(segment
		(start 204.7748 -27.07386)
		(end 206.2353 -25.61336)
		(width 0.1143)
		(layer "F.Cu")
		(net "JTAG_PLD_TDI")
	)
	(segment
		(start 203.581 -10.541)
		(end 203.073 -10.033)
		(width 0.1143)
		(layer "F.Cu")
		(net "JTAG_PLD_TDI")
	)
	(segment
		(start 144.49806 -45.1612)
		(end 144.49806 -46.42993)
		(width 0.1143)
		(layer "F.Cu")
		(net "JTAG_PLD_TDI")
	)
	(segment
		(start 206.2353 -11.9253)
		(end 204.851 -10.541)
		(width 0.1143)
		(layer "F.Cu")
		(net "JTAG_PLD_TDI")
	)
	(via
		(at 144.62633 -46.5582)
		(size 0.508)
		(drill 0.254)
		(layers "F.Cu" "B.Cu")
		(net "JTAG_PLD_TDI")
	)
	(via
		(at 154.305 -47.8282)
		(size 0.508)
		(drill 0.254)
		(layers "F.Cu" "B.Cu")
		(net "JTAG_PLD_TDI")
	)
	(segment
		(start 152.04313 -47.84725)
		(end 151.4983 -47.886366)
		(width 0.1143)
		(layer "B.Cu")
		(net "JTAG_PLD_TDI")
	)
	(segment
		(start 149.764242 -47.736252)
		(end 146.07032 -47.736252)
		(width 0.1143)
		(layer "B.Cu")
		(net "JTAG_PLD_TDI")
	)
	(segment
		(start 150.14829 -48.1203)
		(end 149.764242 -47.736252)
		(width 0.1143)
		(layer "B.Cu")
		(net "JTAG_PLD_TDI")
	)
	(segment
		(start 151.1935 -48.1203)
		(end 150.14829 -48.1203)
		(width 0.1143)
		(layer "B.Cu")
		(net "JTAG_PLD_TDI")
	)
	(segment
		(start 151.257 -48.0568)
		(end 151.1935 -48.1203)
		(width 0.1143)
		(layer "B.Cu")
		(net "JTAG_PLD_TDI")
	)
	(segment
		(start 146.07032 -47.736252)
		(end 145.285714 -46.951646)
		(width 0.1143)
		(layer "B.Cu")
		(net "JTAG_PLD_TDI")
	)
	(segment
		(start 154.305 -47.8282)
		(end 154.28595 -47.84725)
		(width 0.1143)
		(layer "B.Cu")
		(net "JTAG_PLD_TDI")
	)
	(segment
		(start 151.422354 -47.8917)
		(end 151.257 -48.0568)
		(width 0.1143)
		(layer "B.Cu")
		(net "JTAG_PLD_TDI")
	)
	(segment
		(start 145.285714 -46.951646)
		(end 145.001488 -46.951646)
		(width 0.1143)
		(layer "B.Cu")
		(net "JTAG_PLD_TDI")
	)
	(segment
		(start 145.001488 -46.951646)
		(end 144.6276 -46.577758)
		(width 0.1143)
		(layer "B.Cu")
		(net "JTAG_PLD_TDI")
	)
	(segment
		(start 144.6276 -46.55947)
		(end 144.62633 -46.5582)
		(width 0.1143)
		(layer "B.Cu")
		(net "JTAG_PLD_TDI")
	)
	(segment
		(start 154.28595 -47.84725)
		(end 152.04313 -47.84725)
		(width 0.1143)
		(layer "B.Cu")
		(net "JTAG_PLD_TDI")
	)
	(segment
		(start 151.4983 -47.886366)
		(end 151.422354 -47.8917)
		(width 0.1143)
		(layer "B.Cu")
		(net "JTAG_PLD_TDI")
	)
	(segment
		(start 144.6276 -46.577758)
		(end 144.6276 -46.55947)
		(width 0.1143)
		(layer "B.Cu")
		(net "JTAG_PLD_TDI")
	)
	(segment
		(start 144.9832 -44.704)
		(end 145.669 -45.3898)
		(width 0.1143)
		(layer "B.Cu")
		(net "JTAG_PLD_TDI")
	)
	(segment
		(start 145.669 -45.3898)
		(end 145.669 -45.533818)
		(width 0.1143)
		(layer "B.Cu")
		(net "JTAG_PLD_TDI")
	)
	(segment
		(start 145.669 -45.533818)
		(end 144.644618 -46.5582)
		(width 0.1143)
		(layer "B.Cu")
		(net "JTAG_PLD_TDI")
	)
	(segment
		(start 144.8308 -44.704)
		(end 144.9832 -44.704)
		(width 0.1143)
		(layer "B.Cu")
		(net "JTAG_PLD_TDI")
	)
	(segment
		(start 144.644618 -46.5582)
		(end 144.62633 -46.5582)
		(width 0.1143)
		(layer "B.Cu")
		(net "JTAG_PLD_TDI")
	)
	(segment
		(start 154.9146 -47.2186)
		(end 154.305 -47.8282)
		(width 0.0889)
		(layer "In9.Cu")
		(net "JTAG_PLD_TDI")
	)
	(segment
		(start 164.60597 -38.91407)
		(end 156.30144 -47.2186)
		(width 0.0889)
		(layer "In9.Cu")
		(net "JTAG_PLD_TDI")
	)
	(segment
		(start 178.520344 -38.77945)
		(end 167.13835 -38.77945)
		(width 0.0889)
		(layer "In9.Cu")
		(net "JTAG_PLD_TDI")
	)
	(segment
		(start 182.2958 -25.265888)
		(end 182.2958 -35.003994)
		(width 0.0889)
		(layer "In9.Cu")
		(net "JTAG_PLD_TDI")
	)
	(segment
		(start 200.66 -12.109704)
		(end 196.683376 -16.086328)
		(width 0.0889)
		(layer "In9.Cu")
		(net "JTAG_PLD_TDI")
	)
	(segment
		(start 156.30144 -47.2186)
		(end 154.9146 -47.2186)
		(width 0.0889)
		(layer "In9.Cu")
		(net "JTAG_PLD_TDI")
	)
	(segment
		(start 196.683376 -16.086328)
		(end 195.364608 -16.086328)
		(width 0.0889)
		(layer "In9.Cu")
		(net "JTAG_PLD_TDI")
	)
	(segment
		(start 201.684128 -6.866128)
		(end 200.66 -7.890256)
		(width 0.0889)
		(layer "In9.Cu")
		(net "JTAG_PLD_TDI")
	)
	(segment
		(start 185.209688 -22.352)
		(end 182.2958 -25.265888)
		(width 0.0889)
		(layer "In9.Cu")
		(net "JTAG_PLD_TDI")
	)
	(segment
		(start 189.098936 -22.352)
		(end 185.209688 -22.352)
		(width 0.0889)
		(layer "In9.Cu")
		(net "JTAG_PLD_TDI")
	)
	(segment
		(start 200.66 -7.890256)
		(end 200.66 -12.109704)
		(width 0.0889)
		(layer "In9.Cu")
		(net "JTAG_PLD_TDI")
	)
	(segment
		(start 167.13835 -38.77945)
		(end 167.00373 -38.91407)
		(width 0.0889)
		(layer "In9.Cu")
		(net "JTAG_PLD_TDI")
	)
	(segment
		(start 167.00373 -38.91407)
		(end 164.60597 -38.91407)
		(width 0.0889)
		(layer "In9.Cu")
		(net "JTAG_PLD_TDI")
	)
	(segment
		(start 195.364608 -16.086328)
		(end 189.098936 -22.352)
		(width 0.0889)
		(layer "In9.Cu")
		(net "JTAG_PLD_TDI")
	)
	(segment
		(start 182.2958 -35.003994)
		(end 178.520344 -38.77945)
		(width 0.0889)
		(layer "In9.Cu")
		(net "JTAG_PLD_TDI")
	)
	(segment
		(start 27.1018 -65.9892)
		(end 27.4828 -65.6082)
		(width 0.4572)
		(layer "F.Cu")
		(net "VCCP_5VBIAS")
	)
	(segment
		(start 28.7274 -60.4266)
		(end 28.321 -60.833)
		(width 0.508)
		(layer "F.Cu")
		(net "VCCP_5VBIAS")
	)
	(segment
		(start 27.4066 -65.2018)
		(end 27.813 -65.6082)
		(width 0.4572)
		(layer "F.Cu")
		(net "VCCP_5VBIAS")
	)
	(segment
		(start 27.4066 -64.5922)
		(end 27.4066 -65.2018)
		(width 0.4572)
		(layer "F.Cu")
		(net "VCCP_5VBIAS")
	)
	(segment
		(start 26.5938 -65.9892)
		(end 27.1018 -65.9892)
		(width 0.508)
		(layer "F.Cu")
		(net "VCCP_5VBIAS")
	)
	(segment
		(start 27.4828 -65.6082)
		(end 27.813 -65.6082)
		(width 0.4572)
		(layer "F.Cu")
		(net "VCCP_5VBIAS")
	)
	(segment
		(start 28.321 -60.833)
		(end 27.982164 -60.833)
		(width 0.508)
		(layer "F.Cu")
		(net "VCCP_5VBIAS")
	)
	(segment
		(start 27.178 -60.833)
		(end 27.982164 -60.833)
		(width 0.508)
		(layer "F.Cu")
		(net "VCCP_5VBIAS")
	)
	(via
		(at 27.813 -65.6082)
		(size 0.508)
		(drill 0.254)
		(layers "F.Cu" "B.Cu")
		(net "VCCP_5VBIAS")
	)
	(via
		(at 27.7368 -62.6618)
		(size 0.7112)
		(drill 0.3556)
		(layers "F.Cu" "B.Cu")
		(net "VCCP_5VBIAS")
	)
	(via
		(at 27.982164 -60.833)
		(size 0.508)
		(drill 0.254)
		(layers "F.Cu" "B.Cu")
		(net "VCCP_5VBIAS")
	)
	(segment
		(start 27.982164 -60.833)
		(end 27.94 -60.833)
		(width 0.508)
		(layer "B.Cu")
		(net "VCCP_5VBIAS")
	)
	(segment
		(start 27.7368 -61.0362)
		(end 27.7368 -62.6618)
		(width 0.508)
		(layer "B.Cu")
		(net "VCCP_5VBIAS")
	)
	(segment
		(start 27.7368 -64.77)
		(end 27.7368 -65.532)
		(width 0.508)
		(layer "B.Cu")
		(net "VCCP_5VBIAS")
	)
	(segment
		(start 27.94 -60.833)
		(end 27.7368 -61.0362)
		(width 0.508)
		(layer "B.Cu")
		(net "VCCP_5VBIAS")
	)
	(segment
		(start 27.7368 -65.532)
		(end 27.813 -65.6082)
		(width 0.508)
		(layer "B.Cu")
		(net "VCCP_5VBIAS")
	)
	(segment
		(start 27.7368 -62.6618)
		(end 27.7368 -64.77)
		(width 0.508)
		(layer "B.Cu")
		(net "VCCP_5VBIAS")
	)
	(segment
		(start 70.850252 -22.07387)
		(end 70.607936 -21.831554)
		(width 0.254)
		(layer "B.Cu")
		(net "VR_EN_P1V8_STBY")
	)
	(segment
		(start 71.9074 -22.3774)
		(end 71.60387 -22.07387)
		(width 0.254)
		(layer "B.Cu")
		(net "VR_EN_P1V8_STBY")
	)
	(segment
		(start 71.60387 -22.07387)
		(end 70.850252 -22.07387)
		(width 0.254)
		(layer "B.Cu")
		(net "VR_EN_P1V8_STBY")
	)
	(segment
		(start 70.607936 -21.831554)
		(end 70.607936 -21.38807)
		(width 0.254)
		(layer "B.Cu")
		(net "VR_EN_P1V8_STBY")
	)
	(segment
		(start 67.0052 -17.78)
		(end 66.3194 -17.78)
		(width 0.254)
		(layer "B.Cu")
		(net "VR_FB_R_P1V8_STBY")
	)
	(segment
		(start 65.532 -18.5674)
		(end 65.532 -19.2278)
		(width 0.254)
		(layer "B.Cu")
		(net "VR_FB_R_P1V8_STBY")
	)
	(segment
		(start 65.532 -19.2278)
		(end 65.405 -19.3548)
		(width 0.254)
		(layer "B.Cu")
		(net "VR_FB_R_P1V8_STBY")
	)
	(segment
		(start 66.3194 -17.78)
		(end 65.532 -18.5674)
		(width 0.254)
		(layer "B.Cu")
		(net "VR_FB_R_P1V8_STBY")
	)
	(via
		(at 70.5358 -24.6126)
		(size 0.7112)
		(drill 0.3556)
		(layers "F.Cu" "B.Cu")
		(net "VR_AVIN_P1V8_STBY")
	)
	(segment
		(start 71.0946 -24.6126)
		(end 70.5358 -24.6126)
		(width 0.3048)
		(layer "B.Cu")
		(net "VR_AVIN_P1V8_STBY")
	)
	(segment
		(start 70.231 -23.4188)
		(end 69.3674 -22.5552)
		(width 0.3048)
		(layer "B.Cu")
		(net "VR_AVIN_P1V8_STBY")
	)
	(segment
		(start 70.108064 -19.369786)
		(end 70.108064 -18.74393)
		(width 0.3048)
		(layer "B.Cu")
		(net "VR_AVIN_P1V8_STBY")
	)
	(segment
		(start 70.4342 -19.695922)
		(end 70.108064 -19.369786)
		(width 0.3048)
		(layer "B.Cu")
		(net "VR_AVIN_P1V8_STBY")
	)
	(segment
		(start 69.607938 -20.908772)
		(end 69.99351 -20.5232)
		(width 0.3048)
		(layer "B.Cu")
		(net "VR_AVIN_P1V8_STBY")
	)
	(segment
		(start 70.2818 -23.4188)
		(end 70.231 -23.4188)
		(width 0.3048)
		(layer "B.Cu")
		(net "VR_AVIN_P1V8_STBY")
	)
	(segment
		(start 70.5358 -24.6126)
		(end 70.2818 -24.3586)
		(width 0.3048)
		(layer "B.Cu")
		(net "VR_AVIN_P1V8_STBY")
	)
	(segment
		(start 69.607938 -21.38807)
		(end 69.607938 -20.908772)
		(width 0.3048)
		(layer "B.Cu")
		(net "VR_AVIN_P1V8_STBY")
	)
	(segment
		(start 69.3674 -22.5552)
		(end 69.3674 -22.136354)
		(width 0.3048)
		(layer "B.Cu")
		(net "VR_AVIN_P1V8_STBY")
	)
	(segment
		(start 70.12178 -20.5232)
		(end 70.4342 -20.21078)
		(width 0.3048)
		(layer "B.Cu")
		(net "VR_AVIN_P1V8_STBY")
	)
	(segment
		(start 69.99351 -20.5232)
		(end 70.12178 -20.5232)
		(width 0.3048)
		(layer "B.Cu")
		(net "VR_AVIN_P1V8_STBY")
	)
	(segment
		(start 71.5772 -24.13)
		(end 71.0946 -24.6126)
		(width 0.3048)
		(layer "B.Cu")
		(net "VR_AVIN_P1V8_STBY")
	)
	(segment
		(start 69.3674 -22.136354)
		(end 69.607938 -21.895816)
		(width 0.3048)
		(layer "B.Cu")
		(net "VR_AVIN_P1V8_STBY")
	)
	(segment
		(start 70.2818 -24.3586)
		(end 70.2818 -23.4188)
		(width 0.3048)
		(layer "B.Cu")
		(net "VR_AVIN_P1V8_STBY")
	)
	(segment
		(start 69.607938 -21.895816)
		(end 69.607938 -21.38807)
		(width 0.3048)
		(layer "B.Cu")
		(net "VR_AVIN_P1V8_STBY")
	)
	(segment
		(start 70.4342 -20.21078)
		(end 70.4342 -19.695922)
		(width 0.3048)
		(layer "B.Cu")
		(net "VR_AVIN_P1V8_STBY")
	)
	(segment
		(start 67.780408 -17.868392)
		(end 67.848734 -17.868392)
		(width 0.254)
		(layer "F.Cu")
		(net "VR_FB_P1V8_STBY")
	)
	(segment
		(start 67.183 -18.4658)
		(end 67.780408 -17.868392)
		(width 0.254)
		(layer "F.Cu")
		(net "VR_FB_P1V8_STBY")
	)
	(segment
		(start 67.183 -18.5674)
		(end 67.183 -18.4658)
		(width 0.254)
		(layer "F.Cu")
		(net "VR_FB_P1V8_STBY")
	)
	(via
		(at 67.848734 -17.868392)
		(size 0.7112)
		(drill 0.3556)
		(layers "F.Cu" "B.Cu")
		(net "VR_FB_P1V8_STBY")
	)
	(via
		(at 69.9008 -19.9898)
		(size 0.508)
		(drill 0.254)
		(layers "F.Cu" "B.Cu")
		(net "VR_FB_P1V8_STBY")
	)
	(via
		(at 67.183 -18.5674)
		(size 0.508)
		(drill 0.254)
		(layers "F.Cu" "B.Cu")
		(net "VR_FB_P1V8_STBY")
	)
	(segment
		(start 66.3194 -18.6436)
		(end 66.3956 -18.5674)
		(width 0.254)
		(layer "B.Cu")
		(net "VR_FB_P1V8_STBY")
	)
	(segment
		(start 69.607938 -18.74393)
		(end 69.607938 -19.444462)
		(width 0.254)
		(layer "B.Cu")
		(net "VR_FB_P1V8_STBY")
	)
	(segment
		(start 67.183 -18.5674)
		(end 66.3956 -18.5674)
		(width 0.254)
		(layer "B.Cu")
		(net "VR_FB_P1V8_STBY")
	)
	(segment
		(start 69.9008 -19.737324)
		(end 69.9008 -19.9898)
		(width 0.254)
		(layer "B.Cu")
		(net "VR_FB_P1V8_STBY")
	)
	(segment
		(start 66.3194 -19.4818)
		(end 66.3194 -19.3548)
		(width 0.254)
		(layer "B.Cu")
		(net "VR_FB_P1V8_STBY")
	)
	(segment
		(start 66.3194 -19.3548)
		(end 66.3194 -18.6436)
		(width 0.254)
		(layer "B.Cu")
		(net "VR_FB_P1V8_STBY")
	)
	(segment
		(start 66.3956 -19.558)
		(end 66.3194 -19.4818)
		(width 0.254)
		(layer "B.Cu")
		(net "VR_FB_P1V8_STBY")
	)
	(segment
		(start 66.3956 -21.082)
		(end 66.3956 -19.558)
		(width 0.254)
		(layer "B.Cu")
		(net "VR_FB_P1V8_STBY")
	)
	(segment
		(start 69.607938 -19.444462)
		(end 69.9008 -19.737324)
		(width 0.254)
		(layer "B.Cu")
		(net "VR_FB_P1V8_STBY")
	)
	(segment
		(start 67.2084 -18.5928)
		(end 68.5038 -18.5928)
		(width 0.254)
		(layer "In7.Cu")
		(net "VR_FB_P1V8_STBY")
	)
	(segment
		(start 67.183 -18.5674)
		(end 67.2084 -18.5928)
		(width 0.254)
		(layer "In7.Cu")
		(net "VR_FB_P1V8_STBY")
	)
	(segment
		(start 68.5038 -18.5928)
		(end 69.9008 -19.9898)
		(width 0.254)
		(layer "In7.Cu")
		(net "VR_FB_P1V8_STBY")
	)
	(via
		(at 72.8218 -21.9964)
		(size 0.7112)
		(drill 0.3556)
		(layers "F.Cu" "B.Cu")
		(net "VR_PVIN_P1V8_STBY")
	)
	(segment
		(start 72.593454 -23.977346)
		(end 72.4408 -24.13)
		(width 0.4572)
		(layer "B.Cu")
		(net "VR_PVIN_P1V8_STBY")
	)
	(segment
		(start 72.593454 -22.224746)
		(end 72.593454 -23.977346)
		(width 0.4572)
		(layer "B.Cu")
		(net "VR_PVIN_P1V8_STBY")
	)
	(segment
		(start 72.8218 -21.9964)
		(end 72.593454 -22.224746)
		(width 0.4572)
		(layer "B.Cu")
		(net "VR_PVIN_P1V8_STBY")
	)
	(segment
		(start 14.2494 -34.1376)
		(end 14.2494 -33.1978)
		(width 0.254)
		(layer "F.Cu")
		(net "P3V3_STBY_EN")
	)
	(segment
		(start 13.937996 -34.449004)
		(end 14.2494 -34.1376)
		(width 0.254)
		(layer "F.Cu")
		(net "P3V3_STBY_EN")
	)
	(segment
		(start 14.2494 -32.5374)
		(end 14.2494 -33.1978)
		(width 0.254)
		(layer "F.Cu")
		(net "P3V3_STBY_EN")
	)
	(segment
		(start 15.24 -32.3088)
		(end 14.478 -32.3088)
		(width 0.254)
		(layer "F.Cu")
		(net "P3V3_STBY_EN")
	)
	(segment
		(start 14.478 -32.3088)
		(end 14.2494 -32.5374)
		(width 0.254)
		(layer "F.Cu")
		(net "P3V3_STBY_EN")
	)
	(segment
		(start 13.371322 -34.449004)
		(end 13.937996 -34.449004)
		(width 0.254)
		(layer "F.Cu")
		(net "P3V3_STBY_EN")
	)
	(via
		(at 14.2494 -33.1978)
		(size 0.508)
		(drill 0.254)
		(layers "F.Cu" "B.Cu")
		(net "P3V3_STBY_EN")
	)
	(via
		(at 15.24 -33.401)
		(size 0.7112)
		(drill 0.3556)
		(layers "F.Cu" "B.Cu")
		(net "P3V3_STBY_EN")
	)
	(segment
		(start 14.2494 -33.1978)
		(end 14.4526 -33.401)
		(width 0.254)
		(layer "B.Cu")
		(net "P3V3_STBY_EN")
	)
	(segment
		(start 14.4526 -33.401)
		(end 15.24 -33.401)
		(width 0.254)
		(layer "B.Cu")
		(net "P3V3_STBY_EN")
	)
	(segment
		(start 15.367 -33.274)
		(end 15.24 -33.401)
		(width 0.254)
		(layer "B.Cu")
		(net "P3V3_STBY_EN")
	)
	(segment
		(start 15.367 -32.2072)
		(end 15.367 -33.274)
		(width 0.254)
		(layer "B.Cu")
		(net "P3V3_STBY_EN")
	)
	(segment
		(start 85.687408 -30.759654)
		(end 84.887308 -30.759654)
		(width 0.1397)
		(layer "F.Cu")
		(net "CLK_100M_SATA2_DN")
	)
	(segment
		(start 84.887308 -30.759654)
		(end 84.734654 -30.607)
		(width 0.1397)
		(layer "F.Cu")
		(net "CLK_100M_SATA2_DN")
	)
	(via
		(at 45.956474 -43.93819)
		(size 0.508)
		(drill 0.254)
		(layers "F.Cu" "B.Cu")
		(net "CLK_100M_SATA2_DN")
	)
	(via
		(at 84.734654 -30.607)
		(size 0.4318)
		(drill 0.2032)
		(layers "F.Cu" "B.Cu")
		(net "CLK_100M_SATA2_DN")
	)
	(segment
		(start 46.001686 -45.319188)
		(end 46.001686 -45.135546)
		(width 0.1397)
		(layer "B.Cu")
		(net "CLK_100M_SATA2_DN")
	)
	(segment
		(start 46.058582 -46.087792)
		(end 46.058582 -45.376084)
		(width 0.1397)
		(layer "B.Cu")
		(net "CLK_100M_SATA2_DN")
	)
	(segment
		(start 45.649134 -44.782994)
		(end 45.649134 -44.24553)
		(width 0.1397)
		(layer "B.Cu")
		(net "CLK_100M_SATA2_DN")
	)
	(segment
		(start 46.058582 -45.376084)
		(end 46.001686 -45.319188)
		(width 0.1397)
		(layer "B.Cu")
		(net "CLK_100M_SATA2_DN")
	)
	(segment
		(start 45.649134 -44.24553)
		(end 45.956474 -43.93819)
		(width 0.1397)
		(layer "B.Cu")
		(net "CLK_100M_SATA2_DN")
	)
	(segment
		(start 46.001686 -45.135546)
		(end 45.649134 -44.782994)
		(width 0.1397)
		(layer "B.Cu")
		(net "CLK_100M_SATA2_DN")
	)
	(segment
		(start 64.627506 -29.4005)
		(end 69.812154 -29.4005)
		(width 0.1143)
		(layer "In4.Cu")
		(net "CLK_100M_SATA2_DN")
	)
	(segment
		(start 45.4152 -42.79011)
		(end 45.4152 -42.16019)
		(width 0.1143)
		(layer "In4.Cu")
		(net "CLK_100M_SATA2_DN")
	)
	(segment
		(start 45.668184 -43.043094)
		(end 45.4152 -42.79011)
		(width 0.1143)
		(layer "In4.Cu")
		(net "CLK_100M_SATA2_DN")
	)
	(segment
		(start 45.4152 -42.16019)
		(end 47.59579 -39.9796)
		(width 0.1143)
		(layer "In4.Cu")
		(net "CLK_100M_SATA2_DN")
	)
	(segment
		(start 82.242914 -27.76855)
		(end 82.585814 -27.76855)
		(width 0.1143)
		(layer "In4.Cu")
		(net "CLK_100M_SATA2_DN")
	)
	(segment
		(start 83.1215 -29.221176)
		(end 84.278724 -30.3784)
		(width 0.1016)
		(layer "In4.Cu")
		(net "CLK_100M_SATA2_DN")
	)
	(segment
		(start 69.812154 -29.4005)
		(end 70.281546 -28.9306)
		(width 0.1143)
		(layer "In4.Cu")
		(net "CLK_100M_SATA2_DN")
	)
	(segment
		(start 81.686654 -27.98191)
		(end 82.029554 -27.98191)
		(width 0.1143)
		(layer "In4.Cu")
		(net "CLK_100M_SATA2_DN")
	)
	(segment
		(start 84.278724 -30.3784)
		(end 84.506054 -30.3784)
		(width 0.1016)
		(layer "In4.Cu")
		(net "CLK_100M_SATA2_DN")
	)
	(segment
		(start 83.1215 -28.6385)
		(end 83.1215 -29.221176)
		(width 0.1016)
		(layer "In4.Cu")
		(net "CLK_100M_SATA2_DN")
	)
	(segment
		(start 82.585814 -27.76855)
		(end 83.058 -28.240736)
		(width 0.1143)
		(layer "In4.Cu")
		(net "CLK_100M_SATA2_DN")
	)
	(segment
		(start 82.029554 -27.98191)
		(end 82.242914 -27.76855)
		(width 0.1143)
		(layer "In4.Cu")
		(net "CLK_100M_SATA2_DN")
	)
	(segment
		(start 80.917034 -27.98191)
		(end 81.130394 -27.76855)
		(width 0.1143)
		(layer "In4.Cu")
		(net "CLK_100M_SATA2_DN")
	)
	(segment
		(start 83.058 -28.5496)
		(end 83.058 -28.575)
		(width 0.1016)
		(layer "In4.Cu")
		(net "CLK_100M_SATA2_DN")
	)
	(segment
		(start 56.2102 -36.486338)
		(end 56.2102 -34.299906)
		(width 0.1143)
		(layer "In4.Cu")
		(net "CLK_100M_SATA2_DN")
	)
	(segment
		(start 81.130394 -27.76855)
		(end 81.473294 -27.76855)
		(width 0.1143)
		(layer "In4.Cu")
		(net "CLK_100M_SATA2_DN")
	)
	(segment
		(start 60.02274 -33.18256)
		(end 60.2361 -32.9692)
		(width 0.1143)
		(layer "In4.Cu")
		(net "CLK_100M_SATA2_DN")
	)
	(segment
		(start 83.058 -28.575)
		(end 83.1215 -28.6385)
		(width 0.1016)
		(layer "In4.Cu")
		(net "CLK_100M_SATA2_DN")
	)
	(segment
		(start 80.574134 -27.98191)
		(end 80.917034 -27.98191)
		(width 0.1143)
		(layer "In4.Cu")
		(net "CLK_100M_SATA2_DN")
	)
	(segment
		(start 57.540906 -32.9692)
		(end 58.35396 -32.9692)
		(width 0.1143)
		(layer "In4.Cu")
		(net "CLK_100M_SATA2_DN")
	)
	(segment
		(start 60.2361 -32.9692)
		(end 61.058806 -32.9692)
		(width 0.1143)
		(layer "In4.Cu")
		(net "CLK_100M_SATA2_DN")
	)
	(segment
		(start 59.12358 -32.9692)
		(end 59.46648 -32.9692)
		(width 0.1143)
		(layer "In4.Cu")
		(net "CLK_100M_SATA2_DN")
	)
	(segment
		(start 56.2102 -34.299906)
		(end 57.540906 -32.9692)
		(width 0.1143)
		(layer "In4.Cu")
		(net "CLK_100M_SATA2_DN")
	)
	(segment
		(start 58.35396 -32.9692)
		(end 58.56732 -33.18256)
		(width 0.1143)
		(layer "In4.Cu")
		(net "CLK_100M_SATA2_DN")
	)
	(segment
		(start 47.59579 -39.9796)
		(end 52.716938 -39.9796)
		(width 0.1143)
		(layer "In4.Cu")
		(net "CLK_100M_SATA2_DN")
	)
	(segment
		(start 59.67984 -33.18256)
		(end 60.02274 -33.18256)
		(width 0.1143)
		(layer "In4.Cu")
		(net "CLK_100M_SATA2_DN")
	)
	(segment
		(start 58.91022 -33.18256)
		(end 59.12358 -32.9692)
		(width 0.1143)
		(layer "In4.Cu")
		(net "CLK_100M_SATA2_DN")
	)
	(segment
		(start 75.67676 -28.9306)
		(end 76.83881 -27.76855)
		(width 0.1143)
		(layer "In4.Cu")
		(net "CLK_100M_SATA2_DN")
	)
	(segment
		(start 76.83881 -27.76855)
		(end 80.360774 -27.76855)
		(width 0.1143)
		(layer "In4.Cu")
		(net "CLK_100M_SATA2_DN")
	)
	(segment
		(start 58.56732 -33.18256)
		(end 58.91022 -33.18256)
		(width 0.1143)
		(layer "In4.Cu")
		(net "CLK_100M_SATA2_DN")
	)
	(segment
		(start 70.281546 -28.9306)
		(end 75.67676 -28.9306)
		(width 0.1143)
		(layer "In4.Cu")
		(net "CLK_100M_SATA2_DN")
	)
	(segment
		(start 45.668184 -43.6499)
		(end 45.668184 -43.043094)
		(width 0.1143)
		(layer "In4.Cu")
		(net "CLK_100M_SATA2_DN")
	)
	(segment
		(start 83.058 -28.240736)
		(end 83.058 -28.5496)
		(width 0.1143)
		(layer "In4.Cu")
		(net "CLK_100M_SATA2_DN")
	)
	(segment
		(start 81.473294 -27.76855)
		(end 81.686654 -27.98191)
		(width 0.1143)
		(layer "In4.Cu")
		(net "CLK_100M_SATA2_DN")
	)
	(segment
		(start 84.506054 -30.3784)
		(end 84.734654 -30.607)
		(width 0.1016)
		(layer "In4.Cu")
		(net "CLK_100M_SATA2_DN")
	)
	(segment
		(start 59.46648 -32.9692)
		(end 59.67984 -33.18256)
		(width 0.1143)
		(layer "In4.Cu")
		(net "CLK_100M_SATA2_DN")
	)
	(segment
		(start 61.058806 -32.9692)
		(end 64.627506 -29.4005)
		(width 0.1143)
		(layer "In4.Cu")
		(net "CLK_100M_SATA2_DN")
	)
	(segment
		(start 80.360774 -27.76855)
		(end 80.574134 -27.98191)
		(width 0.1143)
		(layer "In4.Cu")
		(net "CLK_100M_SATA2_DN")
	)
	(segment
		(start 45.956474 -43.93819)
		(end 45.668184 -43.6499)
		(width 0.1143)
		(layer "In4.Cu")
		(net "CLK_100M_SATA2_DN")
	)
	(segment
		(start 52.716938 -39.9796)
		(end 56.2102 -36.486338)
		(width 0.1143)
		(layer "In4.Cu")
		(net "CLK_100M_SATA2_DN")
	)
	(segment
		(start 85.687408 -29.997654)
		(end 84.73313 -29.997654)
		(width 0.1397)
		(layer "F.Cu")
		(net "CLK_100M_SATA2_DP")
	)
	(segment
		(start 84.73313 -29.997654)
		(end 84.717636 -29.98216)
		(width 0.1397)
		(layer "F.Cu")
		(net "CLK_100M_SATA2_DP")
	)
	(via
		(at 44.998386 -43.9166)
		(size 0.508)
		(drill 0.254)
		(layers "F.Cu" "B.Cu")
		(net "CLK_100M_SATA2_DP")
	)
	(via
		(at 84.717636 -29.98216)
		(size 0.4318)
		(drill 0.2032)
		(layers "F.Cu" "B.Cu")
		(net "CLK_100M_SATA2_DP")
	)
	(segment
		(start 45.658786 -45.277786)
		(end 45.306234 -44.925234)
		(width 0.1397)
		(layer "B.Cu")
		(net "CLK_100M_SATA2_DP")
	)
	(segment
		(start 45.658786 -46.087792)
		(end 45.658786 -45.277786)
		(width 0.1397)
		(layer "B.Cu")
		(net "CLK_100M_SATA2_DP")
	)
	(segment
		(start 45.306234 -44.224448)
		(end 44.998386 -43.9166)
		(width 0.1397)
		(layer "B.Cu")
		(net "CLK_100M_SATA2_DP")
	)
	(segment
		(start 45.306234 -44.925234)
		(end 45.306234 -44.224448)
		(width 0.1397)
		(layer "B.Cu")
		(net "CLK_100M_SATA2_DP")
	)
	(segment
		(start 55.88 -36.349432)
		(end 55.88 -34.163)
		(width 0.1143)
		(layer "In4.Cu")
		(net "CLK_100M_SATA2_DP")
	)
	(segment
		(start 45.337984 -43.577002)
		(end 45.337984 -43.18)
		(width 0.1143)
		(layer "In4.Cu")
		(net "CLK_100M_SATA2_DP")
	)
	(segment
		(start 76.701904 -27.43835)
		(end 82.72272 -27.43835)
		(width 0.1143)
		(layer "In4.Cu")
		(net "CLK_100M_SATA2_DP")
	)
	(segment
		(start 45.085 -42.927016)
		(end 45.085 -42.023284)
		(width 0.1143)
		(layer "In4.Cu")
		(net "CLK_100M_SATA2_DP")
	)
	(segment
		(start 83.3882 -28.10383)
		(end 83.3882 -28.5496)
		(width 0.1143)
		(layer "In4.Cu")
		(net "CLK_100M_SATA2_DP")
	)
	(segment
		(start 45.337984 -43.18)
		(end 45.085 -42.927016)
		(width 0.1143)
		(layer "In4.Cu")
		(net "CLK_100M_SATA2_DP")
	)
	(segment
		(start 82.72272 -27.43835)
		(end 83.3882 -28.10383)
		(width 0.1143)
		(layer "In4.Cu")
		(net "CLK_100M_SATA2_DP")
	)
	(segment
		(start 84.363052 -30.1752)
		(end 84.524596 -30.1752)
		(width 0.1016)
		(layer "In4.Cu")
		(net "CLK_100M_SATA2_DP")
	)
	(segment
		(start 57.404 -32.639)
		(end 60.9219 -32.639)
		(width 0.1143)
		(layer "In4.Cu")
		(net "CLK_100M_SATA2_DP")
	)
	(segment
		(start 83.3882 -28.5496)
		(end 83.3882 -28.575)
		(width 0.1016)
		(layer "In4.Cu")
		(net "CLK_100M_SATA2_DP")
	)
	(segment
		(start 84.524596 -30.1752)
		(end 84.717636 -29.98216)
		(width 0.1016)
		(layer "In4.Cu")
		(net "CLK_100M_SATA2_DP")
	)
	(segment
		(start 75.539854 -28.6004)
		(end 76.701904 -27.43835)
		(width 0.1143)
		(layer "In4.Cu")
		(net "CLK_100M_SATA2_DP")
	)
	(segment
		(start 83.3247 -29.136848)
		(end 84.363052 -30.1752)
		(width 0.1016)
		(layer "In4.Cu")
		(net "CLK_100M_SATA2_DP")
	)
	(segment
		(start 83.3247 -28.6385)
		(end 83.3247 -29.136848)
		(width 0.1016)
		(layer "In4.Cu")
		(net "CLK_100M_SATA2_DP")
	)
	(segment
		(start 69.675248 -29.0703)
		(end 70.14464 -28.6004)
		(width 0.1143)
		(layer "In4.Cu")
		(net "CLK_100M_SATA2_DP")
	)
	(segment
		(start 55.88 -34.163)
		(end 57.404 -32.639)
		(width 0.1143)
		(layer "In4.Cu")
		(net "CLK_100M_SATA2_DP")
	)
	(segment
		(start 70.14464 -28.6004)
		(end 75.539854 -28.6004)
		(width 0.1143)
		(layer "In4.Cu")
		(net "CLK_100M_SATA2_DP")
	)
	(segment
		(start 52.580032 -39.6494)
		(end 55.88 -36.349432)
		(width 0.1143)
		(layer "In4.Cu")
		(net "CLK_100M_SATA2_DP")
	)
	(segment
		(start 44.998386 -43.9166)
		(end 45.337984 -43.577002)
		(width 0.1143)
		(layer "In4.Cu")
		(net "CLK_100M_SATA2_DP")
	)
	(segment
		(start 47.458884 -39.6494)
		(end 52.580032 -39.6494)
		(width 0.1143)
		(layer "In4.Cu")
		(net "CLK_100M_SATA2_DP")
	)
	(segment
		(start 45.085 -42.023284)
		(end 47.458884 -39.6494)
		(width 0.1143)
		(layer "In4.Cu")
		(net "CLK_100M_SATA2_DP")
	)
	(segment
		(start 83.3882 -28.575)
		(end 83.3247 -28.6385)
		(width 0.1016)
		(layer "In4.Cu")
		(net "CLK_100M_SATA2_DP")
	)
	(segment
		(start 64.4906 -29.0703)
		(end 69.675248 -29.0703)
		(width 0.1143)
		(layer "In4.Cu")
		(net "CLK_100M_SATA2_DP")
	)
	(segment
		(start 60.9219 -32.639)
		(end 64.4906 -29.0703)
		(width 0.1143)
		(layer "In4.Cu")
		(net "CLK_100M_SATA2_DP")
	)
	(segment
		(start 160.1978 -25.527)
		(end 161.29 -25.527)
		(width 0.3048)
		(layer "F.Cu")
		(net "P2V5_STBY")
	)
	(segment
		(start 134.49808 -45.974)
		(end 134.49808 -45.1612)
		(width 0.3048)
		(layer "F.Cu")
		(net "P2V5_STBY")
	)
	(segment
		(start 166.822882 -38.427406)
		(end 166.787068 -38.46322)
		(width 0.508)
		(layer "F.Cu")
		(net "P2V5_STBY")
	)
	(segment
		(start 166.116 -37.792152)
		(end 166.787068 -38.46322)
		(width 0.3048)
		(layer "F.Cu")
		(net "P2V5_STBY")
	)
	(segment
		(start 163.81095 -28.04795)
		(end 163.81095 -33.039304)
		(width 0.3048)
		(layer "F.Cu")
		(net "P2V5_STBY")
	)
	(segment
		(start 150.99792 -21.16328)
		(end 151.003 -21.1582)
		(width 0.3048)
		(layer "F.Cu")
		(net "P2V5_STBY")
	)
	(segment
		(start 150.088092 -22.61743)
		(end 150.241 -22.464522)
		(width 0.3048)
		(layer "F.Cu")
		(net "P2V5_STBY")
	)
	(segment
		(start 167.767 -38.427406)
		(end 166.822882 -38.427406)
		(width 0.508)
		(layer "F.Cu")
		(net "P2V5_STBY")
	)
	(segment
		(start 134.674356 -46.604174)
		(end 134.674356 -46.150276)
		(width 0.3048)
		(layer "F.Cu")
		(net "P2V5_STBY")
	)
	(segment
		(start 163.81095 -33.039304)
		(end 166.116 -35.344354)
		(width 0.3048)
		(layer "F.Cu")
		(net "P2V5_STBY")
	)
	(segment
		(start 151.003 -21.1582)
		(end 150.241 -21.1582)
		(width 0.3048)
		(layer "F.Cu")
		(net "P2V5_STBY")
	)
	(segment
		(start 161.29 -25.527)
		(end 163.81095 -28.04795)
		(width 0.3048)
		(layer "F.Cu")
		(net "P2V5_STBY")
	)
	(segment
		(start 166.116 -35.344354)
		(end 166.116 -37.792152)
		(width 0.3048)
		(layer "F.Cu")
		(net "P2V5_STBY")
	)
	(segment
		(start 168.450006 -38.427406)
		(end 167.767 -38.427406)
		(width 0.508)
		(layer "F.Cu")
		(net "P2V5_STBY")
	)
	(segment
		(start 150.99792 -23.9268)
		(end 150.99792 -21.16328)
		(width 0.3048)
		(layer "F.Cu")
		(net "P2V5_STBY")
	)
	(segment
		(start 150.241 -22.464522)
		(end 150.241 -21.1582)
		(width 0.3048)
		(layer "F.Cu")
		(net "P2V5_STBY")
	)
	(segment
		(start 134.674356 -46.150276)
		(end 134.49808 -45.974)
		(width 0.3048)
		(layer "F.Cu")
		(net "P2V5_STBY")
	)
	(segment
		(start 169.0116 -38.989)
		(end 168.450006 -38.427406)
		(width 0.508)
		(layer "F.Cu")
		(net "P2V5_STBY")
	)
	(via
		(at 134.674356 -46.604174)
		(size 0.508)
		(drill 0.254)
		(layers "F.Cu" "B.Cu")
		(net "P2V5_STBY")
	)
	(via
		(at 136.305036 -43.145964)
		(size 0.7112)
		(drill 0.3556)
		(layers "F.Cu" "B.Cu")
		(net "P2V5_STBY")
	)
	(via
		(at 154.4066 -24.8666)
		(size 0.7112)
		(drill 0.3556)
		(layers "F.Cu" "B.Cu")
		(net "P2V5_STBY")
	)
	(via
		(at 160.1978 -25.527)
		(size 0.508)
		(drill 0.254)
		(layers "F.Cu" "B.Cu")
		(net "P2V5_STBY")
	)
	(via
		(at 166.787068 -38.46322)
		(size 0.508)
		(drill 0.254)
		(layers "F.Cu" "B.Cu")
		(net "P2V5_STBY")
	)
	(via
		(at 150.088092 -22.61743)
		(size 0.508)
		(drill 0.254)
		(layers "F.Cu" "B.Cu")
		(net "P2V5_STBY")
	)
	(via
		(at 167.767 -38.427406)
		(size 0.7112)
		(drill 0.3556)
		(layers "F.Cu" "B.Cu")
		(net "P2V5_STBY")
	)
	(segment
		(start 154.4066 -24.8666)
		(end 159.5374 -24.8666)
		(width 0.3048)
		(layer "B.Cu")
		(net "P2V5_STBY")
	)
	(segment
		(start 134.8232 -44.704)
		(end 134.8232 -45.466)
		(width 0.3048)
		(layer "B.Cu")
		(net "P2V5_STBY")
	)
	(segment
		(start 134.8232 -44.6278)
		(end 134.8232 -44.704)
		(width 0.3048)
		(layer "B.Cu")
		(net "P2V5_STBY")
	)
	(segment
		(start 136.305036 -43.145964)
		(end 134.8232 -44.6278)
		(width 0.3048)
		(layer "B.Cu")
		(net "P2V5_STBY")
	)
	(segment
		(start 139.4968 -39.9542)
		(end 136.305036 -43.145964)
		(width 0.3048)
		(layer "B.Cu")
		(net "P2V5_STBY")
	)
	(segment
		(start 134.8232 -45.466)
		(end 134.5946 -45.6946)
		(width 0.3048)
		(layer "B.Cu")
		(net "P2V5_STBY")
	)
	(segment
		(start 134.5946 -46.524418)
		(end 134.674356 -46.604174)
		(width 0.3048)
		(layer "B.Cu")
		(net "P2V5_STBY")
	)
	(segment
		(start 159.5374 -24.8666)
		(end 160.1978 -25.527)
		(width 0.3048)
		(layer "B.Cu")
		(net "P2V5_STBY")
	)
	(segment
		(start 154.90571 -38.46322)
		(end 153.41473 -39.9542)
		(width 0.3048)
		(layer "B.Cu")
		(net "P2V5_STBY")
	)
	(segment
		(start 150.088092 -22.61743)
		(end 152.337262 -24.8666)
		(width 0.3048)
		(layer "B.Cu")
		(net "P2V5_STBY")
	)
	(segment
		(start 152.337262 -24.8666)
		(end 154.4066 -24.8666)
		(width 0.3048)
		(layer "B.Cu")
		(net "P2V5_STBY")
	)
	(segment
		(start 134.5946 -45.6946)
		(end 134.5946 -46.524418)
		(width 0.3048)
		(layer "B.Cu")
		(net "P2V5_STBY")
	)
	(segment
		(start 153.41473 -39.9542)
		(end 139.4968 -39.9542)
		(width 0.3048)
		(layer "B.Cu")
		(net "P2V5_STBY")
	)
	(segment
		(start 166.787068 -38.46322)
		(end 154.90571 -38.46322)
		(width 0.3048)
		(layer "B.Cu")
		(net "P2V5_STBY")
	)
	(segment
		(start 55.57393 -51.058064)
		(end 55.045864 -51.058064)
		(width 0.254)
		(layer "F.Cu")
		(net "VR_EN_P1V0_STBY")
	)
	(segment
		(start 55.045864 -51.058064)
		(end 54.6354 -50.6476)
		(width 0.254)
		(layer "F.Cu")
		(net "VR_EN_P1V0_STBY")
	)
	(via
		(at 54.6354 -50.6476)
		(size 0.508)
		(drill 0.254)
		(layers "F.Cu" "B.Cu")
		(net "VR_EN_P1V0_STBY")
	)
	(via
		(at 55.6768 -51.4096)
		(size 0.7112)
		(drill 0.3556)
		(layers "F.Cu" "B.Cu")
		(net "VR_EN_P1V0_STBY")
	)
	(segment
		(start 55.3974 -50.3936)
		(end 54.8894 -50.3936)
		(width 0.254)
		(layer "B.Cu")
		(net "VR_EN_P1V0_STBY")
	)
	(segment
		(start 54.8894 -50.3936)
		(end 54.6354 -50.6476)
		(width 0.254)
		(layer "B.Cu")
		(net "VR_EN_P1V0_STBY")
	)
	(segment
		(start 55.6768 -50.673)
		(end 55.3974 -50.3936)
		(width 0.254)
		(layer "B.Cu")
		(net "VR_EN_P1V0_STBY")
	)
	(segment
		(start 55.6768 -51.4096)
		(end 55.6768 -50.673)
		(width 0.254)
		(layer "B.Cu")
		(net "VR_EN_P1V0_STBY")
	)
	(segment
		(start 55.5244 -53.9242)
		(end 56.261 -53.9242)
		(width 0.254)
		(layer "F.Cu")
		(net "VR_FB_R_P1V0_STBY")
	)
	(segment
		(start 57.404 -54.7878)
		(end 57.15381 -54.7878)
		(width 0.254)
		(layer "F.Cu")
		(net "VR_FB_R_P1V0_STBY")
	)
	(segment
		(start 57.15381 -54.7878)
		(end 56.29021 -53.9242)
		(width 0.254)
		(layer "F.Cu")
		(net "VR_FB_R_P1V0_STBY")
	)
	(segment
		(start 55.499 -53.8988)
		(end 55.5244 -53.9242)
		(width 0.254)
		(layer "F.Cu")
		(net "VR_FB_R_P1V0_STBY")
	)
	(segment
		(start 59.4614 -54.7878)
		(end 57.404 -54.7878)
		(width 0.254)
		(layer "F.Cu")
		(net "VR_FB_R_P1V0_STBY")
	)
	(segment
		(start 56.29021 -53.9242)
		(end 56.261 -53.9242)
		(width 0.254)
		(layer "F.Cu")
		(net "VR_FB_R_P1V0_STBY")
	)
	(via
		(at 59.4614 -54.7878)
		(size 0.7112)
		(drill 0.3556)
		(layers "F.Cu" "B.Cu")
		(net "VR_FB_R_P1V0_STBY")
	)
	(segment
		(start 56.261 -54.7878)
		(end 56.2356 -54.8132)
		(width 0.254)
		(layer "F.Cu")
		(net "VR_FB_P1V0_STBY")
	)
	(segment
		(start 56.2356 -54.8132)
		(end 55.499 -54.8132)
		(width 0.254)
		(layer "F.Cu")
		(net "VR_FB_P1V0_STBY")
	)
	(segment
		(start 54.737 -55.626)
		(end 54.737 -54.7878)
		(width 0.254)
		(layer "F.Cu")
		(net "VR_FB_P1V0_STBY")
	)
	(segment
		(start 54.737 -54.7878)
		(end 55.4736 -54.7878)
		(width 0.254)
		(layer "F.Cu")
		(net "VR_FB_P1V0_STBY")
	)
	(segment
		(start 55.4736 -54.7878)
		(end 55.499 -54.8132)
		(width 0.254)
		(layer "F.Cu")
		(net "VR_FB_P1V0_STBY")
	)
	(segment
		(start 54.864 -55.753)
		(end 54.737 -55.626)
		(width 0.254)
		(layer "F.Cu")
		(net "VR_FB_P1V0_STBY")
	)
	(segment
		(start 58.21807 -52.058062)
		(end 58.891678 -52.058062)
		(width 0.254)
		(layer "F.Cu")
		(net "VR_FB_P1V0_STBY")
	)
	(segment
		(start 58.891678 -52.058062)
		(end 59.07024 -51.8795)
		(width 0.254)
		(layer "F.Cu")
		(net "VR_FB_P1V0_STBY")
	)
	(via
		(at 54.864 -55.753)
		(size 0.508)
		(drill 0.254)
		(layers "F.Cu" "B.Cu")
		(net "VR_FB_P1V0_STBY")
	)
	(via
		(at 56.007 -56.134)
		(size 0.7112)
		(drill 0.3556)
		(layers "F.Cu" "B.Cu")
		(net "VR_FB_P1V0_STBY")
	)
	(via
		(at 59.07024 -51.8795)
		(size 0.508)
		(drill 0.254)
		(layers "F.Cu" "B.Cu")
		(net "VR_FB_P1V0_STBY")
	)
	(segment
		(start 56.007 -56.134)
		(end 55.245 -56.134)
		(width 0.254)
		(layer "B.Cu")
		(net "VR_FB_P1V0_STBY")
	)
	(segment
		(start 55.245 -56.134)
		(end 54.864 -55.753)
		(width 0.254)
		(layer "B.Cu")
		(net "VR_FB_P1V0_STBY")
	)
	(segment
		(start 54.864 -55.753)
		(end 55.232554 -55.753)
		(width 0.254)
		(layer "In4.Cu")
		(net "VR_FB_P1V0_STBY")
	)
	(segment
		(start 59.07024 -51.915314)
		(end 59.07024 -51.8795)
		(width 0.254)
		(layer "In4.Cu")
		(net "VR_FB_P1V0_STBY")
	)
	(segment
		(start 55.232554 -55.753)
		(end 59.07024 -51.915314)
		(width 0.254)
		(layer "In4.Cu")
		(net "VR_FB_P1V0_STBY")
	)
	(segment
		(start 54.115716 -51.474116)
		(end 53.2892 -50.6476)
		(width 0.3048)
		(layer "F.Cu")
		(net "VR_AVIN_P1V0_STBY")
	)
	(segment
		(start 53.5432 -49.7078)
		(end 53.5432 -50.3174)
		(width 0.508)
		(layer "F.Cu")
		(net "VR_AVIN_P1V0_STBY")
	)
	(segment
		(start 56.095138 -52.058062)
		(end 56.595264 -51.557936)
		(width 0.3048)
		(layer "F.Cu")
		(net "VR_AVIN_P1V0_STBY")
	)
	(segment
		(start 55.57393 -52.058062)
		(end 56.095138 -52.058062)
		(width 0.3048)
		(layer "F.Cu")
		(net "VR_AVIN_P1V0_STBY")
	)
	(segment
		(start 55.061104 -52.091336)
		(end 54.486556 -52.091336)
		(width 0.3048)
		(layer "F.Cu")
		(net "VR_AVIN_P1V0_STBY")
	)
	(segment
		(start 55.57393 -52.058062)
		(end 55.094378 -52.058062)
		(width 0.3048)
		(layer "F.Cu")
		(net "VR_AVIN_P1V0_STBY")
	)
	(segment
		(start 56.595264 -51.557936)
		(end 58.21807 -51.557936)
		(width 0.3048)
		(layer "F.Cu")
		(net "VR_AVIN_P1V0_STBY")
	)
	(segment
		(start 53.213 -50.6476)
		(end 53.2892 -50.6476)
		(width 0.3048)
		(layer "F.Cu")
		(net "VR_AVIN_P1V0_STBY")
	)
	(segment
		(start 53.5432 -50.3174)
		(end 53.213 -50.6476)
		(width 0.508)
		(layer "F.Cu")
		(net "VR_AVIN_P1V0_STBY")
	)
	(segment
		(start 54.486556 -52.091336)
		(end 54.115716 -51.720496)
		(width 0.3048)
		(layer "F.Cu")
		(net "VR_AVIN_P1V0_STBY")
	)
	(segment
		(start 54.115716 -51.720496)
		(end 54.115716 -51.474116)
		(width 0.3048)
		(layer "F.Cu")
		(net "VR_AVIN_P1V0_STBY")
	)
	(segment
		(start 55.094378 -52.058062)
		(end 55.061104 -52.091336)
		(width 0.3048)
		(layer "F.Cu")
		(net "VR_AVIN_P1V0_STBY")
	)
	(via
		(at 52.4002 -48.9966)
		(size 0.7112)
		(drill 0.3556)
		(layers "F.Cu" "B.Cu")
		(net "VR_PVIN_P1V0_STBY")
	)
	(segment
		(start 87.63 -12.192)
		(end 85.217 -12.192)
		(width 0.1143)
		(layer "F.Cu")
		(net "PCIE_RESET#")
	)
	(segment
		(start 83.668108 -12.139168)
		(end 83.668108 -12.504674)
		(width 0.1143)
		(layer "F.Cu")
		(net "PCIE_RESET#")
	)
	(segment
		(start 81.534 -13.716)
		(end 79.756 -13.716)
		(width 0.1143)
		(layer "F.Cu")
		(net "PCIE_RESET#")
	)
	(segment
		(start 78.4098 -13.716)
		(end 79.756 -13.716)
		(width 0.1143)
		(layer "F.Cu")
		(net "PCIE_RESET#")
	)
	(segment
		(start 85.217 -12.192)
		(end 84.8741 -11.8491)
		(width 0.1143)
		(layer "F.Cu")
		(net "PCIE_RESET#")
	)
	(segment
		(start 84.8741 -11.8491)
		(end 83.958176 -11.8491)
		(width 0.1143)
		(layer "F.Cu")
		(net "PCIE_RESET#")
	)
	(segment
		(start 83.668108 -12.504674)
		(end 83.364832 -12.80795)
		(width 0.1143)
		(layer "F.Cu")
		(net "PCIE_RESET#")
	)
	(segment
		(start 83.958176 -11.8491)
		(end 83.668108 -12.139168)
		(width 0.1143)
		(layer "F.Cu")
		(net "PCIE_RESET#")
	)
	(segment
		(start 88.619076 -11.202924)
		(end 87.63 -12.192)
		(width 0.1143)
		(layer "F.Cu")
		(net "PCIE_RESET#")
	)
	(segment
		(start 88.619076 -9.117076)
		(end 88.619076 -11.202924)
		(width 0.1143)
		(layer "F.Cu")
		(net "PCIE_RESET#")
	)
	(segment
		(start 83.364832 -12.80795)
		(end 82.44205 -12.80795)
		(width 0.1143)
		(layer "F.Cu")
		(net "PCIE_RESET#")
	)
	(segment
		(start 88.35009 -6.195568)
		(end 88.35009 -8.84809)
		(width 0.1143)
		(layer "F.Cu")
		(net "PCIE_RESET#")
	)
	(segment
		(start 88.35009 -8.84809)
		(end 88.619076 -9.117076)
		(width 0.1143)
		(layer "F.Cu")
		(net "PCIE_RESET#")
	)
	(segment
		(start 82.44205 -12.80795)
		(end 81.534 -13.716)
		(width 0.1143)
		(layer "F.Cu")
		(net "PCIE_RESET#")
	)
	(via
		(at 79.756 -13.716)
		(size 0.7112)
		(drill 0.3556)
		(layers "F.Cu" "B.Cu")
		(net "PCIE_RESET#")
	)
	(segment
		(start 81.86801 -23.4696)
		(end 82.07248 -23.4696)
		(width 0.1143)
		(layer "F.Cu")
		(net "CPU_RXD")
	)
	(segment
		(start 80.96631 -24.3713)
		(end 81.86801 -23.4696)
		(width 0.1143)
		(layer "F.Cu")
		(net "CPU_RXD")
	)
	(segment
		(start 74.40295 -21.36775)
		(end 73.787 -20.7518)
		(width 0.1143)
		(layer "F.Cu")
		(net "CPU_RXD")
	)
	(segment
		(start 77.34935 -21.36775)
		(end 80.3529 -24.3713)
		(width 0.1143)
		(layer "F.Cu")
		(net "CPU_RXD")
	)
	(segment
		(start 80.3529 -24.3713)
		(end 80.96631 -24.3713)
		(width 0.1143)
		(layer "F.Cu")
		(net "CPU_RXD")
	)
	(segment
		(start 75.184 -21.36775)
		(end 77.34935 -21.36775)
		(width 0.1143)
		(layer "F.Cu")
		(net "CPU_RXD")
	)
	(segment
		(start 71.882 -21.082)
		(end 71.38924 -20.58924)
		(width 0.1143)
		(layer "F.Cu")
		(net "CPU_RXD")
	)
	(segment
		(start 73.4568 -21.082)
		(end 71.882 -21.082)
		(width 0.1143)
		(layer "F.Cu")
		(net "CPU_RXD")
	)
	(segment
		(start 75.184 -21.36775)
		(end 74.40295 -21.36775)
		(width 0.1143)
		(layer "F.Cu")
		(net "CPU_RXD")
	)
	(segment
		(start 73.787 -20.7518)
		(end 73.4568 -21.082)
		(width 0.1143)
		(layer "F.Cu")
		(net "CPU_RXD")
	)
	(segment
		(start 71.38924 -20.58924)
		(end 71.0565 -20.58924)
		(width 0.1143)
		(layer "F.Cu")
		(net "CPU_RXD")
	)
	(via
		(at 75.184 -21.36775)
		(size 0.7112)
		(drill 0.3556)
		(layers "F.Cu" "B.Cu")
		(net "CPU_RXD")
	)
	(via
		(at 82.07248 -23.4696)
		(size 0.4318)
		(drill 0.2032)
		(layers "F.Cu" "B.Cu")
		(net "CPU_RXD")
	)
	(segment
		(start 82.423 -24.0792)
		(end 82.07248 -23.72868)
		(width 0.1143)
		(layer "B.Cu")
		(net "CPU_RXD")
	)
	(segment
		(start 82.07248 -23.72868)
		(end 82.07248 -23.4696)
		(width 0.1143)
		(layer "B.Cu")
		(net "CPU_RXD")
	)
	(segment
		(start 80.4672 -24.1554)
		(end 79.35976 -23.04796)
		(width 0.1143)
		(layer "F.Cu")
		(net "CPU_TXD")
	)
	(segment
		(start 81.09585 -23.935944)
		(end 80.876394 -24.1554)
		(width 0.1143)
		(layer "F.Cu")
		(net "CPU_TXD")
	)
	(segment
		(start 81.09585 -23.536656)
		(end 81.09585 -23.935944)
		(width 0.1143)
		(layer "F.Cu")
		(net "CPU_TXD")
	)
	(segment
		(start 81.15808 -23.474426)
		(end 81.09585 -23.536656)
		(width 0.1143)
		(layer "F.Cu")
		(net "CPU_TXD")
	)
	(segment
		(start 72.3138 -19.1008)
		(end 72.50176 -19.28876)
		(width 0.1143)
		(layer "F.Cu")
		(net "CPU_TXD")
	)
	(segment
		(start 80.876394 -24.1554)
		(end 80.4672 -24.1554)
		(width 0.1143)
		(layer "F.Cu")
		(net "CPU_TXD")
	)
	(segment
		(start 77.703934 -19.28876)
		(end 75.184 -19.28876)
		(width 0.1143)
		(layer "F.Cu")
		(net "CPU_TXD")
	)
	(segment
		(start 79.35976 -20.944586)
		(end 77.703934 -19.28876)
		(width 0.1143)
		(layer "F.Cu")
		(net "CPU_TXD")
	)
	(segment
		(start 79.35976 -23.04796)
		(end 79.35976 -20.944586)
		(width 0.1143)
		(layer "F.Cu")
		(net "CPU_TXD")
	)
	(segment
		(start 75.184 -19.28876)
		(end 72.7075 -19.28876)
		(width 0.1143)
		(layer "F.Cu")
		(net "CPU_TXD")
	)
	(segment
		(start 72.50176 -19.28876)
		(end 72.7075 -19.28876)
		(width 0.1143)
		(layer "F.Cu")
		(net "CPU_TXD")
	)
	(segment
		(start 72.3138 -18.288)
		(end 72.3138 -19.1008)
		(width 0.1143)
		(layer "F.Cu")
		(net "CPU_TXD")
	)
	(via
		(at 81.15808 -23.474426)
		(size 0.4318)
		(drill 0.2032)
		(layers "F.Cu" "B.Cu")
		(net "CPU_TXD")
	)
	(via
		(at 75.184 -19.28876)
		(size 0.7112)
		(drill 0.3556)
		(layers "F.Cu" "B.Cu")
		(net "CPU_TXD")
	)
	(segment
		(start 81.661 -23.977346)
		(end 81.15808 -23.474426)
		(width 0.1143)
		(layer "B.Cu")
		(net "CPU_TXD")
	)
	(segment
		(start 81.661 -24.0792)
		(end 81.661 -23.977346)
		(width 0.1143)
		(layer "B.Cu")
		(net "CPU_TXD")
	)
	(segment
		(start 26.5176 -68.199)
		(end 26.5176 -67.0814)
		(width 0.508)
		(layer "F.Cu")
		(net "VCCP_Z")
	)
	(segment
		(start 25.067514 -69.2404)
		(end 24.483314 -68.6562)
		(width 0.508)
		(layer "F.Cu")
		(net "VCCP_Z")
	)
	(segment
		(start 25.7556 -69.2404)
		(end 25.067514 -69.2404)
		(width 0.508)
		(layer "F.Cu")
		(net "VCCP_Z")
	)
	(segment
		(start 26.5176 -68.199)
		(end 26.5176 -68.4784)
		(width 0.508)
		(layer "F.Cu")
		(net "VCCP_Z")
	)
	(segment
		(start 26.5176 -67.0814)
		(end 26.5938 -67.0052)
		(width 0.508)
		(layer "F.Cu")
		(net "VCCP_Z")
	)
	(segment
		(start 26.5176 -68.4784)
		(end 25.7556 -69.2404)
		(width 0.508)
		(layer "F.Cu")
		(net "VCCP_Z")
	)
	(via
		(at 25.7556 -69.2404)
		(size 0.7112)
		(drill 0.3556)
		(layers "F.Cu" "B.Cu")
		(net "VCCP_Z")
	)
	(segment
		(start 194.7418 -37.0586)
		(end 195.057776 -37.0586)
		(width 0.4572)
		(layer "F.Cu")
		(net "VDDR_5VBIAS")
	)
	(segment
		(start 195.057776 -37.0586)
		(end 195.9102 -36.206176)
		(width 0.4572)
		(layer "F.Cu")
		(net "VDDR_5VBIAS")
	)
	(segment
		(start 195.9102 -36.206176)
		(end 195.9102 -35.6108)
		(width 0.4572)
		(layer "F.Cu")
		(net "VDDR_5VBIAS")
	)
	(via
		(at 192.1256 -28.067)
		(size 0.5588)
		(drill 0.3048)
		(layers "F.Cu" "B.Cu")
		(net "VDDR_5VBIAS")
	)
	(via
		(at 195.7324 -39.0398)
		(size 0.7112)
		(drill 0.3556)
		(layers "F.Cu" "B.Cu")
		(net "VDDR_5VBIAS")
	)
	(via
		(at 195.9102 -35.6108)
		(size 0.508)
		(drill 0.254)
		(layers "F.Cu" "B.Cu")
		(net "VDDR_5VBIAS")
	)
	(segment
		(start 191.5668 -27.5082)
		(end 192.1256 -28.067)
		(width 0.508)
		(layer "B.Cu")
		(net "VDDR_5VBIAS")
	)
	(segment
		(start 195.7578 -39.0144)
		(end 195.7324 -39.0398)
		(width 0.508)
		(layer "B.Cu")
		(net "VDDR_5VBIAS")
	)
	(segment
		(start 196.215 -35.306)
		(end 196.9262 -35.306)
		(width 0.508)
		(layer "B.Cu")
		(net "VDDR_5VBIAS")
	)
	(segment
		(start 190.881 -27.5082)
		(end 191.5668 -27.5082)
		(width 0.508)
		(layer "B.Cu")
		(net "VDDR_5VBIAS")
	)
	(segment
		(start 196.6722 -37.9984)
		(end 197.358 -37.3126)
		(width 0.508)
		(layer "B.Cu")
		(net "VDDR_5VBIAS")
	)
	(segment
		(start 195.7578 -37.9984)
		(end 195.7578 -39.0144)
		(width 0.508)
		(layer "B.Cu")
		(net "VDDR_5VBIAS")
	)
	(segment
		(start 197.358 -37.3126)
		(end 196.9262 -36.8808)
		(width 0.508)
		(layer "B.Cu")
		(net "VDDR_5VBIAS")
	)
	(segment
		(start 196.9262 -36.8808)
		(end 196.9262 -35.306)
		(width 0.508)
		(layer "B.Cu")
		(net "VDDR_5VBIAS")
	)
	(segment
		(start 195.7578 -37.9984)
		(end 196.6722 -37.9984)
		(width 0.508)
		(layer "B.Cu")
		(net "VDDR_5VBIAS")
	)
	(segment
		(start 195.9102 -35.6108)
		(end 196.215 -35.306)
		(width 0.508)
		(layer "B.Cu")
		(net "VDDR_5VBIAS")
	)
	(segment
		(start 195.9102 -35.349942)
		(end 195.9102 -35.6108)
		(width 0.508)
		(layer "In7.Cu")
		(net "VDDR_5VBIAS")
	)
	(segment
		(start 192.1256 -28.067)
		(end 192.2018 -28.067)
		(width 0.508)
		(layer "In7.Cu")
		(net "VDDR_5VBIAS")
	)
	(segment
		(start 194.818 -34.257742)
		(end 195.9102 -35.349942)
		(width 0.508)
		(layer "In7.Cu")
		(net "VDDR_5VBIAS")
	)
	(segment
		(start 194.818 -32.639)
		(end 194.818 -34.257742)
		(width 0.508)
		(layer "In7.Cu")
		(net "VDDR_5VBIAS")
	)
	(segment
		(start 192.2018 -28.067)
		(end 192.532 -28.3972)
		(width 0.508)
		(layer "In7.Cu")
		(net "VDDR_5VBIAS")
	)
	(segment
		(start 192.532 -28.3972)
		(end 192.532 -30.353)
		(width 0.508)
		(layer "In7.Cu")
		(net "VDDR_5VBIAS")
	)
	(segment
		(start 192.532 -30.353)
		(end 194.818 -32.639)
		(width 0.508)
		(layer "In7.Cu")
		(net "VDDR_5VBIAS")
	)
	(via
		(at 192.278 -37.846)
		(size 0.7112)
		(drill 0.3556)
		(layers "F.Cu" "B.Cu")
		(net "VDDR_Z")
	)
	(segment
		(start 193.548 -37.9984)
		(end 193.548 -39.285926)
		(width 0.508)
		(layer "B.Cu")
		(net "VDDR_Z")
	)
	(segment
		(start 193.548 -37.9984)
		(end 194.7418 -37.9984)
		(width 0.508)
		(layer "B.Cu")
		(net "VDDR_Z")
	)
	(segment
		(start 193.3956 -37.846)
		(end 193.548 -37.9984)
		(width 0.508)
		(layer "B.Cu")
		(net "VDDR_Z")
	)
	(segment
		(start 192.278 -37.846)
		(end 193.3956 -37.846)
		(width 0.508)
		(layer "B.Cu")
		(net "VDDR_Z")
	)
	(segment
		(start 46.906434 -59.436)
		(end 49.53 -59.436)
		(width 0.508)
		(layer "F.Cu")
		(net "VR_PVCCP_PWM_OUT")
	)
	(via
		(at 49.53 -59.436)
		(size 0.508)
		(drill 0.254)
		(layers "F.Cu" "B.Cu")
		(net "VR_PVCCP_PWM_OUT")
	)
	(via
		(at 48.768 -59.436)
		(size 0.7112)
		(drill 0.3556)
		(layers "F.Cu" "B.Cu")
		(net "VR_PVCCP_PWM_OUT")
	)
	(segment
		(start 48.768 -59.436)
		(end 49.53 -59.436)
		(width 0.3048)
		(layer "B.Cu")
		(net "VR_PVCCP_PWM_OUT")
	)
	(segment
		(start 49.6062 -58.547)
		(end 49.6062 -59.3598)
		(width 0.508)
		(layer "B.Cu")
		(net "VR_PVCCP_PWM_OUT")
	)
	(segment
		(start 49.6062 -59.3598)
		(end 49.53 -59.436)
		(width 0.508)
		(layer "B.Cu")
		(net "VR_PVCCP_PWM_OUT")
	)
	(segment
		(start 167.486584 -62.59322)
		(end 167.496998 -62.582806)
		(width 0.1778)
		(layer "F.Cu")
		(net "M_A_ECC1")
	)
	(segment
		(start 114.6302 -48.006)
		(end 114.408712 -47.784512)
		(width 0.1016)
		(layer "F.Cu")
		(net "M_A_ECC1")
	)
	(segment
		(start 111.694214 -45.595794)
		(end 111.491268 -45.595794)
		(width 0.1016)
		(layer "F.Cu")
		(net "M_A_ECC1")
	)
	(segment
		(start 111.780574 -45.6819)
		(end 111.694214 -45.595794)
		(width 0.1016)
		(layer "F.Cu")
		(net "M_A_ECC1")
	)
	(segment
		(start 114.408712 -47.784512)
		(end 112.37087 -45.746924)
		(width 0.1016)
		(layer "F.Cu")
		(net "M_A_ECC1")
	)
	(segment
		(start 112.37087 -45.746924)
		(end 111.845598 -45.746924)
		(width 0.1016)
		(layer "F.Cu")
		(net "M_A_ECC1")
	)
	(segment
		(start 117.475 -48.006)
		(end 114.6302 -48.006)
		(width 0.1016)
		(layer "F.Cu")
		(net "M_A_ECC1")
	)
	(segment
		(start 111.845598 -45.746924)
		(end 111.780574 -45.6819)
		(width 0.1016)
		(layer "F.Cu")
		(net "M_A_ECC1")
	)
	(segment
		(start 165.850062 -62.59322)
		(end 167.486584 -62.59322)
		(width 0.1778)
		(layer "F.Cu")
		(net "M_A_ECC1")
	)
	(via
		(at 167.496998 -62.582806)
		(size 0.4318)
		(drill 0.2032)
		(layers "F.Cu" "B.Cu")
		(net "M_A_ECC1")
	)
	(via
		(at 117.475 -48.006)
		(size 0.4318)
		(drill 0.2032)
		(layers "F.Cu" "B.Cu")
		(net "M_A_ECC1")
	)
	(segment
		(start 169.15003 -62.599824)
		(end 167.514016 -62.599824)
		(width 0.1778)
		(layer "B.Cu")
		(net "M_A_ECC1")
	)
	(segment
		(start 167.514016 -62.599824)
		(end 167.496998 -62.582806)
		(width 0.1778)
		(layer "B.Cu")
		(net "M_A_ECC1")
	)
	(segment
		(start 149.398482 -51.481482)
		(end 149.613874 -51.481482)
		(width 0.1524)
		(layer "In2.Cu")
		(net "M_A_ECC1")
	)
	(segment
		(start 154.393138 -53.2384)
		(end 154.545538 -53.086)
		(width 0.1524)
		(layer "In2.Cu")
		(net "M_A_ECC1")
	)
	(segment
		(start 150.451058 -52.369466)
		(end 150.908766 -51.911758)
		(width 0.1524)
		(layer "In2.Cu")
		(net "M_A_ECC1")
	)
	(segment
		(start 152.2984 -54.1528)
		(end 153.383234 -54.1528)
		(width 0.1524)
		(layer "In2.Cu")
		(net "M_A_ECC1")
	)
	(segment
		(start 150.89505 -52.788058)
		(end 150.89505 -53.00345)
		(width 0.1524)
		(layer "In2.Cu")
		(net "M_A_ECC1")
	)
	(segment
		(start 120.691656 -48.631856)
		(end 144.355312 -48.631856)
		(width 0.1524)
		(layer "In2.Cu")
		(net "M_A_ECC1")
	)
	(segment
		(start 155.764738 -53.086)
		(end 156.069538 -53.086)
		(width 0.1524)
		(layer "In2.Cu")
		(net "M_A_ECC1")
	)
	(segment
		(start 151.340058 -52.127658)
		(end 151.340058 -52.34305)
		(width 0.1524)
		(layer "In2.Cu")
		(net "M_A_ECC1")
	)
	(segment
		(start 120.691656 -48.631856)
		(end 119.634 -47.5742)
		(width 0.1016)
		(layer "In2.Cu")
		(net "M_A_ECC1")
	)
	(segment
		(start 149.61489 -50.40249)
		(end 149.61489 -50.617882)
		(width 0.1524)
		(layer "In2.Cu")
		(net "M_A_ECC1")
	)
	(segment
		(start 156.831538 -53.2384)
		(end 156.983938 -53.086)
		(width 0.1524)
		(layer "In2.Cu")
		(net "M_A_ECC1")
	)
	(segment
		(start 150.908766 -51.911758)
		(end 151.124158 -51.911758)
		(width 0.1524)
		(layer "In2.Cu")
		(net "M_A_ECC1")
	)
	(segment
		(start 156.221938 -53.7464)
		(end 156.374338 -53.8988)
		(width 0.1524)
		(layer "In2.Cu")
		(net "M_A_ECC1")
	)
	(segment
		(start 144.355312 -48.631856)
		(end 145.202656 -49.4792)
		(width 0.1524)
		(layer "In2.Cu")
		(net "M_A_ECC1")
	)
	(segment
		(start 156.679138 -53.8988)
		(end 156.831538 -53.7464)
		(width 0.1524)
		(layer "In2.Cu")
		(net "M_A_ECC1")
	)
	(segment
		(start 150.477474 -51.265074)
		(end 150.477474 -51.480466)
		(width 0.1524)
		(layer "In2.Cu")
		(net "M_A_ECC1")
	)
	(segment
		(start 151.884634 -53.739034)
		(end 152.2984 -54.1528)
		(width 0.1524)
		(layer "In2.Cu")
		(net "M_A_ECC1")
	)
	(segment
		(start 157.288738 -53.086)
		(end 157.441138 -53.2384)
		(width 0.1524)
		(layer "In2.Cu")
		(net "M_A_ECC1")
	)
	(segment
		(start 156.831538 -53.7464)
		(end 156.831538 -53.2384)
		(width 0.1524)
		(layer "In2.Cu")
		(net "M_A_ECC1")
	)
	(segment
		(start 153.637488 -53.8988)
		(end 154.240738 -53.8988)
		(width 0.1524)
		(layer "In2.Cu")
		(net "M_A_ECC1")
	)
	(segment
		(start 151.326342 -53.21935)
		(end 151.77135 -52.774342)
		(width 0.1524)
		(layer "In2.Cu")
		(net "M_A_ECC1")
	)
	(segment
		(start 151.77135 -52.774342)
		(end 151.986742 -52.774342)
		(width 0.1524)
		(layer "In2.Cu")
		(net "M_A_ECC1")
	)
	(segment
		(start 150.019766 -52.153566)
		(end 150.235666 -52.369466)
		(width 0.1524)
		(layer "In2.Cu")
		(net "M_A_ECC1")
	)
	(segment
		(start 149.182582 -51.265582)
		(end 149.398482 -51.481482)
		(width 0.1524)
		(layer "In2.Cu")
		(net "M_A_ECC1")
	)
	(segment
		(start 150.477474 -51.480466)
		(end 150.019766 -51.938174)
		(width 0.1524)
		(layer "In2.Cu")
		(net "M_A_ECC1")
	)
	(segment
		(start 152.202642 -53.205634)
		(end 151.884634 -53.523642)
		(width 0.1524)
		(layer "In2.Cu")
		(net "M_A_ECC1")
	)
	(segment
		(start 145.202656 -49.4792)
		(end 147.6248 -49.4792)
		(width 0.1524)
		(layer "In2.Cu")
		(net "M_A_ECC1")
	)
	(segment
		(start 150.235666 -52.369466)
		(end 150.451058 -52.369466)
		(width 0.1524)
		(layer "In2.Cu")
		(net "M_A_ECC1")
	)
	(segment
		(start 156.983938 -53.086)
		(end 157.288738 -53.086)
		(width 0.1524)
		(layer "In2.Cu")
		(net "M_A_ECC1")
	)
	(segment
		(start 150.89505 -53.00345)
		(end 151.11095 -53.21935)
		(width 0.1524)
		(layer "In2.Cu")
		(net "M_A_ECC1")
	)
	(segment
		(start 155.002738 -53.2384)
		(end 155.002738 -53.7464)
		(width 0.1524)
		(layer "In2.Cu")
		(net "M_A_ECC1")
	)
	(segment
		(start 149.61489 -50.617882)
		(end 149.182582 -51.05019)
		(width 0.1524)
		(layer "In2.Cu")
		(net "M_A_ECC1")
	)
	(segment
		(start 157.441138 -53.7464)
		(end 157.593538 -53.8988)
		(width 0.1524)
		(layer "In2.Cu")
		(net "M_A_ECC1")
	)
	(segment
		(start 157.441138 -53.2384)
		(end 157.441138 -53.7464)
		(width 0.1524)
		(layer "In2.Cu")
		(net "M_A_ECC1")
	)
	(segment
		(start 150.261574 -51.049174)
		(end 150.477474 -51.265074)
		(width 0.1524)
		(layer "In2.Cu")
		(net "M_A_ECC1")
	)
	(segment
		(start 154.393138 -53.7464)
		(end 154.393138 -53.2384)
		(width 0.1524)
		(layer "In2.Cu")
		(net "M_A_ECC1")
	)
	(segment
		(start 160.897062 -53.8988)
		(end 167.496998 -60.498736)
		(width 0.1524)
		(layer "In2.Cu")
		(net "M_A_ECC1")
	)
	(segment
		(start 154.850338 -53.086)
		(end 155.002738 -53.2384)
		(width 0.1524)
		(layer "In2.Cu")
		(net "M_A_ECC1")
	)
	(segment
		(start 151.986742 -52.774342)
		(end 152.202642 -52.990242)
		(width 0.1524)
		(layer "In2.Cu")
		(net "M_A_ECC1")
	)
	(segment
		(start 149.182582 -51.05019)
		(end 149.182582 -51.265582)
		(width 0.1524)
		(layer "In2.Cu")
		(net "M_A_ECC1")
	)
	(segment
		(start 151.11095 -53.21935)
		(end 151.326342 -53.21935)
		(width 0.1524)
		(layer "In2.Cu")
		(net "M_A_ECC1")
	)
	(segment
		(start 151.884634 -53.523642)
		(end 151.884634 -53.739034)
		(width 0.1524)
		(layer "In2.Cu")
		(net "M_A_ECC1")
	)
	(segment
		(start 156.221938 -53.2384)
		(end 156.221938 -53.7464)
		(width 0.1524)
		(layer "In2.Cu")
		(net "M_A_ECC1")
	)
	(segment
		(start 150.046182 -51.049174)
		(end 150.261574 -51.049174)
		(width 0.1524)
		(layer "In2.Cu")
		(net "M_A_ECC1")
	)
	(segment
		(start 154.545538 -53.086)
		(end 154.850338 -53.086)
		(width 0.1524)
		(layer "In2.Cu")
		(net "M_A_ECC1")
	)
	(segment
		(start 148.86559 -50.504598)
		(end 149.183598 -50.18659)
		(width 0.1524)
		(layer "In2.Cu")
		(net "M_A_ECC1")
	)
	(segment
		(start 156.069538 -53.086)
		(end 156.221938 -53.2384)
		(width 0.1524)
		(layer "In2.Cu")
		(net "M_A_ECC1")
	)
	(segment
		(start 155.155138 -53.8988)
		(end 155.459938 -53.8988)
		(width 0.1524)
		(layer "In2.Cu")
		(net "M_A_ECC1")
	)
	(segment
		(start 149.183598 -50.18659)
		(end 149.39899 -50.18659)
		(width 0.1524)
		(layer "In2.Cu")
		(net "M_A_ECC1")
	)
	(segment
		(start 151.124158 -51.911758)
		(end 151.340058 -52.127658)
		(width 0.1524)
		(layer "In2.Cu")
		(net "M_A_ECC1")
	)
	(segment
		(start 117.9068 -47.5742)
		(end 117.475 -48.006)
		(width 0.1016)
		(layer "In2.Cu")
		(net "M_A_ECC1")
	)
	(segment
		(start 155.002738 -53.7464)
		(end 155.155138 -53.8988)
		(width 0.1524)
		(layer "In2.Cu")
		(net "M_A_ECC1")
	)
	(segment
		(start 156.374338 -53.8988)
		(end 156.679138 -53.8988)
		(width 0.1524)
		(layer "In2.Cu")
		(net "M_A_ECC1")
	)
	(segment
		(start 154.240738 -53.8988)
		(end 154.393138 -53.7464)
		(width 0.1524)
		(layer "In2.Cu")
		(net "M_A_ECC1")
	)
	(segment
		(start 148.650198 -50.504598)
		(end 148.86559 -50.504598)
		(width 0.1524)
		(layer "In2.Cu")
		(net "M_A_ECC1")
	)
	(segment
		(start 153.383234 -54.1528)
		(end 153.637488 -53.8988)
		(width 0.1524)
		(layer "In2.Cu")
		(net "M_A_ECC1")
	)
	(segment
		(start 150.019766 -51.938174)
		(end 150.019766 -52.153566)
		(width 0.1524)
		(layer "In2.Cu")
		(net "M_A_ECC1")
	)
	(segment
		(start 157.593538 -53.8988)
		(end 160.897062 -53.8988)
		(width 0.1524)
		(layer "In2.Cu")
		(net "M_A_ECC1")
	)
	(segment
		(start 167.496998 -60.498736)
		(end 167.496998 -62.582806)
		(width 0.1524)
		(layer "In2.Cu")
		(net "M_A_ECC1")
	)
	(segment
		(start 151.340058 -52.34305)
		(end 150.89505 -52.788058)
		(width 0.1524)
		(layer "In2.Cu")
		(net "M_A_ECC1")
	)
	(segment
		(start 155.459938 -53.8988)
		(end 155.612338 -53.7464)
		(width 0.1524)
		(layer "In2.Cu")
		(net "M_A_ECC1")
	)
	(segment
		(start 155.612338 -53.7464)
		(end 155.612338 -53.2384)
		(width 0.1524)
		(layer "In2.Cu")
		(net "M_A_ECC1")
	)
	(segment
		(start 119.634 -47.5742)
		(end 117.9068 -47.5742)
		(width 0.1016)
		(layer "In2.Cu")
		(net "M_A_ECC1")
	)
	(segment
		(start 152.202642 -52.990242)
		(end 152.202642 -53.205634)
		(width 0.1524)
		(layer "In2.Cu")
		(net "M_A_ECC1")
	)
	(segment
		(start 149.39899 -50.18659)
		(end 149.61489 -50.40249)
		(width 0.1524)
		(layer "In2.Cu")
		(net "M_A_ECC1")
	)
	(segment
		(start 155.612338 -53.2384)
		(end 155.764738 -53.086)
		(width 0.1524)
		(layer "In2.Cu")
		(net "M_A_ECC1")
	)
	(segment
		(start 147.6248 -49.4792)
		(end 148.650198 -50.504598)
		(width 0.1524)
		(layer "In2.Cu")
		(net "M_A_ECC1")
	)
	(segment
		(start 149.613874 -51.481482)
		(end 150.046182 -51.049174)
		(width 0.1524)
		(layer "In2.Cu")
		(net "M_A_ECC1")
	)
	(segment
		(start 83.647788 -37.444934)
		(end 83.219798 -37.872924)
		(width 0.1143)
		(layer "F.Cu")
		(net "PMU_SUS_CLK_CPU")
	)
	(segment
		(start 83.219798 -37.872924)
		(end 83.15706 -37.872924)
		(width 0.1143)
		(layer "F.Cu")
		(net "PMU_SUS_CLK_CPU")
	)
	(via
		(at 83.15706 -37.872924)
		(size 0.4318)
		(drill 0.2032)
		(layers "F.Cu" "B.Cu")
		(net "PMU_SUS_CLK_CPU")
	)
	(via
		(at 81.3562 -37.2618)
		(size 0.7112)
		(drill 0.3556)
		(layers "F.Cu" "B.Cu")
		(net "PMU_SUS_CLK_CPU")
	)
	(segment
		(start 82.815176 -37.552376)
		(end 83.135724 -37.872924)
		(width 0.1143)
		(layer "B.Cu")
		(net "PMU_SUS_CLK_CPU")
	)
	(segment
		(start 83.135724 -37.872924)
		(end 83.15706 -37.872924)
		(width 0.1143)
		(layer "B.Cu")
		(net "PMU_SUS_CLK_CPU")
	)
	(segment
		(start 80.4418 -37.592)
		(end 80.772 -37.2618)
		(width 0.1143)
		(layer "B.Cu")
		(net "PMU_SUS_CLK_CPU")
	)
	(segment
		(start 81.818734 -37.724334)
		(end 82.273648 -37.724334)
		(width 0.1143)
		(layer "B.Cu")
		(net "PMU_SUS_CLK_CPU")
	)
	(segment
		(start 80.772 -37.2618)
		(end 81.3562 -37.2618)
		(width 0.1143)
		(layer "B.Cu")
		(net "PMU_SUS_CLK_CPU")
	)
	(segment
		(start 82.273648 -37.724334)
		(end 82.445606 -37.552376)
		(width 0.1143)
		(layer "B.Cu")
		(net "PMU_SUS_CLK_CPU")
	)
	(segment
		(start 82.445606 -37.552376)
		(end 82.815176 -37.552376)
		(width 0.1143)
		(layer "B.Cu")
		(net "PMU_SUS_CLK_CPU")
	)
	(segment
		(start 81.3562 -37.2618)
		(end 81.818734 -37.724334)
		(width 0.1143)
		(layer "B.Cu")
		(net "PMU_SUS_CLK_CPU")
	)
	(segment
		(start 51.711606 -32.280606)
		(end 52.67706 -33.24606)
		(width 0.254)
		(layer "F.Cu")
		(net "P3V3_CPU")
	)
	(segment
		(start 74.1172 -25.5524)
		(end 74.0918 -25.527)
		(width 0.3048)
		(layer "F.Cu")
		(net "P3V3_CPU")
	)
	(segment
		(start 51.494436 -35.525964)
		(end 50.897028 -35.525964)
		(width 0.254)
		(layer "F.Cu")
		(net "P3V3_CPU")
	)
	(segment
		(start 64.370458 -34.502344)
		(end 66.171572 -36.303458)
		(width 0.4572)
		(layer "F.Cu")
		(net "P3V3_CPU")
	)
	(segment
		(start 58.487056 -34.502344)
		(end 63.2714 -34.502344)
		(width 0.4572)
		(layer "F.Cu")
		(net "P3V3_CPU")
	)
	(segment
		(start 90.648028 -37.582602)
		(end 90.283538 -37.218112)
		(width 0.254)
		(layer "F.Cu")
		(net "P3V3_CPU")
	)
	(segment
		(start 73.2282 -29.972)
		(end 72.771 -30.4292)
		(width 0.3048)
		(layer "F.Cu")
		(net "P3V3_CPU")
	)
	(segment
		(start 66.949574 -36.303458)
		(end 67.603116 -36.957)
		(width 0.4572)
		(layer "F.Cu")
		(net "P3V3_CPU")
	)
	(segment
		(start 91.450668 -44.000674)
		(end 91.498674 -44.000674)
		(width 0.3048)
		(layer "F.Cu")
		(net "P3V3_CPU")
	)
	(segment
		(start 44.704 -47.117)
		(end 46.5328 -47.117)
		(width 0.508)
		(layer "F.Cu")
		(net "P3V3_CPU")
	)
	(segment
		(start 91.407488 -44.973494)
		(end 91.407488 -45.001688)
		(width 0.254)
		(layer "F.Cu")
		(net "P3V3_CPU")
	)
	(segment
		(start 57.912 -35.0774)
		(end 58.487056 -34.502344)
		(width 0.4572)
		(layer "F.Cu")
		(net "P3V3_CPU")
	)
	(segment
		(start 46.2788 -33.720024)
		(end 46.2788 -33.9598)
		(width 0.3048)
		(layer "F.Cu")
		(net "P3V3_CPU")
	)
	(segment
		(start 158.0896 -45.339)
		(end 158.0896 -45.9994)
		(width 0.3048)
		(layer "F.Cu")
		(net "P3V3_CPU")
	)
	(segment
		(start 54.570884 -26.2382)
		(end 55.771542 -25.037542)
		(width 0.3048)
		(layer "F.Cu")
		(net "P3V3_CPU")
	)
	(segment
		(start 74.0918 -26.416)
		(end 74.0918 -25.5778)
		(width 0.3048)
		(layer "F.Cu")
		(net "P3V3_CPU")
	)
	(segment
		(start 67.2211 -20.1549)
		(end 67.08775 -20.1549)
		(width 0.3048)
		(layer "F.Cu")
		(net "P3V3_CPU")
	)
	(segment
		(start 51.711606 -28.506674)
		(end 51.711606 -32.280606)
		(width 0.254)
		(layer "F.Cu")
		(net "P3V3_CPU")
	)
	(segment
		(start 50.727864 -35.3568)
		(end 50.1142 -35.3568)
		(width 0.254)
		(layer "F.Cu")
		(net "P3V3_CPU")
	)
	(segment
		(start 50.1142 -35.7632)
		(end 50.1142 -35.3568)
		(width 0.3048)
		(layer "F.Cu")
		(net "P3V3_CPU")
	)
	(segment
		(start 56.4388 -37.592)
		(end 56.1848 -37.846)
		(width 0.3048)
		(layer "F.Cu")
		(net "P3V3_CPU")
	)
	(segment
		(start 51.7525 -27.6733)
		(end 51.7525 -28.46578)
		(width 0.254)
		(layer "F.Cu")
		(net "P3V3_CPU")
	)
	(segment
		(start 90.648028 -37.599366)
		(end 90.648028 -37.582602)
		(width 0.254)
		(layer "F.Cu")
		(net "P3V3_CPU")
	)
	(segment
		(start 47.4726 -30.4546)
		(end 47.625 -30.607)
		(width 0.3048)
		(layer "F.Cu")
		(net "P3V3_CPU")
	)
	(segment
		(start 69.7992 -36.957)
		(end 69.7992 -36.3982)
		(width 0.508)
		(layer "F.Cu")
		(net "P3V3_CPU")
	)
	(segment
		(start 158.0896 -45.9994)
		(end 157.226 -46.863)
		(width 0.3048)
		(layer "F.Cu")
		(net "P3V3_CPU")
	)
	(segment
		(start 66.171572 -36.303458)
		(end 66.949574 -36.303458)
		(width 0.4572)
		(layer "F.Cu")
		(net "P3V3_CPU")
	)
	(segment
		(start 46.5328 -47.117)
		(end 46.609 -47.0408)
		(width 0.508)
		(layer "F.Cu")
		(net "P3V3_CPU")
	)
	(segment
		(start 73.533254 -34.492946)
		(end 73.6092 -34.417)
		(width 0.508)
		(layer "F.Cu")
		(net "P3V3_CPU")
	)
	(segment
		(start 91.407488 -45.001688)
		(end 91.7448 -45.339)
		(width 0.254)
		(layer "F.Cu")
		(net "P3V3_CPU")
	)
	(segment
		(start 90.648028 -37.599874)
		(end 90.648028 -37.599366)
		(width 0.254)
		(layer "F.Cu")
		(net "P3V3_CPU")
	)
	(segment
		(start 55.940706 -38.1254)
		(end 54.737 -38.1254)
		(width 0.3048)
		(layer "F.Cu")
		(net "P3V3_CPU")
	)
	(segment
		(start 74.0918 -25.5778)
		(end 74.1172 -25.5524)
		(width 0.3048)
		(layer "F.Cu")
		(net "P3V3_CPU")
	)
	(segment
		(start 52.669948 -34.350452)
		(end 51.494436 -35.525964)
		(width 0.254)
		(layer "F.Cu")
		(net "P3V3_CPU")
	)
	(segment
		(start 43.434 -49.9364)
		(end 43.434 -49.1744)
		(width 0.381)
		(layer "F.Cu")
		(net "P3V3_CPU")
	)
	(segment
		(start 73.2282 -36.576)
		(end 72.7964 -36.1442)
		(width 0.3048)
		(layer "F.Cu")
		(net "P3V3_CPU")
	)
	(segment
		(start 69.1642 -32.878268)
		(end 69.1642 -31.496)
		(width 0.3048)
		(layer "F.Cu")
		(net "P3V3_CPU")
	)
	(segment
		(start 91.450668 -37.599874)
		(end 91.45016 -37.599366)
		(width 0.254)
		(layer "F.Cu")
		(net "P3V3_CPU")
	)
	(segment
		(start 69.7992 -36.3982)
		(end 69.1642 -35.7632)
		(width 0.508)
		(layer "F.Cu")
		(net "P3V3_CPU")
	)
	(segment
		(start 47.625 -32.3088)
		(end 46.6598 -33.274)
		(width 0.3048)
		(layer "F.Cu")
		(net "P3V3_CPU")
	)
	(segment
		(start 67.603116 -36.957)
		(end 69.7992 -36.957)
		(width 0.4572)
		(layer "F.Cu")
		(net "P3V3_CPU")
	)
	(segment
		(start 56.1848 -37.881306)
		(end 55.940706 -38.1254)
		(width 0.3048)
		(layer "F.Cu")
		(net "P3V3_CPU")
	)
	(segment
		(start 47.9552 -47.0408)
		(end 48.26 -46.736)
		(width 0.508)
		(layer "F.Cu")
		(net "P3V3_CPU")
	)
	(segment
		(start 56.4388 -34.544)
		(end 56.9722 -34.544)
		(width 0.3048)
		(layer "F.Cu")
		(net "P3V3_CPU")
	)
	(segment
		(start 72.7964 -34.544)
		(end 72.847454 -34.492946)
		(width 0.508)
		(layer "F.Cu")
		(net "P3V3_CPU")
	)
	(segment
		(start 54.0512 -37.4396)
		(end 51.7906 -37.4396)
		(width 0.3048)
		(layer "F.Cu")
		(net "P3V3_CPU")
	)
	(segment
		(start 91.498674 -44.000674)
		(end 91.821 -44.323)
		(width 0.3048)
		(layer "F.Cu")
		(net "P3V3_CPU")
	)
	(segment
		(start 51.689 -27.6098)
		(end 51.7525 -27.6733)
		(width 0.254)
		(layer "F.Cu")
		(net "P3V3_CPU")
	)
	(segment
		(start 56.515 -22.8346)
		(end 56.4642 -22.8346)
		(width 0.3048)
		(layer "F.Cu")
		(net "P3V3_CPU")
	)
	(segment
		(start 43.434 -49.1744)
		(end 43.434 -48.06696)
		(width 0.381)
		(layer "F.Cu")
		(net "P3V3_CPU")
	)
	(segment
		(start 52.2478 -26.2382)
		(end 54.570884 -26.2382)
		(width 0.3048)
		(layer "F.Cu")
		(net "P3V3_CPU")
	)
	(segment
		(start 56.1848 -37.846)
		(end 56.1848 -37.881306)
		(width 0.3048)
		(layer "F.Cu")
		(net "P3V3_CPU")
	)
	(segment
		(start 51.7525 -28.46578)
		(end 51.711606 -28.506674)
		(width 0.254)
		(layer "F.Cu")
		(net "P3V3_CPU")
	)
	(segment
		(start 43.815 -48.006)
		(end 44.704 -47.117)
		(width 0.508)
		(layer "F.Cu")
		(net "P3V3_CPU")
	)
	(segment
		(start 67.7164 -20.6502)
		(end 67.2211 -20.1549)
		(width 0.3048)
		(layer "F.Cu")
		(net "P3V3_CPU")
	)
	(segment
		(start 73.4314 -25.527)
		(end 73.1774 -25.273)
		(width 0.3048)
		(layer "F.Cu")
		(net "P3V3_CPU")
	)
	(segment
		(start 48.826166 -26.891234)
		(end 47.27956 -28.43784)
		(width 0.254)
		(layer "F.Cu")
		(net "P3V3_CPU")
	)
	(segment
		(start 55.771542 -25.037542)
		(end 55.771542 -23.527258)
		(width 0.3048)
		(layer "F.Cu")
		(net "P3V3_CPU")
	)
	(segment
		(start 55.771542 -23.527258)
		(end 55.8038 -23.495)
		(width 0.3048)
		(layer "F.Cu")
		(net "P3V3_CPU")
	)
	(segment
		(start 46.6598 -33.274)
		(end 46.355 -33.5788)
		(width 0.3048)
		(layer "F.Cu")
		(net "P3V3_CPU")
	)
	(segment
		(start 50.897028 -35.525964)
		(end 50.727864 -35.3568)
		(width 0.254)
		(layer "F.Cu")
		(net "P3V3_CPU")
	)
	(segment
		(start 48.5648 -46.4312)
		(end 48.5648 -45.991272)
		(width 0.508)
		(layer "F.Cu")
		(net "P3V3_CPU")
	)
	(segment
		(start 56.9722 -34.544)
		(end 57.912 -35.4838)
		(width 0.3048)
		(layer "F.Cu")
		(net "P3V3_CPU")
	)
	(segment
		(start 56.4642 -22.8346)
		(end 55.8038 -23.495)
		(width 0.3048)
		(layer "F.Cu")
		(net "P3V3_CPU")
	)
	(segment
		(start 72.7964 -36.1442)
		(end 72.7964 -34.544)
		(width 0.3048)
		(layer "F.Cu")
		(net "P3V3_CPU")
	)
	(segment
		(start 47.27956 -30.26156)
		(end 47.4726 -30.4546)
		(width 0.254)
		(layer "F.Cu")
		(net "P3V3_CPU")
	)
	(segment
		(start 157.226 -46.863)
		(end 157.226 -49.403)
		(width 0.3048)
		(layer "F.Cu")
		(net "P3V3_CPU")
	)
	(segment
		(start 73.2282 -36.576)
		(end 73.2282 -37.465)
		(width 0.3048)
		(layer "F.Cu")
		(net "P3V3_CPU")
	)
	(segment
		(start 51.7906 -37.4396)
		(end 50.1142 -35.7632)
		(width 0.3048)
		(layer "F.Cu")
		(net "P3V3_CPU")
	)
	(segment
		(start 46.355 -33.5788)
		(end 46.355 -33.643824)
		(width 0.3048)
		(layer "F.Cu")
		(net "P3V3_CPU")
	)
	(segment
		(start 73.6092 -34.417)
		(end 73.6092 -33.655)
		(width 0.508)
		(layer "F.Cu")
		(net "P3V3_CPU")
	)
	(segment
		(start 48.26 -46.736)
		(end 48.5648 -46.4312)
		(width 0.508)
		(layer "F.Cu")
		(net "P3V3_CPU")
	)
	(segment
		(start 43.434 -48.06696)
		(end 43.37304 -48.006)
		(width 0.381)
		(layer "F.Cu")
		(net "P3V3_CPU")
	)
	(segment
		(start 52.67706 -34.339784)
		(end 52.669948 -34.350452)
		(width 0.254)
		(layer "F.Cu")
		(net "P3V3_CPU")
	)
	(segment
		(start 157.226 -49.403)
		(end 156.4894 -50.1396)
		(width 0.3048)
		(layer "F.Cu")
		(net "P3V3_CPU")
	)
	(segment
		(start 69.1642 -35.7632)
		(end 69.1642 -32.878268)
		(width 0.508)
		(layer "F.Cu")
		(net "P3V3_CPU")
	)
	(segment
		(start 57.912 -35.4838)
		(end 57.912 -35.0774)
		(width 0.4572)
		(layer "F.Cu")
		(net "P3V3_CPU")
	)
	(segment
		(start 47.625 -30.607)
		(end 47.625 -32.3088)
		(width 0.3048)
		(layer "F.Cu")
		(net "P3V3_CPU")
	)
	(segment
		(start 67.818 -20.6502)
		(end 67.7164 -20.6502)
		(width 0.3048)
		(layer "F.Cu")
		(net "P3V3_CPU")
	)
	(segment
		(start 73.6092 -29.972)
		(end 73.2282 -29.972)
		(width 0.3048)
		(layer "F.Cu")
		(net "P3V3_CPU")
	)
	(segment
		(start 46.69536 -30.4546)
		(end 47.4726 -30.4546)
		(width 0.3048)
		(layer "F.Cu")
		(net "P3V3_CPU")
	)
	(segment
		(start 56.7309 -22.6187)
		(end 56.515 -22.8346)
		(width 0.3048)
		(layer "F.Cu")
		(net "P3V3_CPU")
	)
	(segment
		(start 49.326038 -26.891234)
		(end 48.826166 -26.891234)
		(width 0.254)
		(layer "F.Cu")
		(net "P3V3_CPU")
	)
	(segment
		(start 72.771 -30.4292)
		(end 72.771 -30.4546)
		(width 0.3048)
		(layer "F.Cu")
		(net "P3V3_CPU")
	)
	(segment
		(start 47.27956 -28.43784)
		(end 47.27956 -30.26156)
		(width 0.254)
		(layer "F.Cu")
		(net "P3V3_CPU")
	)
	(segment
		(start 46.355 -33.643824)
		(end 46.2788 -33.720024)
		(width 0.3048)
		(layer "F.Cu")
		(net "P3V3_CPU")
	)
	(segment
		(start 91.821 -44.323)
		(end 91.821 -44.45)
		(width 0.3048)
		(layer "F.Cu")
		(net "P3V3_CPU")
	)
	(segment
		(start 63.2714 -34.502344)
		(end 64.370458 -34.502344)
		(width 0.4572)
		(layer "F.Cu")
		(net "P3V3_CPU")
	)
	(segment
		(start 51.689 -27.305)
		(end 51.689 -27.6098)
		(width 0.254)
		(layer "F.Cu")
		(net "P3V3_CPU")
	)
	(segment
		(start 72.847454 -34.492946)
		(end 73.533254 -34.492946)
		(width 0.508)
		(layer "F.Cu")
		(net "P3V3_CPU")
	)
	(segment
		(start 54.737 -38.1254)
		(end 54.0512 -37.4396)
		(width 0.3048)
		(layer "F.Cu")
		(net "P3V3_CPU")
	)
	(segment
		(start 46.609 -47.0408)
		(end 47.9552 -47.0408)
		(width 0.508)
		(layer "F.Cu")
		(net "P3V3_CPU")
	)
	(segment
		(start 52.67706 -33.24606)
		(end 52.67706 -34.339784)
		(width 0.254)
		(layer "F.Cu")
		(net "P3V3_CPU")
	)
	(segment
		(start 43.37304 -48.006)
		(end 43.815 -48.006)
		(width 0.508)
		(layer "F.Cu")
		(net "P3V3_CPU")
	)
	(segment
		(start 74.0918 -25.527)
		(end 73.4314 -25.527)
		(width 0.3048)
		(layer "F.Cu")
		(net "P3V3_CPU")
	)
	(segment
		(start 91.45016 -37.599366)
		(end 90.648028 -37.599366)
		(width 0.254)
		(layer "F.Cu")
		(net "P3V3_CPU")
	)
	(segment
		(start 56.7309 -21.5646)
		(end 56.7309 -22.6187)
		(width 0.3048)
		(layer "F.Cu")
		(net "P3V3_CPU")
	)
	(via
		(at 91.821 -44.45)
		(size 0.4318)
		(drill 0.2032)
		(layers "F.Cu" "B.Cu")
		(net "P3V3_CPU")
	)
	(via
		(at 80.2513 -25.0571)
		(size 0.4318)
		(drill 0.2032)
		(layers "F.Cu" "B.Cu")
		(net "P3V3_CPU")
	)
	(via
		(at 63.2714 -34.502344)
		(size 0.7112)
		(drill 0.3556)
		(layers "F.Cu" "B.Cu")
		(net "P3V3_CPU")
	)
	(via
		(at 110.014766 -62.428882)
		(size 0.508)
		(drill 0.254)
		(layers "F.Cu" "B.Cu")
		(net "P3V3_CPU")
	)
	(via
		(at 72.771 -30.4546)
		(size 0.508)
		(drill 0.254)
		(layers "F.Cu" "B.Cu")
		(net "P3V3_CPU")
	)
	(via
		(at 57.912 -35.4838)
		(size 0.508)
		(drill 0.254)
		(layers "F.Cu" "B.Cu")
		(net "P3V3_CPU")
	)
	(via
		(at 90.283538 -37.218112)
		(size 0.4318)
		(drill 0.2032)
		(layers "F.Cu" "B.Cu")
		(net "P3V3_CPU")
	)
	(via
		(at 48.5648 -45.991272)
		(size 0.508)
		(drill 0.254)
		(layers "F.Cu" "B.Cu")
		(net "P3V3_CPU")
	)
	(via
		(at 48.26 -46.736)
		(size 0.7112)
		(drill 0.3556)
		(layers "F.Cu" "B.Cu")
		(net "P3V3_CPU")
	)
	(via
		(at 72.7964 -34.544)
		(size 0.508)
		(drill 0.254)
		(layers "F.Cu" "B.Cu")
		(net "P3V3_CPU")
	)
	(via
		(at 67.08775 -20.1549)
		(size 0.508)
		(drill 0.254)
		(layers "F.Cu" "B.Cu")
		(net "P3V3_CPU")
	)
	(via
		(at 52.6288 -26.924)
		(size 0.508)
		(drill 0.254)
		(layers "F.Cu" "B.Cu")
		(net "P3V3_CPU")
	)
	(via
		(at 73.1774 -25.273)
		(size 0.508)
		(drill 0.254)
		(layers "F.Cu" "B.Cu")
		(net "P3V3_CPU")
	)
	(via
		(at 69.1642 -32.878268)
		(size 0.508)
		(drill 0.254)
		(layers "F.Cu" "B.Cu")
		(net "P3V3_CPU")
	)
	(via
		(at 91.7448 -45.339)
		(size 0.4318)
		(drill 0.2032)
		(layers "F.Cu" "B.Cu")
		(net "P3V3_CPU")
	)
	(via
		(at 156.4894 -50.1396)
		(size 0.508)
		(drill 0.254)
		(layers "F.Cu" "B.Cu")
		(net "P3V3_CPU")
	)
	(segment
		(start 80.2513 -25.0571)
		(end 80.27162 -25.0571)
		(width 0.3048)
		(layer "B.Cu")
		(net "P3V3_CPU")
	)
	(segment
		(start 90.54465 -36.957)
		(end 91.186 -36.957)
		(width 0.3048)
		(layer "B.Cu")
		(net "P3V3_CPU")
	)
	(segment
		(start 80.27162 -25.0571)
		(end 80.635602 -25.421082)
		(width 0.3048)
		(layer "B.Cu")
		(net "P3V3_CPU")
	)
	(segment
		(start 88.7349 -33.8709)
		(end 88.9 -33.7058)
		(width 0.2286)
		(layer "B.Cu")
		(net "P3V3_CPU")
	)
	(segment
		(start 91.186 -45.0342)
		(end 91.186 -45.6438)
		(width 0.3048)
		(layer "B.Cu")
		(net "P3V3_CPU")
	)
	(segment
		(start 80.8482 -27.051)
		(end 80.4418 -26.6446)
		(width 0.3048)
		(layer "B.Cu")
		(net "P3V3_CPU")
	)
	(segment
		(start 91.186 -45.6438)
		(end 91.44 -45.6438)
		(width 0.3048)
		(layer "B.Cu")
		(net "P3V3_CPU")
	)
	(segment
		(start 156.4894 -50.1396)
		(end 156.409898 -50.1396)
		(width 0.3048)
		(layer "B.Cu")
		(net "P3V3_CPU")
	)
	(segment
		(start 73.6092 -30.226)
		(end 73.6092 -29.464)
		(width 0.254)
		(layer "B.Cu")
		(net "P3V3_CPU")
	)
	(segment
		(start 119.11457 -50.673)
		(end 110.014766 -59.772804)
		(width 0.3048)
		(layer "B.Cu")
		(net "P3V3_CPU")
	)
	(segment
		(start 71.0438 -26.1366)
		(end 71.201788 -26.1366)
		(width 0.3048)
		(layer "B.Cu")
		(net "P3V3_CPU")
	)
	(segment
		(start 89.408 -36.5252)
		(end 89.662 -36.5252)
		(width 0.3048)
		(layer "B.Cu")
		(net "P3V3_CPU")
	)
	(segment
		(start 89.662 -37.1348)
		(end 90.200226 -37.1348)
		(width 0.3048)
		(layer "B.Cu")
		(net "P3V3_CPU")
	)
	(segment
		(start 110.014766 -59.772804)
		(end 110.014766 -62.428882)
		(width 0.3048)
		(layer "B.Cu")
		(net "P3V3_CPU")
	)
	(segment
		(start 90.283538 -37.218112)
		(end 90.54465 -36.957)
		(width 0.3048)
		(layer "B.Cu")
		(net "P3V3_CPU")
	)
	(segment
		(start 70.739 -26.4414)
		(end 71.0438 -26.1366)
		(width 0.3048)
		(layer "B.Cu")
		(net "P3V3_CPU")
	)
	(segment
		(start 73.6092 -30.226)
		(end 73.6092 -30.988)
		(width 0.254)
		(layer "B.Cu")
		(net "P3V3_CPU")
	)
	(segment
		(start 73.6092 -30.988)
		(end 73.6092 -31.75)
		(width 0.254)
		(layer "B.Cu")
		(net "P3V3_CPU")
	)
	(segment
		(start 88.7349 -34.887662)
		(end 88.7349 -33.8709)
		(width 0.2286)
		(layer "B.Cu")
		(net "P3V3_CPU")
	)
	(segment
		(start 73.6092 -31.75)
		(end 73.6092 -32.512)
		(width 0.254)
		(layer "B.Cu")
		(net "P3V3_CPU")
	)
	(segment
		(start 73.6092 -30.226)
		(end 72.9996 -30.226)
		(width 0.254)
		(layer "B.Cu")
		(net "P3V3_CPU")
	)
	(segment
		(start 91.186 -45.0342)
		(end 91.7702 -44.45)
		(width 0.3048)
		(layer "B.Cu")
		(net "P3V3_CPU")
	)
	(segment
		(start 88.265 -35.3822)
		(end 88.265 -35.357562)
		(width 0.2286)
		(layer "B.Cu")
		(net "P3V3_CPU")
	)
	(segment
		(start 73.6092 -29.464)
		(end 73.6092 -28.702)
		(width 0.254)
		(layer "B.Cu")
		(net "P3V3_CPU")
	)
	(segment
		(start 74.2442 -24.7904)
		(end 73.7616 -25.273)
		(width 0.3048)
		(layer "B.Cu")
		(net "P3V3_CPU")
	)
	(segment
		(start 72.9996 -30.226)
		(end 72.771 -30.4546)
		(width 0.254)
		(layer "B.Cu")
		(net "P3V3_CPU")
	)
	(segment
		(start 90.424 -45.6438)
		(end 91.186 -45.6438)
		(width 0.3048)
		(layer "B.Cu")
		(net "P3V3_CPU")
	)
	(segment
		(start 80.4418 -26.6446)
		(end 80.4418 -26.289)
		(width 0.3048)
		(layer "B.Cu")
		(net "P3V3_CPU")
	)
	(segment
		(start 73.6092 -28.702)
		(end 73.6092 -27.94)
		(width 0.254)
		(layer "B.Cu")
		(net "P3V3_CPU")
	)
	(segment
		(start 71.201788 -26.1366)
		(end 72.065388 -25.273)
		(width 0.3048)
		(layer "B.Cu")
		(net "P3V3_CPU")
	)
	(segment
		(start 156.409898 -50.1396)
		(end 155.876498 -50.673)
		(width 0.3048)
		(layer "B.Cu")
		(net "P3V3_CPU")
	)
	(segment
		(start 72.065388 -25.273)
		(end 73.1774 -25.273)
		(width 0.3048)
		(layer "B.Cu")
		(net "P3V3_CPU")
	)
	(segment
		(start 91.44 -45.6438)
		(end 91.7448 -45.339)
		(width 0.3048)
		(layer "B.Cu")
		(net "P3V3_CPU")
	)
	(segment
		(start 89.662 -36.5252)
		(end 89.662 -37.1348)
		(width 0.3048)
		(layer "B.Cu")
		(net "P3V3_CPU")
	)
	(segment
		(start 90.200226 -37.1348)
		(end 90.283538 -37.218112)
		(width 0.3048)
		(layer "B.Cu")
		(net "P3V3_CPU")
	)
	(segment
		(start 88.265 -35.357562)
		(end 88.7349 -34.887662)
		(width 0.2286)
		(layer "B.Cu")
		(net "P3V3_CPU")
	)
	(segment
		(start 91.7702 -44.45)
		(end 91.821 -44.45)
		(width 0.3048)
		(layer "B.Cu")
		(net "P3V3_CPU")
	)
	(segment
		(start 73.6092 -32.512)
		(end 73.6092 -33.274)
		(width 0.254)
		(layer "B.Cu")
		(net "P3V3_CPU")
	)
	(segment
		(start 80.635602 -26.095198)
		(end 80.4418 -26.289)
		(width 0.3048)
		(layer "B.Cu")
		(net "P3V3_CPU")
	)
	(segment
		(start 88.265 -35.3822)
		(end 89.408 -36.5252)
		(width 0.3048)
		(layer "B.Cu")
		(net "P3V3_CPU")
	)
	(segment
		(start 73.7616 -25.273)
		(end 73.1774 -25.273)
		(width 0.3048)
		(layer "B.Cu")
		(net "P3V3_CPU")
	)
	(segment
		(start 155.876498 -50.673)
		(end 119.11457 -50.673)
		(width 0.3048)
		(layer "B.Cu")
		(net "P3V3_CPU")
	)
	(segment
		(start 80.635602 -25.421082)
		(end 80.635602 -26.095198)
		(width 0.3048)
		(layer "B.Cu")
		(net "P3V3_CPU")
	)
	(segment
		(start 72.5424 -34.29)
		(end 70.575932 -34.29)
		(width 0.508)
		(layer "In2.Cu")
		(net "P3V3_CPU")
	)
	(segment
		(start 69.1642 -31.2928)
		(end 69.85 -30.607)
		(width 0.508)
		(layer "In2.Cu")
		(net "P3V3_CPU")
	)
	(segment
		(start 78.557882 -25.527)
		(end 79.027782 -25.0571)
		(width 0.3048)
		(layer "In2.Cu")
		(net "P3V3_CPU")
	)
	(segment
		(start 72.771 -25.6794)
		(end 73.1774 -25.273)
		(width 0.3048)
		(layer "In2.Cu")
		(net "P3V3_CPU")
	)
	(segment
		(start 72.771 -30.4546)
		(end 72.771 -25.6794)
		(width 0.3048)
		(layer "In2.Cu")
		(net "P3V3_CPU")
	)
	(segment
		(start 69.85 -30.607)
		(end 72.6186 -30.607)
		(width 0.508)
		(layer "In2.Cu")
		(net "P3V3_CPU")
	)
	(segment
		(start 70.575932 -34.29)
		(end 69.1642 -32.878268)
		(width 0.508)
		(layer "In2.Cu")
		(net "P3V3_CPU")
	)
	(segment
		(start 72.6186 -30.607)
		(end 72.771 -30.4546)
		(width 0.508)
		(layer "In2.Cu")
		(net "P3V3_CPU")
	)
	(segment
		(start 69.1642 -32.878268)
		(end 69.1642 -31.2928)
		(width 0.508)
		(layer "In2.Cu")
		(net "P3V3_CPU")
	)
	(segment
		(start 72.7964 -34.544)
		(end 72.5424 -34.29)
		(width 0.508)
		(layer "In2.Cu")
		(net "P3V3_CPU")
	)
	(segment
		(start 79.027782 -25.0571)
		(end 80.2513 -25.0571)
		(width 0.3048)
		(layer "In2.Cu")
		(net "P3V3_CPU")
	)
	(segment
		(start 73.4314 -25.527)
		(end 78.557882 -25.527)
		(width 0.3048)
		(layer "In2.Cu")
		(net "P3V3_CPU")
	)
	(segment
		(start 73.1774 -25.273)
		(end 73.4314 -25.527)
		(width 0.3048)
		(layer "In2.Cu")
		(net "P3V3_CPU")
	)
	(segment
		(start 58.179208 -38.15207)
		(end 53.806344 -42.524934)
		(width 0.508)
		(layer "In4.Cu")
		(net "P3V3_CPU")
	)
	(segment
		(start 57.912 -35.4838)
		(end 57.912 -36.561522)
		(width 0.508)
		(layer "In4.Cu")
		(net "P3V3_CPU")
	)
	(segment
		(start 49.210722 -45.39615)
		(end 48.6156 -45.991272)
		(width 0.508)
		(layer "In4.Cu")
		(net "P3V3_CPU")
	)
	(segment
		(start 49.224438 -45.39615)
		(end 49.210722 -45.39615)
		(width 0.508)
		(layer "In4.Cu")
		(net "P3V3_CPU")
	)
	(segment
		(start 57.912 -36.561522)
		(end 58.179208 -36.82873)
		(width 0.508)
		(layer "In4.Cu")
		(net "P3V3_CPU")
	)
	(segment
		(start 58.179208 -36.82873)
		(end 58.179208 -38.15207)
		(width 0.508)
		(layer "In4.Cu")
		(net "P3V3_CPU")
	)
	(segment
		(start 52.095654 -42.524934)
		(end 49.224438 -45.39615)
		(width 0.508)
		(layer "In4.Cu")
		(net "P3V3_CPU")
	)
	(segment
		(start 48.6156 -45.991272)
		(end 48.5648 -45.991272)
		(width 0.508)
		(layer "In4.Cu")
		(net "P3V3_CPU")
	)
	(segment
		(start 53.806344 -42.524934)
		(end 52.095654 -42.524934)
		(width 0.508)
		(layer "In4.Cu")
		(net "P3V3_CPU")
	)
	(segment
		(start 67.08775 -20.238212)
		(end 67.08775 -20.1549)
		(width 0.3048)
		(layer "In7.Cu")
		(net "P3V3_CPU")
	)
	(segment
		(start 94.134432 -46.822614)
		(end 96.3168 -49.004982)
		(width 0.3048)
		(layer "In7.Cu")
		(net "P3V3_CPU")
	)
	(segment
		(start 88.770714 -33.068514)
		(end 87.69985 -31.99765)
		(width 0.3048)
		(layer "In7.Cu")
		(net "P3V3_CPU")
	)
	(segment
		(start 99.0854 -59.4106)
		(end 98.0313 -58.3565)
		(width 0.3048)
		(layer "In7.Cu")
		(net "P3V3_CPU")
	)
	(segment
		(start 98.425 -54.0512)
		(end 98.0694 -53.6956)
		(width 0.1524)
		(layer "In7.Cu")
		(net "P3V3_CPU")
	)
	(segment
		(start 90.297 -40.377618)
		(end 90.297 -42.926)
		(width 0.3048)
		(layer "In7.Cu")
		(net "P3V3_CPU")
	)
	(segment
		(start 109.920024 -62.33414)
		(end 109.920024 -61.961776)
		(width 0.3048)
		(layer "In7.Cu")
		(net "P3V3_CPU")
	)
	(segment
		(start 96.3168 -49.004982)
		(end 96.3168 -52.206398)
		(width 0.3048)
		(layer "In7.Cu")
		(net "P3V3_CPU")
	)
	(segment
		(start 90.283538 -37.218112)
		(end 89.77884 -37.72281)
		(width 0.3048)
		(layer "In7.Cu")
		(net "P3V3_CPU")
	)
	(segment
		(start 88.770714 -34.098484)
		(end 88.770714 -33.068514)
		(width 0.3048)
		(layer "In7.Cu")
		(net "P3V3_CPU")
	)
	(segment
		(start 98.0694 -53.6956)
		(end 97.990406 -53.6956)
		(width 0.1524)
		(layer "In7.Cu")
		(net "P3V3_CPU")
	)
	(segment
		(start 98.0313 -58.3565)
		(end 98.425 -57.9628)
		(width 0.1524)
		(layer "In7.Cu")
		(net "P3V3_CPU")
	)
	(segment
		(start 88.5444 -35.296856)
		(end 88.5444 -34.324798)
		(width 0.3048)
		(layer "In7.Cu")
		(net "P3V3_CPU")
	)
	(segment
		(start 109.299248 -61.341)
		(end 102.2858 -61.341)
		(width 0.3048)
		(layer "In7.Cu")
		(net "P3V3_CPU")
	)
	(segment
		(start 97.6122 -54.073806)
		(end 97.990406 -53.6956)
		(width 0.1524)
		(layer "In7.Cu")
		(net "P3V3_CPU")
	)
	(segment
		(start 88.898984 -35.5727)
		(end 88.820244 -35.5727)
		(width 0.3048)
		(layer "In7.Cu")
		(net "P3V3_CPU")
	)
	(segment
		(start 89.77884 -37.72281)
		(end 89.77884 -39.859458)
		(width 0.3048)
		(layer "In7.Cu")
		(net "P3V3_CPU")
	)
	(segment
		(start 97.628202 -53.5178)
		(end 97.812606 -53.5178)
		(width 0.3048)
		(layer "In7.Cu")
		(net "P3V3_CPU")
	)
	(segment
		(start 90.283538 -37.218112)
		(end 89.786968 -36.721542)
		(width 0.3048)
		(layer "In7.Cu")
		(net "P3V3_CPU")
	)
	(segment
		(start 98.0313 -58.3565)
		(end 97.8535 -58.3565)
		(width 0.1524)
		(layer "In7.Cu")
		(net "P3V3_CPU")
	)
	(segment
		(start 88.5444 -34.324798)
		(end 88.770714 -34.098484)
		(width 0.3048)
		(layer "In7.Cu")
		(net "P3V3_CPU")
	)
	(segment
		(start 82.188812 -26.035)
		(end 81.478882 -26.035)
		(width 0.3048)
		(layer "In7.Cu")
		(net "P3V3_CPU")
	)
	(segment
		(start 109.920024 -61.961776)
		(end 109.299248 -61.341)
		(width 0.3048)
		(layer "In7.Cu")
		(net "P3V3_CPU")
	)
	(segment
		(start 87.3252 -30.9372)
		(end 85.901784 -30.9372)
		(width 0.3048)
		(layer "In7.Cu")
		(net "P3V3_CPU")
	)
	(segment
		(start 89.786968 -36.721542)
		(end 89.786968 -36.460684)
		(width 0.3048)
		(layer "In7.Cu")
		(net "P3V3_CPU")
	)
	(segment
		(start 73.1774 -25.273)
		(end 72.51827 -24.61387)
		(width 0.3048)
		(layer "In7.Cu")
		(net "P3V3_CPU")
	)
	(segment
		(start 97.6122 -58.1152)
		(end 97.6122 -54.073806)
		(width 0.1524)
		(layer "In7.Cu")
		(net "P3V3_CPU")
	)
	(segment
		(start 96.3168 -52.206398)
		(end 97.628202 -53.5178)
		(width 0.3048)
		(layer "In7.Cu")
		(net "P3V3_CPU")
	)
	(segment
		(start 85.901784 -30.9372)
		(end 85.3948 -30.430216)
		(width 0.3048)
		(layer "In7.Cu")
		(net "P3V3_CPU")
	)
	(segment
		(start 89.77884 -39.859458)
		(end 90.297 -40.377618)
		(width 0.3048)
		(layer "In7.Cu")
		(net "P3V3_CPU")
	)
	(segment
		(start 88.820244 -35.5727)
		(end 88.5444 -35.296856)
		(width 0.3048)
		(layer "In7.Cu")
		(net "P3V3_CPU")
	)
	(segment
		(start 93.228414 -46.822614)
		(end 94.134432 -46.822614)
		(width 0.3048)
		(layer "In7.Cu")
		(net "P3V3_CPU")
	)
	(segment
		(start 110.014766 -62.428882)
		(end 109.920024 -62.33414)
		(width 0.3048)
		(layer "In7.Cu")
		(net "P3V3_CPU")
	)
	(segment
		(start 80.589882 -25.146)
		(end 80.3402 -25.146)
		(width 0.3048)
		(layer "In7.Cu")
		(net "P3V3_CPU")
	)
	(segment
		(start 91.7448 -45.339)
		(end 93.228414 -46.822614)
		(width 0.3048)
		(layer "In7.Cu")
		(net "P3V3_CPU")
	)
	(segment
		(start 71.463408 -24.61387)
		(end 67.08775 -20.238212)
		(width 0.3048)
		(layer "In7.Cu")
		(net "P3V3_CPU")
	)
	(segment
		(start 85.3948 -29.240988)
		(end 82.188812 -26.035)
		(width 0.3048)
		(layer "In7.Cu")
		(net "P3V3_CPU")
	)
	(segment
		(start 90.297 -42.926)
		(end 91.821 -44.45)
		(width 0.3048)
		(layer "In7.Cu")
		(net "P3V3_CPU")
	)
	(segment
		(start 97.8535 -58.3565)
		(end 97.6122 -58.1152)
		(width 0.1524)
		(layer "In7.Cu")
		(net "P3V3_CPU")
	)
	(segment
		(start 100.3554 -59.4106)
		(end 99.0854 -59.4106)
		(width 0.3048)
		(layer "In7.Cu")
		(net "P3V3_CPU")
	)
	(segment
		(start 72.51827 -24.61387)
		(end 71.463408 -24.61387)
		(width 0.3048)
		(layer "In7.Cu")
		(net "P3V3_CPU")
	)
	(segment
		(start 98.425 -57.9628)
		(end 98.425 -54.0512)
		(width 0.1524)
		(layer "In7.Cu")
		(net "P3V3_CPU")
	)
	(segment
		(start 87.69985 -31.99765)
		(end 87.69985 -31.31185)
		(width 0.3048)
		(layer "In7.Cu")
		(net "P3V3_CPU")
	)
	(segment
		(start 80.3402 -25.146)
		(end 80.2513 -25.0571)
		(width 0.3048)
		(layer "In7.Cu")
		(net "P3V3_CPU")
	)
	(segment
		(start 102.2858 -61.341)
		(end 100.3554 -59.4106)
		(width 0.3048)
		(layer "In7.Cu")
		(net "P3V3_CPU")
	)
	(segment
		(start 81.478882 -26.035)
		(end 80.589882 -25.146)
		(width 0.3048)
		(layer "In7.Cu")
		(net "P3V3_CPU")
	)
	(segment
		(start 85.3948 -30.430216)
		(end 85.3948 -29.240988)
		(width 0.3048)
		(layer "In7.Cu")
		(net "P3V3_CPU")
	)
	(segment
		(start 97.812606 -53.5178)
		(end 97.990406 -53.6956)
		(width 0.3048)
		(layer "In7.Cu")
		(net "P3V3_CPU")
	)
	(segment
		(start 89.786968 -36.460684)
		(end 88.898984 -35.5727)
		(width 0.3048)
		(layer "In7.Cu")
		(net "P3V3_CPU")
	)
	(segment
		(start 87.69985 -31.31185)
		(end 87.3252 -30.9372)
		(width 0.3048)
		(layer "In7.Cu")
		(net "P3V3_CPU")
	)
	(segment
		(start 53.5686 -26.924)
		(end 54.89575 -28.25115)
		(width 0.508)
		(layer "In9.Cu")
		(net "P3V3_CPU")
	)
	(segment
		(start 56.8706 -31.641034)
		(end 56.8706 -34.4424)
		(width 0.508)
		(layer "In9.Cu")
		(net "P3V3_CPU")
	)
	(segment
		(start 54.89575 -28.25115)
		(end 54.89575 -29.666184)
		(width 0.508)
		(layer "In9.Cu")
		(net "P3V3_CPU")
	)
	(segment
		(start 56.8706 -34.4424)
		(end 57.912 -35.4838)
		(width 0.508)
		(layer "In9.Cu")
		(net "P3V3_CPU")
	)
	(segment
		(start 54.89575 -29.666184)
		(end 56.8706 -31.641034)
		(width 0.508)
		(layer "In9.Cu")
		(net "P3V3_CPU")
	)
	(segment
		(start 52.6288 -26.924)
		(end 53.5686 -26.924)
		(width 0.508)
		(layer "In9.Cu")
		(net "P3V3_CPU")
	)
	(segment
		(start 187.449968 -62.59322)
		(end 187.449968 -63.337694)
		(width 0.1778)
		(layer "F.Cu")
		(net "M_A_DQS_DN0")
	)
	(segment
		(start 187.410598 -65.064894)
		(end 187.198 -65.277492)
		(width 0.1778)
		(layer "F.Cu")
		(net "M_A_DQS_DN0")
	)
	(segment
		(start 187.198 -66.303144)
		(end 187.567062 -66.672206)
		(width 0.1778)
		(layer "F.Cu")
		(net "M_A_DQS_DN0")
	)
	(segment
		(start 187.198 -65.277492)
		(end 187.198 -66.303144)
		(width 0.1778)
		(layer "F.Cu")
		(net "M_A_DQS_DN0")
	)
	(segment
		(start 106.9086 -40.649398)
		(end 106.9086 -40.8178)
		(width 0.1016)
		(layer "F.Cu")
		(net "M_A_DQS_DN0")
	)
	(segment
		(start 106.9086 -40.8178)
		(end 106.771186 -40.955214)
		(width 0.1016)
		(layer "F.Cu")
		(net "M_A_DQS_DN0")
	)
	(segment
		(start 187.449968 -63.337694)
		(end 187.410598 -63.377064)
		(width 0.1778)
		(layer "F.Cu")
		(net "M_A_DQS_DN0")
	)
	(segment
		(start 106.771186 -40.955214)
		(end 106.528108 -40.955214)
		(width 0.1016)
		(layer "F.Cu")
		(net "M_A_DQS_DN0")
	)
	(segment
		(start 187.410598 -63.377064)
		(end 187.410598 -65.064894)
		(width 0.1778)
		(layer "F.Cu")
		(net "M_A_DQS_DN0")
	)
	(via
		(at 106.9086 -40.649398)
		(size 0.4318)
		(drill 0.2032)
		(layers "F.Cu" "B.Cu")
		(net "M_A_DQS_DN0")
	)
	(via
		(at 187.567062 -66.672206)
		(size 0.4318)
		(drill 0.2032)
		(layers "F.Cu" "B.Cu")
		(net "M_A_DQS_DN0")
	)
	(segment
		(start 187.449968 -70.79996)
		(end 187.449968 -70.038976)
		(width 0.1778)
		(layer "B.Cu")
		(net "M_A_DQS_DN0")
	)
	(segment
		(start 187.302394 -66.936874)
		(end 187.567062 -66.672206)
		(width 0.1778)
		(layer "B.Cu")
		(net "M_A_DQS_DN0")
	)
	(segment
		(start 187.449968 -70.038976)
		(end 187.302394 -69.891402)
		(width 0.1778)
		(layer "B.Cu")
		(net "M_A_DQS_DN0")
	)
	(segment
		(start 187.302394 -69.891402)
		(end 187.302394 -66.936874)
		(width 0.1778)
		(layer "B.Cu")
		(net "M_A_DQS_DN0")
	)
	(segment
		(start 176.236376 -57.0992)
		(end 175.528224 -57.0992)
		(width 0.1524)
		(layer "In7.Cu")
		(net "M_A_DQS_DN0")
	)
	(segment
		(start 112.179862 -41.741598)
		(end 112.093248 -41.741598)
		(width 0.1016)
		(layer "In7.Cu")
		(net "M_A_DQS_DN0")
	)
	(segment
		(start 187.4774 -65.151)
		(end 187.4774 -64.07658)
		(width 0.1524)
		(layer "In7.Cu")
		(net "M_A_DQS_DN0")
	)
	(segment
		(start 167.102028 -51.583844)
		(end 167.102028 -51.136804)
		(width 0.1524)
		(layer "In7.Cu")
		(net "M_A_DQS_DN0")
	)
	(segment
		(start 184.824624 -62.1284)
		(end 182.4228 -62.1284)
		(width 0.1524)
		(layer "In7.Cu")
		(net "M_A_DQS_DN0")
	)
	(segment
		(start 152.924256 -42.008298)
		(end 118.944898 -42.008298)
		(width 0.1524)
		(layer "In7.Cu")
		(net "M_A_DQS_DN0")
	)
	(segment
		(start 110.776258 -41.021)
		(end 110.0328 -41.021)
		(width 0.1016)
		(layer "In7.Cu")
		(net "M_A_DQS_DN0")
	)
	(segment
		(start 118.237 -41.3004)
		(end 113.538 -41.3004)
		(width 0.1524)
		(layer "In7.Cu")
		(net "M_A_DQS_DN0")
	)
	(segment
		(start 182.4228 -62.1284)
		(end 179.4764 -59.182)
		(width 0.1524)
		(layer "In7.Cu")
		(net "M_A_DQS_DN0")
	)
	(segment
		(start 110.0328 -41.021)
		(end 109.854238 -41.199562)
		(width 0.1016)
		(layer "In7.Cu")
		(net "M_A_DQS_DN0")
	)
	(segment
		(start 187.28944 -65.33896)
		(end 187.4774 -65.151)
		(width 0.1524)
		(layer "In7.Cu")
		(net "M_A_DQS_DN0")
	)
	(segment
		(start 166.468806 -52.432458)
		(end 166.468806 -52.217066)
		(width 0.1524)
		(layer "In7.Cu")
		(net "M_A_DQS_DN0")
	)
	(segment
		(start 165.42639 -51.17465)
		(end 165.210998 -51.17465)
		(width 0.1524)
		(layer "In7.Cu")
		(net "M_A_DQS_DN0")
	)
	(segment
		(start 111.51362 -41.758362)
		(end 110.776258 -41.021)
		(width 0.1016)
		(layer "In7.Cu")
		(net "M_A_DQS_DN0")
	)
	(segment
		(start 162.448748 -48.4124)
		(end 159.328358 -48.4124)
		(width 0.1524)
		(layer "In7.Cu")
		(net "M_A_DQS_DN0")
	)
	(segment
		(start 166.506652 -50.541428)
		(end 166.059612 -50.541428)
		(width 0.1524)
		(layer "In7.Cu")
		(net "M_A_DQS_DN0")
	)
	(segment
		(start 186.944 -63.54318)
		(end 186.378596 -63.100458)
		(width 0.1524)
		(layer "In7.Cu")
		(net "M_A_DQS_DN0")
	)
	(segment
		(start 173.239938 -55.1434)
		(end 171.149772 -53.053234)
		(width 0.1524)
		(layer "In7.Cu")
		(net "M_A_DQS_DN0")
	)
	(segment
		(start 113.096802 -41.741598)
		(end 112.179862 -41.741598)
		(width 0.1524)
		(layer "In7.Cu")
		(net "M_A_DQS_DN0")
	)
	(segment
		(start 185.973212 -62.783212)
		(end 184.824624 -62.1284)
		(width 0.1524)
		(layer "In7.Cu")
		(net "M_A_DQS_DN0")
	)
	(segment
		(start 174.3202 -55.1434)
		(end 173.239938 -55.1434)
		(width 0.1524)
		(layer "In7.Cu")
		(net "M_A_DQS_DN0")
	)
	(segment
		(start 175.185832 -56.009032)
		(end 174.3202 -55.1434)
		(width 0.1524)
		(layer "In7.Cu")
		(net "M_A_DQS_DN0")
	)
	(segment
		(start 166.059612 -50.541428)
		(end 165.42639 -51.17465)
		(width 0.1524)
		(layer "In7.Cu")
		(net "M_A_DQS_DN0")
	)
	(segment
		(start 166.468806 -52.217066)
		(end 167.102028 -51.583844)
		(width 0.1524)
		(layer "In7.Cu")
		(net "M_A_DQS_DN0")
	)
	(segment
		(start 118.944898 -42.008298)
		(end 118.237 -41.3004)
		(width 0.1524)
		(layer "In7.Cu")
		(net "M_A_DQS_DN0")
	)
	(segment
		(start 175.185832 -56.756808)
		(end 175.185832 -56.009032)
		(width 0.1524)
		(layer "In7.Cu")
		(net "M_A_DQS_DN0")
	)
	(segment
		(start 171.149772 -53.053234)
		(end 167.089582 -53.053234)
		(width 0.1524)
		(layer "In7.Cu")
		(net "M_A_DQS_DN0")
	)
	(segment
		(start 112.093248 -41.741598)
		(end 112.076484 -41.758362)
		(width 0.1016)
		(layer "In7.Cu")
		(net "M_A_DQS_DN0")
	)
	(segment
		(start 113.538 -41.3004)
		(end 113.096802 -41.741598)
		(width 0.1524)
		(layer "In7.Cu")
		(net "M_A_DQS_DN0")
	)
	(segment
		(start 107.178602 -40.9194)
		(end 106.9086 -40.649398)
		(width 0.1016)
		(layer "In7.Cu")
		(net "M_A_DQS_DN0")
	)
	(segment
		(start 165.210998 -51.17465)
		(end 162.448748 -48.4124)
		(width 0.1524)
		(layer "In7.Cu")
		(net "M_A_DQS_DN0")
	)
	(segment
		(start 108.26242 -41.199562)
		(end 107.982258 -40.9194)
		(width 0.1016)
		(layer "In7.Cu")
		(net "M_A_DQS_DN0")
	)
	(segment
		(start 178.319176 -59.182)
		(end 176.236376 -57.0992)
		(width 0.1524)
		(layer "In7.Cu")
		(net "M_A_DQS_DN0")
	)
	(segment
		(start 109.854238 -41.199562)
		(end 108.26242 -41.199562)
		(width 0.1016)
		(layer "In7.Cu")
		(net "M_A_DQS_DN0")
	)
	(segment
		(start 167.102028 -51.136804)
		(end 166.506652 -50.541428)
		(width 0.1524)
		(layer "In7.Cu")
		(net "M_A_DQS_DN0")
	)
	(segment
		(start 107.982258 -40.9194)
		(end 107.178602 -40.9194)
		(width 0.1016)
		(layer "In7.Cu")
		(net "M_A_DQS_DN0")
	)
	(segment
		(start 159.328358 -48.4124)
		(end 152.924256 -42.008298)
		(width 0.1524)
		(layer "In7.Cu")
		(net "M_A_DQS_DN0")
	)
	(segment
		(start 175.528224 -57.0992)
		(end 175.185832 -56.756808)
		(width 0.1524)
		(layer "In7.Cu")
		(net "M_A_DQS_DN0")
	)
	(segment
		(start 112.076484 -41.758362)
		(end 111.51362 -41.758362)
		(width 0.1016)
		(layer "In7.Cu")
		(net "M_A_DQS_DN0")
	)
	(segment
		(start 179.4764 -59.182)
		(end 178.319176 -59.182)
		(width 0.1524)
		(layer "In7.Cu")
		(net "M_A_DQS_DN0")
	)
	(segment
		(start 186.37758 -63.099696)
		(end 185.973212 -62.783212)
		(width 0.1524)
		(layer "In7.Cu")
		(net "M_A_DQS_DN0")
	)
	(segment
		(start 187.567062 -66.672206)
		(end 187.28944 -66.394584)
		(width 0.1524)
		(layer "In7.Cu")
		(net "M_A_DQS_DN0")
	)
	(segment
		(start 186.378596 -63.100458)
		(end 186.37758 -63.099696)
		(width 0.1524)
		(layer "In7.Cu")
		(net "M_A_DQS_DN0")
	)
	(segment
		(start 187.4774 -64.07658)
		(end 186.944 -63.54318)
		(width 0.1524)
		(layer "In7.Cu")
		(net "M_A_DQS_DN0")
	)
	(segment
		(start 167.089582 -53.053234)
		(end 166.468806 -52.432458)
		(width 0.1524)
		(layer "In7.Cu")
		(net "M_A_DQS_DN0")
	)
	(segment
		(start 187.28944 -66.394584)
		(end 187.28944 -65.33896)
		(width 0.1524)
		(layer "In7.Cu")
		(net "M_A_DQS_DN0")
	)
	(segment
		(start 28.8036 -54.5084)
		(end 28.6766 -54.3814)
		(width 0.508)
		(layer "F.Cu")
		(net "VR_PVCCP_BOOT_R")
	)
	(segment
		(start 28.6766 -54.3814)
		(end 27.7368 -54.3814)
		(width 0.508)
		(layer "F.Cu")
		(net "VR_PVCCP_BOOT_R")
	)
	(segment
		(start 146.349974 -70.806564)
		(end 146.349974 -70.088252)
		(width 0.1778)
		(layer "F.Cu")
		(net "M_A_DQS_DN4")
	)
	(segment
		(start 146.349974 -70.088252)
		(end 146.2024 -69.940678)
		(width 0.1778)
		(layer "F.Cu")
		(net "M_A_DQS_DN4")
	)
	(segment
		(start 97.6884 -47.249842)
		(end 98.059748 -46.878494)
		(width 0.1016)
		(layer "F.Cu")
		(net "M_A_DQS_DN4")
	)
	(segment
		(start 97.6884 -47.2694)
		(end 97.6884 -47.249842)
		(width 0.1016)
		(layer "F.Cu")
		(net "M_A_DQS_DN4")
	)
	(segment
		(start 98.059748 -46.878494)
		(end 98.067368 -46.878494)
		(width 0.1016)
		(layer "F.Cu")
		(net "M_A_DQS_DN4")
	)
	(segment
		(start 146.2024 -69.940678)
		(end 146.2024 -66.936874)
		(width 0.1778)
		(layer "F.Cu")
		(net "M_A_DQS_DN4")
	)
	(segment
		(start 146.2024 -66.936874)
		(end 146.467068 -66.672206)
		(width 0.1778)
		(layer "F.Cu")
		(net "M_A_DQS_DN4")
	)
	(via
		(at 97.6884 -47.2694)
		(size 0.4318)
		(drill 0.2032)
		(layers "F.Cu" "B.Cu")
		(net "M_A_DQS_DN4")
	)
	(via
		(at 146.467068 -66.672206)
		(size 0.4318)
		(drill 0.2032)
		(layers "F.Cu" "B.Cu")
		(net "M_A_DQS_DN4")
	)
	(segment
		(start 146.2024 -66.407538)
		(end 146.467068 -66.672206)
		(width 0.1778)
		(layer "B.Cu")
		(net "M_A_DQS_DN4")
	)
	(segment
		(start 146.349974 -62.599824)
		(end 146.349974 -63.33363)
		(width 0.1778)
		(layer "B.Cu")
		(net "M_A_DQS_DN4")
	)
	(segment
		(start 146.2024 -63.481204)
		(end 146.2024 -66.407538)
		(width 0.1778)
		(layer "B.Cu")
		(net "M_A_DQS_DN4")
	)
	(segment
		(start 146.349974 -63.33363)
		(end 146.2024 -63.481204)
		(width 0.1778)
		(layer "B.Cu")
		(net "M_A_DQS_DN4")
	)
	(segment
		(start 140.6398 -58.42)
		(end 141.3383 -57.7215)
		(width 0.1524)
		(layer "In4.Cu")
		(net "M_A_DQS_DN4")
	)
	(segment
		(start 97.6884 -47.278798)
		(end 97.6884 -47.2694)
		(width 0.1016)
		(layer "In4.Cu")
		(net "M_A_DQS_DN4")
	)
	(segment
		(start 107.480608 -55.746396)
		(end 107.480608 -55.576216)
		(width 0.1524)
		(layer "In4.Cu")
		(net "M_A_DQS_DN4")
	)
	(segment
		(start 107.963716 -56.229504)
		(end 107.480608 -55.746396)
		(width 0.1524)
		(layer "In4.Cu")
		(net "M_A_DQS_DN4")
	)
	(segment
		(start 140.334238 -59.381644)
		(end 140.118084 -59.16549)
		(width 0.1524)
		(layer "In4.Cu")
		(net "M_A_DQS_DN4")
	)
	(segment
		(start 107.726988 -55.329836)
		(end 107.726988 -54.691788)
		(width 0.1524)
		(layer "In4.Cu")
		(net "M_A_DQS_DN4")
	)
	(segment
		(start 138.87831 -57.925716)
		(end 138.662156 -57.709562)
		(width 0.1524)
		(layer "In4.Cu")
		(net "M_A_DQS_DN4")
	)
	(segment
		(start 142.780512 -59.733688)
		(end 142.9512 -59.563)
		(width 0.1524)
		(layer "In4.Cu")
		(net "M_A_DQS_DN4")
	)
	(segment
		(start 138.662156 -57.709562)
		(end 138.662156 -56.809132)
		(width 0.1524)
		(layer "In4.Cu")
		(net "M_A_DQS_DN4")
	)
	(segment
		(start 143.394176 -60.2742)
		(end 142.940024 -60.2742)
		(width 0.1524)
		(layer "In4.Cu")
		(net "M_A_DQS_DN4")
	)
	(segment
		(start 145.923762 -61.367162)
		(end 144.5514 -59.9948)
		(width 0.1524)
		(layer "In4.Cu")
		(net "M_A_DQS_DN4")
	)
	(segment
		(start 99.654614 -49.969674)
		(end 99.601274 -49.969674)
		(width 0.1016)
		(layer "In4.Cu")
		(net "M_A_DQS_DN4")
	)
	(segment
		(start 98.425 -47.6758)
		(end 98.2218 -47.4726)
		(width 0.1016)
		(layer "In4.Cu")
		(net "M_A_DQS_DN4")
	)
	(segment
		(start 99.949 -50.26406)
		(end 99.654614 -49.969674)
		(width 0.1524)
		(layer "In4.Cu")
		(net "M_A_DQS_DN4")
	)
	(segment
		(start 146.467068 -66.672206)
		(end 146.2024 -66.407538)
		(width 0.1524)
		(layer "In4.Cu")
		(net "M_A_DQS_DN4")
	)
	(segment
		(start 98.425 -49.1998)
		(end 98.425 -47.6758)
		(width 0.1016)
		(layer "In4.Cu")
		(net "M_A_DQS_DN4")
	)
	(segment
		(start 142.9512 -59.563)
		(end 142.9512 -58.674)
		(width 0.1524)
		(layer "In4.Cu")
		(net "M_A_DQS_DN4")
	)
	(segment
		(start 100.061014 -51.40579)
		(end 99.949 -51.293776)
		(width 0.1524)
		(layer "In4.Cu")
		(net "M_A_DQS_DN4")
	)
	(segment
		(start 140.118084 -58.950098)
		(end 140.6398 -58.428382)
		(width 0.1524)
		(layer "In4.Cu")
		(net "M_A_DQS_DN4")
	)
	(segment
		(start 109.5756 -56.4134)
		(end 108.966 -55.8038)
		(width 0.1524)
		(layer "In4.Cu")
		(net "M_A_DQS_DN4")
	)
	(segment
		(start 103.925878 -52.084478)
		(end 102.525068 -52.084478)
		(width 0.1524)
		(layer "In4.Cu")
		(net "M_A_DQS_DN4")
	)
	(segment
		(start 138.266424 -56.4134)
		(end 109.5756 -56.4134)
		(width 0.1524)
		(layer "In4.Cu")
		(net "M_A_DQS_DN4")
	)
	(segment
		(start 146.2024 -66.407538)
		(end 146.2024 -63.499238)
		(width 0.1524)
		(layer "In4.Cu")
		(net "M_A_DQS_DN4")
	)
	(segment
		(start 142.780512 -60.114688)
		(end 142.780512 -59.733688)
		(width 0.1524)
		(layer "In4.Cu")
		(net "M_A_DQS_DN4")
	)
	(segment
		(start 138.662156 -56.809132)
		(end 138.266424 -56.4134)
		(width 0.1524)
		(layer "In4.Cu")
		(net "M_A_DQS_DN4")
	)
	(segment
		(start 142.5702 -58.293)
		(end 141.6558 -58.293)
		(width 0.1524)
		(layer "In4.Cu")
		(net "M_A_DQS_DN4")
	)
	(segment
		(start 141.6558 -58.293)
		(end 140.567156 -59.381644)
		(width 0.1524)
		(layer "In4.Cu")
		(net "M_A_DQS_DN4")
	)
	(segment
		(start 101.84638 -51.40579)
		(end 100.061014 -51.40579)
		(width 0.1524)
		(layer "In4.Cu")
		(net "M_A_DQS_DN4")
	)
	(segment
		(start 99.949 -51.293776)
		(end 99.949 -50.26406)
		(width 0.1524)
		(layer "In4.Cu")
		(net "M_A_DQS_DN4")
	)
	(segment
		(start 108.966 -55.8038)
		(end 108.5596 -55.8038)
		(width 0.1524)
		(layer "In4.Cu")
		(net "M_A_DQS_DN4")
	)
	(segment
		(start 142.9512 -58.674)
		(end 142.5702 -58.293)
		(width 0.1524)
		(layer "In4.Cu")
		(net "M_A_DQS_DN4")
	)
	(segment
		(start 99.2632 -49.6316)
		(end 98.8568 -49.6316)
		(width 0.1016)
		(layer "In4.Cu")
		(net "M_A_DQS_DN4")
	)
	(segment
		(start 102.525068 -52.084478)
		(end 101.84638 -51.40579)
		(width 0.1524)
		(layer "In4.Cu")
		(net "M_A_DQS_DN4")
	)
	(segment
		(start 144.5514 -59.9948)
		(end 143.673576 -59.9948)
		(width 0.1524)
		(layer "In4.Cu")
		(net "M_A_DQS_DN4")
	)
	(segment
		(start 105.41 -53.5686)
		(end 103.925878 -52.084478)
		(width 0.1524)
		(layer "In4.Cu")
		(net "M_A_DQS_DN4")
	)
	(segment
		(start 140.567156 -59.381644)
		(end 140.334238 -59.381644)
		(width 0.1524)
		(layer "In4.Cu")
		(net "M_A_DQS_DN4")
	)
	(segment
		(start 142.940024 -60.2742)
		(end 142.780512 -60.114688)
		(width 0.1524)
		(layer "In4.Cu")
		(net "M_A_DQS_DN4")
	)
	(segment
		(start 140.29817 -56.721248)
		(end 139.093702 -57.925716)
		(width 0.1524)
		(layer "In4.Cu")
		(net "M_A_DQS_DN4")
	)
	(segment
		(start 107.480608 -55.576216)
		(end 107.726988 -55.329836)
		(width 0.1524)
		(layer "In4.Cu")
		(net "M_A_DQS_DN4")
	)
	(segment
		(start 143.673576 -59.9948)
		(end 143.394176 -60.2742)
		(width 0.1524)
		(layer "In4.Cu")
		(net "M_A_DQS_DN4")
	)
	(segment
		(start 140.6398 -58.428382)
		(end 140.6398 -58.42)
		(width 0.1524)
		(layer "In4.Cu")
		(net "M_A_DQS_DN4")
	)
	(segment
		(start 106.740452 -54.148228)
		(end 106.160824 -53.5686)
		(width 0.1524)
		(layer "In4.Cu")
		(net "M_A_DQS_DN4")
	)
	(segment
		(start 146.2024 -63.499238)
		(end 145.923762 -63.2206)
		(width 0.1524)
		(layer "In4.Cu")
		(net "M_A_DQS_DN4")
	)
	(segment
		(start 141.3383 -57.1373)
		(end 140.922248 -56.721248)
		(width 0.1524)
		(layer "In4.Cu")
		(net "M_A_DQS_DN4")
	)
	(segment
		(start 98.8568 -49.6316)
		(end 98.425 -49.1998)
		(width 0.1016)
		(layer "In4.Cu")
		(net "M_A_DQS_DN4")
	)
	(segment
		(start 99.601274 -49.969674)
		(end 99.2632 -49.6316)
		(width 0.1016)
		(layer "In4.Cu")
		(net "M_A_DQS_DN4")
	)
	(segment
		(start 140.118084 -59.16549)
		(end 140.118084 -58.950098)
		(width 0.1524)
		(layer "In4.Cu")
		(net "M_A_DQS_DN4")
	)
	(segment
		(start 107.726988 -54.691788)
		(end 107.183428 -54.148228)
		(width 0.1524)
		(layer "In4.Cu")
		(net "M_A_DQS_DN4")
	)
	(segment
		(start 139.093702 -57.925716)
		(end 138.87831 -57.925716)
		(width 0.1524)
		(layer "In4.Cu")
		(net "M_A_DQS_DN4")
	)
	(segment
		(start 106.160824 -53.5686)
		(end 105.41 -53.5686)
		(width 0.1524)
		(layer "In4.Cu")
		(net "M_A_DQS_DN4")
	)
	(segment
		(start 108.133896 -56.229504)
		(end 107.963716 -56.229504)
		(width 0.1524)
		(layer "In4.Cu")
		(net "M_A_DQS_DN4")
	)
	(segment
		(start 107.183428 -54.148228)
		(end 106.740452 -54.148228)
		(width 0.1524)
		(layer "In4.Cu")
		(net "M_A_DQS_DN4")
	)
	(segment
		(start 145.923762 -63.2206)
		(end 145.923762 -61.367162)
		(width 0.1524)
		(layer "In4.Cu")
		(net "M_A_DQS_DN4")
	)
	(segment
		(start 141.3383 -57.7215)
		(end 141.3383 -57.1373)
		(width 0.1524)
		(layer "In4.Cu")
		(net "M_A_DQS_DN4")
	)
	(segment
		(start 108.5596 -55.8038)
		(end 108.133896 -56.229504)
		(width 0.1524)
		(layer "In4.Cu")
		(net "M_A_DQS_DN4")
	)
	(segment
		(start 97.882202 -47.4726)
		(end 97.6884 -47.278798)
		(width 0.1016)
		(layer "In4.Cu")
		(net "M_A_DQS_DN4")
	)
	(segment
		(start 140.922248 -56.721248)
		(end 140.29817 -56.721248)
		(width 0.1524)
		(layer "In4.Cu")
		(net "M_A_DQS_DN4")
	)
	(segment
		(start 98.2218 -47.4726)
		(end 97.882202 -47.4726)
		(width 0.1016)
		(layer "In4.Cu")
		(net "M_A_DQS_DN4")
	)
	(segment
		(start 102.904036 -42.145966)
		(end 103.648764 -42.145966)
		(width 0.127)
		(layer "F.Cu")
		(net "TP_CPU_RSVD7")
	)
	(segment
		(start 103.648764 -42.145966)
		(end 103.9622 -42.459402)
		(width 0.127)
		(layer "F.Cu")
		(net "TP_CPU_RSVD7")
	)
	(segment
		(start 102.692708 -42.357294)
		(end 102.904036 -42.145966)
		(width 0.127)
		(layer "F.Cu")
		(net "TP_CPU_RSVD7")
	)
	(via
		(at 103.9622 -42.459402)
		(size 0.4318)
		(drill 0.2032)
		(layers "F.Cu" "B.Cu")
		(net "TP_CPU_RSVD7")
	)
	(segment
		(start 104.648 -42.7228)
		(end 104.225598 -42.7228)
		(width 0.127)
		(layer "B.Cu")
		(net "TP_CPU_RSVD7")
	)
	(segment
		(start 104.225598 -42.7228)
		(end 103.9622 -42.459402)
		(width 0.127)
		(layer "B.Cu")
		(net "TP_CPU_RSVD7")
	)
	(segment
		(start 40.3606 -53.0098)
		(end 42.1386 -53.0098)
		(width 0.508)
		(layer "F.Cu")
		(net "VR_PVCCP_VSW_R")
	)
	(segment
		(start 42.4434 -53.0098)
		(end 42.1386 -53.0098)
		(width 0.508)
		(layer "F.Cu")
		(net "VR_PVCCP_VSW_R")
	)
	(segment
		(start 43.6626 -54.229)
		(end 42.4434 -53.0098)
		(width 0.508)
		(layer "F.Cu")
		(net "VR_PVCCP_VSW_R")
	)
	(segment
		(start 40.2844 -52.9336)
		(end 40.3606 -53.0098)
		(width 0.508)
		(layer "F.Cu")
		(net "VR_PVCCP_VSW_R")
	)
	(via
		(at 40.2844 -52.9336)
		(size 0.7112)
		(drill 0.3556)
		(layers "F.Cu" "B.Cu")
		(net "VR_PVCCP_VSW_R")
	)
	(segment
		(start 107.11434 -41.865296)
		(end 107.290108 -41.689528)
		(width 0.1016)
		(layer "F.Cu")
		(net "M_A_DQ6")
	)
	(segment
		(start 186.550046 -70.116446)
		(end 186.11596 -69.68236)
		(width 0.1778)
		(layer "F.Cu")
		(net "M_A_DQ6")
	)
	(segment
		(start 186.550046 -70.806564)
		(end 186.550046 -70.116446)
		(width 0.1778)
		(layer "F.Cu")
		(net "M_A_DQ6")
	)
	(segment
		(start 107.11434 -42.47642)
		(end 107.11434 -41.865296)
		(width 0.1016)
		(layer "F.Cu")
		(net "M_A_DQ6")
	)
	(segment
		(start 107.290108 -41.689528)
		(end 107.290108 -41.656254)
		(width 0.1016)
		(layer "F.Cu")
		(net "M_A_DQ6")
	)
	(segment
		(start 186.11596 -69.68236)
		(end 186.11596 -68.6308)
		(width 0.1778)
		(layer "F.Cu")
		(net "M_A_DQ6")
	)
	(via
		(at 186.11596 -68.6308)
		(size 0.4318)
		(drill 0.2032)
		(layers "F.Cu" "B.Cu")
		(net "M_A_DQ6")
	)
	(via
		(at 107.11434 -42.47642)
		(size 0.4318)
		(drill 0.2032)
		(layers "F.Cu" "B.Cu")
		(net "M_A_DQ6")
	)
	(segment
		(start 186.11596 -69.389244)
		(end 186.11596 -68.6308)
		(width 0.1778)
		(layer "B.Cu")
		(net "M_A_DQ6")
	)
	(segment
		(start 185.650124 -70.79996)
		(end 185.650124 -69.85508)
		(width 0.1778)
		(layer "B.Cu")
		(net "M_A_DQ6")
	)
	(segment
		(start 185.650124 -69.85508)
		(end 186.11596 -69.389244)
		(width 0.1778)
		(layer "B.Cu")
		(net "M_A_DQ6")
	)
	(segment
		(start 169.827448 -59.083956)
		(end 169.612056 -59.083956)
		(width 0.1524)
		(layer "In7.Cu")
		(net "M_A_DQ6")
	)
	(segment
		(start 109.05998 -44.45)
		(end 109.04474 -44.43476)
		(width 0.1524)
		(layer "In7.Cu")
		(net "M_A_DQ6")
	)
	(segment
		(start 158.650686 -51.435)
		(end 151.840184 -44.624498)
		(width 0.1524)
		(layer "In7.Cu")
		(net "M_A_DQ6")
	)
	(segment
		(start 169.927016 -60.278518)
		(end 169.711116 -60.062618)
		(width 0.1524)
		(layer "In7.Cu")
		(net "M_A_DQ6")
	)
	(segment
		(start 170.043348 -59.299856)
		(end 169.827448 -59.083956)
		(width 0.1524)
		(layer "In7.Cu")
		(net "M_A_DQ6")
	)
	(segment
		(start 172.563536 -64.689736)
		(end 172.563536 -62.915038)
		(width 0.1524)
		(layer "In7.Cu")
		(net "M_A_DQ6")
	)
	(segment
		(start 169.064432 -59.415934)
		(end 168.848532 -59.200034)
		(width 0.1524)
		(layer "In7.Cu")
		(net "M_A_DQ6")
	)
	(segment
		(start 168.749472 -58.221372)
		(end 168.41724 -58.55335)
		(width 0.1524)
		(layer "In7.Cu")
		(net "M_A_DQ6")
	)
	(segment
		(start 168.10228 -57.358788)
		(end 167.886888 -57.358788)
		(width 0.1524)
		(layer "In7.Cu")
		(net "M_A_DQ6")
	)
	(segment
		(start 171.274232 -60.872116)
		(end 171.004992 -61.141102)
		(width 0.1524)
		(layer "In7.Cu")
		(net "M_A_DQ6")
	)
	(segment
		(start 185.468006 -67.993006)
		(end 175.866806 -67.993006)
		(width 0.1524)
		(layer "In7.Cu")
		(net "M_A_DQ6")
	)
	(segment
		(start 108.331 -44.43476)
		(end 107.961938 -44.395644)
		(width 0.1016)
		(layer "In7.Cu")
		(net "M_A_DQ6")
	)
	(segment
		(start 171.48937 -60.872116)
		(end 171.274232 -60.872116)
		(width 0.1524)
		(layer "In7.Cu")
		(net "M_A_DQ6")
	)
	(segment
		(start 169.180764 -58.437272)
		(end 168.964864 -58.221372)
		(width 0.1524)
		(layer "In7.Cu")
		(net "M_A_DQ6")
	)
	(segment
		(start 117.3226 -44.9834)
		(end 112.4204 -44.9834)
		(width 0.1524)
		(layer "In7.Cu")
		(net "M_A_DQ6")
	)
	(segment
		(start 169.279824 -59.415934)
		(end 169.064432 -59.415934)
		(width 0.1524)
		(layer "In7.Cu")
		(net "M_A_DQ6")
	)
	(segment
		(start 171.004992 -61.141102)
		(end 170.7896 -61.141102)
		(width 0.1524)
		(layer "In7.Cu")
		(net "M_A_DQ6")
	)
	(segment
		(start 169.180764 -58.652664)
		(end 169.180764 -58.437272)
		(width 0.1524)
		(layer "In7.Cu")
		(net "M_A_DQ6")
	)
	(segment
		(start 169.711116 -60.062618)
		(end 169.711116 -59.847226)
		(width 0.1524)
		(layer "In7.Cu")
		(net "M_A_DQ6")
	)
	(segment
		(start 167.985948 -58.122058)
		(end 168.31818 -57.79008)
		(width 0.1524)
		(layer "In7.Cu")
		(net "M_A_DQ6")
	)
	(segment
		(start 168.201848 -58.55335)
		(end 167.985948 -58.33745)
		(width 0.1524)
		(layer "In7.Cu")
		(net "M_A_DQ6")
	)
	(segment
		(start 186.1058 -68.6308)
		(end 185.468006 -67.993006)
		(width 0.1524)
		(layer "In7.Cu")
		(net "M_A_DQ6")
	)
	(segment
		(start 112.4204 -44.9834)
		(end 111.887 -44.45)
		(width 0.1524)
		(layer "In7.Cu")
		(net "M_A_DQ6")
	)
	(segment
		(start 168.848532 -58.984642)
		(end 169.180764 -58.652664)
		(width 0.1524)
		(layer "In7.Cu")
		(net "M_A_DQ6")
	)
	(segment
		(start 170.47464 -59.94654)
		(end 170.142408 -60.278518)
		(width 0.1524)
		(layer "In7.Cu")
		(net "M_A_DQ6")
	)
	(segment
		(start 167.985948 -58.33745)
		(end 167.985948 -58.122058)
		(width 0.1524)
		(layer "In7.Cu")
		(net "M_A_DQ6")
	)
	(segment
		(start 166.849298 -57.2008)
		(end 165.501828 -57.2008)
		(width 0.1524)
		(layer "In7.Cu")
		(net "M_A_DQ6")
	)
	(segment
		(start 169.612056 -59.083956)
		(end 169.279824 -59.415934)
		(width 0.1524)
		(layer "In7.Cu")
		(net "M_A_DQ6")
	)
	(segment
		(start 172.563536 -62.915038)
		(end 171.436284 -61.787786)
		(width 0.1524)
		(layer "In7.Cu")
		(net "M_A_DQ6")
	)
	(segment
		(start 107.66044 -42.99712)
		(end 107.13974 -42.47642)
		(width 0.1016)
		(layer "In7.Cu")
		(net "M_A_DQ6")
	)
	(segment
		(start 151.840184 -44.624498)
		(end 117.681502 -44.624498)
		(width 0.1524)
		(layer "In7.Cu")
		(net "M_A_DQ6")
	)
	(segment
		(start 170.905932 -60.377832)
		(end 170.905932 -60.16244)
		(width 0.1524)
		(layer "In7.Cu")
		(net "M_A_DQ6")
	)
	(segment
		(start 167.554656 -57.690766)
		(end 167.339264 -57.690766)
		(width 0.1524)
		(layer "In7.Cu")
		(net "M_A_DQ6")
	)
	(segment
		(start 159.736028 -51.435)
		(end 158.650686 -51.435)
		(width 0.1524)
		(layer "In7.Cu")
		(net "M_A_DQ6")
	)
	(segment
		(start 107.13974 -42.47642)
		(end 107.11434 -42.47642)
		(width 0.1016)
		(layer "In7.Cu")
		(net "M_A_DQ6")
	)
	(segment
		(start 170.690032 -59.94654)
		(end 170.47464 -59.94654)
		(width 0.1524)
		(layer "In7.Cu")
		(net "M_A_DQ6")
	)
	(segment
		(start 171.70527 -61.08827)
		(end 171.48937 -60.872116)
		(width 0.1524)
		(layer "In7.Cu")
		(net "M_A_DQ6")
	)
	(segment
		(start 168.31818 -57.574688)
		(end 168.10228 -57.358788)
		(width 0.1524)
		(layer "In7.Cu")
		(net "M_A_DQ6")
	)
	(segment
		(start 170.5737 -60.70981)
		(end 170.905932 -60.377832)
		(width 0.1524)
		(layer "In7.Cu")
		(net "M_A_DQ6")
	)
	(segment
		(start 168.848532 -59.200034)
		(end 168.848532 -58.984642)
		(width 0.1524)
		(layer "In7.Cu")
		(net "M_A_DQ6")
	)
	(segment
		(start 168.964864 -58.221372)
		(end 168.749472 -58.221372)
		(width 0.1524)
		(layer "In7.Cu")
		(net "M_A_DQ6")
	)
	(segment
		(start 170.905932 -60.16244)
		(end 170.690032 -59.94654)
		(width 0.1524)
		(layer "In7.Cu")
		(net "M_A_DQ6")
	)
	(segment
		(start 170.5737 -60.925202)
		(end 170.5737 -60.70981)
		(width 0.1524)
		(layer "In7.Cu")
		(net "M_A_DQ6")
	)
	(segment
		(start 169.711116 -59.847226)
		(end 170.043348 -59.515248)
		(width 0.1524)
		(layer "In7.Cu")
		(net "M_A_DQ6")
	)
	(segment
		(start 167.886888 -57.358788)
		(end 167.554656 -57.690766)
		(width 0.1524)
		(layer "In7.Cu")
		(net "M_A_DQ6")
	)
	(segment
		(start 168.41724 -58.55335)
		(end 168.201848 -58.55335)
		(width 0.1524)
		(layer "In7.Cu")
		(net "M_A_DQ6")
	)
	(segment
		(start 168.31818 -57.79008)
		(end 168.31818 -57.574688)
		(width 0.1524)
		(layer "In7.Cu")
		(net "M_A_DQ6")
	)
	(segment
		(start 171.70527 -61.303916)
		(end 171.70527 -61.08827)
		(width 0.1524)
		(layer "In7.Cu")
		(net "M_A_DQ6")
	)
	(segment
		(start 171.436284 -61.787786)
		(end 171.436284 -61.572394)
		(width 0.1524)
		(layer "In7.Cu")
		(net "M_A_DQ6")
	)
	(segment
		(start 107.961938 -44.395644)
		(end 107.66044 -44.094146)
		(width 0.1016)
		(layer "In7.Cu")
		(net "M_A_DQ6")
	)
	(segment
		(start 170.043348 -59.515248)
		(end 170.043348 -59.299856)
		(width 0.1524)
		(layer "In7.Cu")
		(net "M_A_DQ6")
	)
	(segment
		(start 107.66044 -44.094146)
		(end 107.66044 -42.99712)
		(width 0.1016)
		(layer "In7.Cu")
		(net "M_A_DQ6")
	)
	(segment
		(start 109.04474 -44.43476)
		(end 108.331 -44.43476)
		(width 0.1016)
		(layer "In7.Cu")
		(net "M_A_DQ6")
	)
	(segment
		(start 167.339264 -57.690766)
		(end 166.849298 -57.2008)
		(width 0.1524)
		(layer "In7.Cu")
		(net "M_A_DQ6")
	)
	(segment
		(start 170.142408 -60.278518)
		(end 169.927016 -60.278518)
		(width 0.1524)
		(layer "In7.Cu")
		(net "M_A_DQ6")
	)
	(segment
		(start 175.866806 -67.993006)
		(end 172.563536 -64.689736)
		(width 0.1524)
		(layer "In7.Cu")
		(net "M_A_DQ6")
	)
	(segment
		(start 117.681502 -44.624498)
		(end 117.3226 -44.9834)
		(width 0.1524)
		(layer "In7.Cu")
		(net "M_A_DQ6")
	)
	(segment
		(start 111.887 -44.45)
		(end 109.05998 -44.45)
		(width 0.1524)
		(layer "In7.Cu")
		(net "M_A_DQ6")
	)
	(segment
		(start 170.7896 -61.141102)
		(end 170.5737 -60.925202)
		(width 0.1524)
		(layer "In7.Cu")
		(net "M_A_DQ6")
	)
	(segment
		(start 165.501828 -57.2008)
		(end 159.736028 -51.435)
		(width 0.1524)
		(layer "In7.Cu")
		(net "M_A_DQ6")
	)
	(segment
		(start 171.436284 -61.572394)
		(end 171.70527 -61.303916)
		(width 0.1524)
		(layer "In7.Cu")
		(net "M_A_DQ6")
	)
	(segment
		(start 186.11596 -68.6308)
		(end 186.1058 -68.6308)
		(width 0.1524)
		(layer "In7.Cu")
		(net "M_A_DQ6")
	)
	(via
		(at 77.4827 -38.3921)
		(size 0.4318)
		(drill 0.2032)
		(layers "F.Cu" "B.Cu")
		(net "PMU_SUS_CLK")
	)
	(via
		(at 78.5749 -37.55136)
		(size 0.7112)
		(drill 0.3556)
		(layers "F.Cu" "B.Cu")
		(net "PMU_SUS_CLK")
	)
	(via
		(at 14.5796 -53.5178)
		(size 0.508)
		(drill 0.254)
		(layers "F.Cu" "B.Cu")
		(net "PMU_SUS_CLK")
	)
	(segment
		(start 78.61554 -37.592)
		(end 78.5749 -37.55136)
		(width 0.1143)
		(layer "B.Cu")
		(net "PMU_SUS_CLK")
	)
	(segment
		(start 78.5749 -37.55136)
		(end 78.55966 -37.55136)
		(width 0.1143)
		(layer "B.Cu")
		(net "PMU_SUS_CLK")
	)
	(segment
		(start 77.343 -37.5158)
		(end 77.343 -38.2016)
		(width 0.1143)
		(layer "B.Cu")
		(net "PMU_SUS_CLK")
	)
	(segment
		(start 14.5796 -53.5178)
		(end 14.5796 -53.3146)
		(width 0.1143)
		(layer "B.Cu")
		(net "PMU_SUS_CLK")
	)
	(segment
		(start 77.4827 -38.3413)
		(end 77.4827 -38.3921)
		(width 0.1143)
		(layer "B.Cu")
		(net "PMU_SUS_CLK")
	)
	(segment
		(start 78.55966 -37.55136)
		(end 78.5241 -37.5158)
		(width 0.1143)
		(layer "B.Cu")
		(net "PMU_SUS_CLK")
	)
	(segment
		(start 13.125196 -51.860196)
		(end 13.125196 -51.199796)
		(width 0.1143)
		(layer "B.Cu")
		(net "PMU_SUS_CLK")
	)
	(segment
		(start 77.343 -38.2016)
		(end 77.4827 -38.3413)
		(width 0.1143)
		(layer "B.Cu")
		(net "PMU_SUS_CLK")
	)
	(segment
		(start 78.5241 -37.5158)
		(end 77.343 -37.5158)
		(width 0.1143)
		(layer "B.Cu")
		(net "PMU_SUS_CLK")
	)
	(segment
		(start 14.5796 -53.3146)
		(end 13.125196 -51.860196)
		(width 0.1143)
		(layer "B.Cu")
		(net "PMU_SUS_CLK")
	)
	(segment
		(start 79.5782 -37.592)
		(end 78.61554 -37.592)
		(width 0.1143)
		(layer "B.Cu")
		(net "PMU_SUS_CLK")
	)
	(segment
		(start 39.048944 -51.73345)
		(end 39.597838 -51.184556)
		(width 0.0889)
		(layer "In4.Cu")
		(net "PMU_SUS_CLK")
	)
	(segment
		(start 52.244244 -50.94605)
		(end 55.616094 -47.5742)
		(width 0.0889)
		(layer "In4.Cu")
		(net "PMU_SUS_CLK")
	)
	(segment
		(start 72.3646 -42.1386)
		(end 74.4728 -40.0304)
		(width 0.0889)
		(layer "In4.Cu")
		(net "PMU_SUS_CLK")
	)
	(segment
		(start 34.347658 -51.73345)
		(end 39.048944 -51.73345)
		(width 0.0889)
		(layer "In4.Cu")
		(net "PMU_SUS_CLK")
	)
	(segment
		(start 26.489152 -53.851048)
		(end 29.71165 -50.62855)
		(width 0.0889)
		(layer "In4.Cu")
		(net "PMU_SUS_CLK")
	)
	(segment
		(start 50.379884 -51.184556)
		(end 50.61839 -50.94605)
		(width 0.0889)
		(layer "In4.Cu")
		(net "PMU_SUS_CLK")
	)
	(segment
		(start 55.616094 -47.5742)
		(end 61.8998 -47.5742)
		(width 0.0889)
		(layer "In4.Cu")
		(net "PMU_SUS_CLK")
	)
	(segment
		(start 69.488812 -42.799)
		(end 70.149212 -42.1386)
		(width 0.0889)
		(layer "In4.Cu")
		(net "PMU_SUS_CLK")
	)
	(segment
		(start 75.5904 -40.0304)
		(end 77.2287 -38.3921)
		(width 0.0889)
		(layer "In4.Cu")
		(net "PMU_SUS_CLK")
	)
	(segment
		(start 61.8998 -47.5742)
		(end 66.675 -42.799)
		(width 0.0889)
		(layer "In4.Cu")
		(net "PMU_SUS_CLK")
	)
	(segment
		(start 77.2287 -38.3921)
		(end 77.4827 -38.3921)
		(width 0.0889)
		(layer "In4.Cu")
		(net "PMU_SUS_CLK")
	)
	(segment
		(start 14.912848 -53.851048)
		(end 26.489152 -53.851048)
		(width 0.0889)
		(layer "In4.Cu")
		(net "PMU_SUS_CLK")
	)
	(segment
		(start 29.71165 -50.62855)
		(end 33.242758 -50.62855)
		(width 0.0889)
		(layer "In4.Cu")
		(net "PMU_SUS_CLK")
	)
	(segment
		(start 66.675 -42.799)
		(end 69.488812 -42.799)
		(width 0.0889)
		(layer "In4.Cu")
		(net "PMU_SUS_CLK")
	)
	(segment
		(start 14.5796 -53.5178)
		(end 14.912848 -53.851048)
		(width 0.0889)
		(layer "In4.Cu")
		(net "PMU_SUS_CLK")
	)
	(segment
		(start 39.597838 -51.184556)
		(end 50.379884 -51.184556)
		(width 0.0889)
		(layer "In4.Cu")
		(net "PMU_SUS_CLK")
	)
	(segment
		(start 74.4728 -40.0304)
		(end 75.5904 -40.0304)
		(width 0.0889)
		(layer "In4.Cu")
		(net "PMU_SUS_CLK")
	)
	(segment
		(start 50.61839 -50.94605)
		(end 52.244244 -50.94605)
		(width 0.0889)
		(layer "In4.Cu")
		(net "PMU_SUS_CLK")
	)
	(segment
		(start 33.242758 -50.62855)
		(end 34.347658 -51.73345)
		(width 0.0889)
		(layer "In4.Cu")
		(net "PMU_SUS_CLK")
	)
	(segment
		(start 70.149212 -42.1386)
		(end 72.3646 -42.1386)
		(width 0.0889)
		(layer "In4.Cu")
		(net "PMU_SUS_CLK")
	)
	(segment
		(start 20.9042 -63.344552)
		(end 20.9042 -63.797942)
		(width 0.2032)
		(layer "F.Cu")
		(net "VR_PVNN_ISUMN_R")
	)
	(segment
		(start 21.9456 -64.7446)
		(end 20.9296 -64.7446)
		(width 0.2032)
		(layer "F.Cu")
		(net "VR_PVNN_ISUMN_R")
	)
	(segment
		(start 20.9296 -64.7446)
		(end 20.828 -64.643)
		(width 0.2032)
		(layer "F.Cu")
		(net "VR_PVNN_ISUMN_R")
	)
	(segment
		(start 21.263102 -61.292994)
		(end 21.263102 -62.26175)
		(width 0.2032)
		(layer "F.Cu")
		(net "VR_PVNN_ISUMN_R")
	)
	(segment
		(start 21.4122 -62.410848)
		(end 21.4122 -62.836552)
		(width 0.2032)
		(layer "F.Cu")
		(net "VR_PVNN_ISUMN_R")
	)
	(segment
		(start 21.4122 -62.836552)
		(end 20.9042 -63.344552)
		(width 0.2032)
		(layer "F.Cu")
		(net "VR_PVNN_ISUMN_R")
	)
	(segment
		(start 20.828 -63.874142)
		(end 20.828 -64.643)
		(width 0.2032)
		(layer "F.Cu")
		(net "VR_PVNN_ISUMN_R")
	)
	(segment
		(start 22.733 -64.7446)
		(end 21.9456 -64.7446)
		(width 0.2032)
		(layer "F.Cu")
		(net "VR_PVNN_ISUMN_R")
	)
	(segment
		(start 20.9042 -63.797942)
		(end 20.828 -63.874142)
		(width 0.2032)
		(layer "F.Cu")
		(net "VR_PVNN_ISUMN_R")
	)
	(segment
		(start 21.263102 -62.26175)
		(end 21.4122 -62.410848)
		(width 0.2032)
		(layer "F.Cu")
		(net "VR_PVNN_ISUMN_R")
	)
	(via
		(at 20.828 -64.643)
		(size 0.7112)
		(drill 0.3556)
		(layers "F.Cu" "B.Cu")
		(net "VR_PVNN_ISUMN_R")
	)
	(segment
		(start 113.6142 -49.07534)
		(end 112.126014 -47.587154)
		(width 0.1016)
		(layer "F.Cu")
		(net "M_A_ECC2")
	)
	(segment
		(start 114.3762 -50.9778)
		(end 113.6142 -50.2158)
		(width 0.1016)
		(layer "F.Cu")
		(net "M_A_ECC2")
	)
	(segment
		(start 114.935 -50.9778)
		(end 114.3762 -50.9778)
		(width 0.1016)
		(layer "F.Cu")
		(net "M_A_ECC2")
	)
	(segment
		(start 164.049964 -64.535304)
		(end 164.06368 -64.54902)
		(width 0.1778)
		(layer "F.Cu")
		(net "M_A_ECC2")
	)
	(segment
		(start 112.126014 -47.587154)
		(end 111.603028 -47.587154)
		(width 0.1016)
		(layer "F.Cu")
		(net "M_A_ECC2")
	)
	(segment
		(start 164.049964 -62.59322)
		(end 164.049964 -64.535304)
		(width 0.1778)
		(layer "F.Cu")
		(net "M_A_ECC2")
	)
	(segment
		(start 113.6142 -50.2158)
		(end 113.6142 -49.07534)
		(width 0.1016)
		(layer "F.Cu")
		(net "M_A_ECC2")
	)
	(via
		(at 114.935 -50.9778)
		(size 0.4318)
		(drill 0.2032)
		(layers "F.Cu" "B.Cu")
		(net "M_A_ECC2")
	)
	(via
		(at 164.06368 -64.54902)
		(size 0.4318)
		(drill 0.2032)
		(layers "F.Cu" "B.Cu")
		(net "M_A_ECC2")
	)
	(segment
		(start 163.74999 -64.23533)
		(end 164.06368 -64.54902)
		(width 0.1778)
		(layer "B.Cu")
		(net "M_A_ECC2")
	)
	(segment
		(start 163.74999 -62.599824)
		(end 163.74999 -64.23533)
		(width 0.1778)
		(layer "B.Cu")
		(net "M_A_ECC2")
	)
	(segment
		(start 132.7912 -51.984656)
		(end 132.9436 -51.832256)
		(width 0.1524)
		(layer "In2.Cu")
		(net "M_A_ECC2")
	)
	(segment
		(start 134.047738 -52.451)
		(end 134.047738 -51.984656)
		(width 0.1524)
		(layer "In2.Cu")
		(net "M_A_ECC2")
	)
	(segment
		(start 153.9748 -57.6961)
		(end 154.1272 -57.5437)
		(width 0.1524)
		(layer "In2.Cu")
		(net "M_A_ECC2")
	)
	(segment
		(start 135.266938 -51.984656)
		(end 135.419338 -51.832256)
		(width 0.1524)
		(layer "In2.Cu")
		(net "M_A_ECC2")
	)
	(segment
		(start 136.638538 -51.832256)
		(end 136.943338 -51.832256)
		(width 0.1524)
		(layer "In2.Cu")
		(net "M_A_ECC2")
	)
	(segment
		(start 117.221 -50.546)
		(end 115.3668 -50.546)
		(width 0.1016)
		(layer "In2.Cu")
		(net "M_A_ECC2")
	)
	(segment
		(start 151.981662 -58.2676)
		(end 151.981662 -57.6961)
		(width 0.1524)
		(layer "In2.Cu")
		(net "M_A_ECC2")
	)
	(segment
		(start 137.552938 -52.4002)
		(end 137.705338 -52.2478)
		(width 0.1524)
		(layer "In2.Cu")
		(net "M_A_ECC2")
	)
	(segment
		(start 132.1562 -52.451)
		(end 132.3086 -52.6034)
		(width 0.1524)
		(layer "In2.Cu")
		(net "M_A_ECC2")
	)
	(segment
		(start 133.438138 -51.984656)
		(end 133.438138 -52.451)
		(width 0.1524)
		(layer "In2.Cu")
		(net "M_A_ECC2")
	)
	(segment
		(start 135.724138 -51.832256)
		(end 135.876538 -51.984656)
		(width 0.1524)
		(layer "In2.Cu")
		(net "M_A_ECC2")
	)
	(segment
		(start 115.3668 -50.546)
		(end 114.935 -50.9778)
		(width 0.1016)
		(layer "In2.Cu")
		(net "M_A_ECC2")
	)
	(segment
		(start 154.5844 -58.4962)
		(end 154.7368 -58.6486)
		(width 0.1524)
		(layer "In2.Cu")
		(net "M_A_ECC2")
	)
	(segment
		(start 132.3086 -52.6034)
		(end 132.6388 -52.6034)
		(width 0.1524)
		(layer "In2.Cu")
		(net "M_A_ECC2")
	)
	(segment
		(start 154.7368 -58.6486)
		(end 155.0416 -58.6486)
		(width 0.1524)
		(layer "In2.Cu")
		(net "M_A_ECC2")
	)
	(segment
		(start 152.134062 -57.5437)
		(end 153.2128 -57.5437)
		(width 0.1524)
		(layer "In2.Cu")
		(net "M_A_ECC2")
	)
	(segment
		(start 163.904422 -61.635894)
		(end 163.904422 -64.389762)
		(width 0.1524)
		(layer "In2.Cu")
		(net "M_A_ECC2")
	)
	(segment
		(start 137.705338 -52.2478)
		(end 137.705338 -51.984656)
		(width 0.1524)
		(layer "In2.Cu")
		(net "M_A_ECC2")
	)
	(segment
		(start 157.65526 -57.6961)
		(end 157.80766 -57.5437)
		(width 0.1524)
		(layer "In2.Cu")
		(net "M_A_ECC2")
	)
	(segment
		(start 155.0416 -58.6486)
		(end 155.194 -58.4962)
		(width 0.1524)
		(layer "In2.Cu")
		(net "M_A_ECC2")
	)
	(segment
		(start 133.590538 -52.6034)
		(end 133.895338 -52.6034)
		(width 0.1524)
		(layer "In2.Cu")
		(net "M_A_ECC2")
	)
	(segment
		(start 151.524462 -58.42)
		(end 151.829262 -58.42)
		(width 0.1524)
		(layer "In2.Cu")
		(net "M_A_ECC2")
	)
	(segment
		(start 160.917128 -58.6486)
		(end 163.904422 -61.635894)
		(width 0.1524)
		(layer "In2.Cu")
		(net "M_A_ECC2")
	)
	(segment
		(start 142.014194 -51.832256)
		(end 142.9512 -52.769262)
		(width 0.1524)
		(layer "In2.Cu")
		(net "M_A_ECC2")
	)
	(segment
		(start 157.50286 -58.1406)
		(end 157.65526 -57.9882)
		(width 0.1524)
		(layer "In2.Cu")
		(net "M_A_ECC2")
	)
	(segment
		(start 146.999706 -57.5437)
		(end 151.219662 -57.5437)
		(width 0.1524)
		(layer "In2.Cu")
		(net "M_A_ECC2")
	)
	(segment
		(start 132.1562 -51.984656)
		(end 132.1562 -52.451)
		(width 0.1524)
		(layer "In2.Cu")
		(net "M_A_ECC2")
	)
	(segment
		(start 132.6388 -52.6034)
		(end 132.7912 -52.451)
		(width 0.1524)
		(layer "In2.Cu")
		(net "M_A_ECC2")
	)
	(segment
		(start 154.432 -57.5437)
		(end 154.5844 -57.6961)
		(width 0.1524)
		(layer "In2.Cu")
		(net "M_A_ECC2")
	)
	(segment
		(start 136.943338 -51.832256)
		(end 137.095738 -51.984656)
		(width 0.1524)
		(layer "In2.Cu")
		(net "M_A_ECC2")
	)
	(segment
		(start 137.095738 -51.984656)
		(end 137.095738 -52.2478)
		(width 0.1524)
		(layer "In2.Cu")
		(net "M_A_ECC2")
	)
	(segment
		(start 153.8224 -58.6486)
		(end 153.9748 -58.4962)
		(width 0.1524)
		(layer "In2.Cu")
		(net "M_A_ECC2")
	)
	(segment
		(start 156.89326 -57.5437)
		(end 157.04566 -57.6961)
		(width 0.1524)
		(layer "In2.Cu")
		(net "M_A_ECC2")
	)
	(segment
		(start 134.200138 -51.832256)
		(end 134.504938 -51.832256)
		(width 0.1524)
		(layer "In2.Cu")
		(net "M_A_ECC2")
	)
	(segment
		(start 137.248138 -52.4002)
		(end 137.552938 -52.4002)
		(width 0.1524)
		(layer "In2.Cu")
		(net "M_A_ECC2")
	)
	(segment
		(start 135.876538 -52.451)
		(end 136.028938 -52.6034)
		(width 0.1524)
		(layer "In2.Cu")
		(net "M_A_ECC2")
	)
	(segment
		(start 151.372062 -57.6961)
		(end 151.372062 -58.2676)
		(width 0.1524)
		(layer "In2.Cu")
		(net "M_A_ECC2")
	)
	(segment
		(start 135.876538 -51.984656)
		(end 135.876538 -52.451)
		(width 0.1524)
		(layer "In2.Cu")
		(net "M_A_ECC2")
	)
	(segment
		(start 154.5844 -57.6961)
		(end 154.5844 -58.4962)
		(width 0.1524)
		(layer "In2.Cu")
		(net "M_A_ECC2")
	)
	(segment
		(start 134.504938 -51.832256)
		(end 134.657338 -51.984656)
		(width 0.1524)
		(layer "In2.Cu")
		(net "M_A_ECC2")
	)
	(segment
		(start 155.3464 -57.5437)
		(end 156.89326 -57.5437)
		(width 0.1524)
		(layer "In2.Cu")
		(net "M_A_ECC2")
	)
	(segment
		(start 134.657338 -51.984656)
		(end 134.657338 -52.451)
		(width 0.1524)
		(layer "In2.Cu")
		(net "M_A_ECC2")
	)
	(segment
		(start 136.028938 -52.6034)
		(end 136.333738 -52.6034)
		(width 0.1524)
		(layer "In2.Cu")
		(net "M_A_ECC2")
	)
	(segment
		(start 151.219662 -57.5437)
		(end 151.372062 -57.6961)
		(width 0.1524)
		(layer "In2.Cu")
		(net "M_A_ECC2")
	)
	(segment
		(start 136.333738 -52.6034)
		(end 136.486138 -52.451)
		(width 0.1524)
		(layer "In2.Cu")
		(net "M_A_ECC2")
	)
	(segment
		(start 157.19806 -58.1406)
		(end 157.50286 -58.1406)
		(width 0.1524)
		(layer "In2.Cu")
		(net "M_A_ECC2")
	)
	(segment
		(start 137.705338 -51.984656)
		(end 137.857738 -51.832256)
		(width 0.1524)
		(layer "In2.Cu")
		(net "M_A_ECC2")
	)
	(segment
		(start 142.9512 -53.495194)
		(end 146.999706 -57.5437)
		(width 0.1524)
		(layer "In2.Cu")
		(net "M_A_ECC2")
	)
	(segment
		(start 133.285738 -51.832256)
		(end 133.438138 -51.984656)
		(width 0.1524)
		(layer "In2.Cu")
		(net "M_A_ECC2")
	)
	(segment
		(start 154.1272 -57.5437)
		(end 154.432 -57.5437)
		(width 0.1524)
		(layer "In2.Cu")
		(net "M_A_ECC2")
	)
	(segment
		(start 153.5176 -58.6486)
		(end 153.8224 -58.6486)
		(width 0.1524)
		(layer "In2.Cu")
		(net "M_A_ECC2")
	)
	(segment
		(start 136.486138 -52.451)
		(end 136.486138 -51.984656)
		(width 0.1524)
		(layer "In2.Cu")
		(net "M_A_ECC2")
	)
	(segment
		(start 153.3652 -57.6961)
		(end 153.3652 -58.4962)
		(width 0.1524)
		(layer "In2.Cu")
		(net "M_A_ECC2")
	)
	(segment
		(start 153.2128 -57.5437)
		(end 153.3652 -57.6961)
		(width 0.1524)
		(layer "In2.Cu")
		(net "M_A_ECC2")
	)
	(segment
		(start 157.04566 -57.9882)
		(end 157.19806 -58.1406)
		(width 0.1524)
		(layer "In2.Cu")
		(net "M_A_ECC2")
	)
	(segment
		(start 136.486138 -51.984656)
		(end 136.638538 -51.832256)
		(width 0.1524)
		(layer "In2.Cu")
		(net "M_A_ECC2")
	)
	(segment
		(start 155.194 -57.6961)
		(end 155.3464 -57.5437)
		(width 0.1524)
		(layer "In2.Cu")
		(net "M_A_ECC2")
	)
	(segment
		(start 133.438138 -52.451)
		(end 133.590538 -52.6034)
		(width 0.1524)
		(layer "In2.Cu")
		(net "M_A_ECC2")
	)
	(segment
		(start 135.114538 -52.6034)
		(end 135.266938 -52.451)
		(width 0.1524)
		(layer "In2.Cu")
		(net "M_A_ECC2")
	)
	(segment
		(start 134.809738 -52.6034)
		(end 135.114538 -52.6034)
		(width 0.1524)
		(layer "In2.Cu")
		(net "M_A_ECC2")
	)
	(segment
		(start 153.9748 -58.4962)
		(end 153.9748 -57.6961)
		(width 0.1524)
		(layer "In2.Cu")
		(net "M_A_ECC2")
	)
	(segment
		(start 134.657338 -52.451)
		(end 134.809738 -52.6034)
		(width 0.1524)
		(layer "In2.Cu")
		(net "M_A_ECC2")
	)
	(segment
		(start 118.507256 -51.832256)
		(end 117.221 -50.546)
		(width 0.1016)
		(layer "In2.Cu")
		(net "M_A_ECC2")
	)
	(segment
		(start 133.895338 -52.6034)
		(end 134.047738 -52.451)
		(width 0.1524)
		(layer "In2.Cu")
		(net "M_A_ECC2")
	)
	(segment
		(start 132.9436 -51.832256)
		(end 133.285738 -51.832256)
		(width 0.1524)
		(layer "In2.Cu")
		(net "M_A_ECC2")
	)
	(segment
		(start 153.3652 -58.4962)
		(end 153.5176 -58.6486)
		(width 0.1524)
		(layer "In2.Cu")
		(net "M_A_ECC2")
	)
	(segment
		(start 157.65526 -57.9882)
		(end 157.65526 -57.6961)
		(width 0.1524)
		(layer "In2.Cu")
		(net "M_A_ECC2")
	)
	(segment
		(start 132.0038 -51.832256)
		(end 132.1562 -51.984656)
		(width 0.1524)
		(layer "In2.Cu")
		(net "M_A_ECC2")
	)
	(segment
		(start 151.981662 -57.6961)
		(end 152.134062 -57.5437)
		(width 0.1524)
		(layer "In2.Cu")
		(net "M_A_ECC2")
	)
	(segment
		(start 157.80766 -57.5437)
		(end 158.3563 -57.5437)
		(width 0.1524)
		(layer "In2.Cu")
		(net "M_A_ECC2")
	)
	(segment
		(start 134.047738 -51.984656)
		(end 134.200138 -51.832256)
		(width 0.1524)
		(layer "In2.Cu")
		(net "M_A_ECC2")
	)
	(segment
		(start 132.7912 -52.451)
		(end 132.7912 -51.984656)
		(width 0.1524)
		(layer "In2.Cu")
		(net "M_A_ECC2")
	)
	(segment
		(start 135.419338 -51.832256)
		(end 135.724138 -51.832256)
		(width 0.1524)
		(layer "In2.Cu")
		(net "M_A_ECC2")
	)
	(segment
		(start 118.507256 -51.832256)
		(end 132.0038 -51.832256)
		(width 0.1524)
		(layer "In2.Cu")
		(net "M_A_ECC2")
	)
	(segment
		(start 155.194 -58.4962)
		(end 155.194 -57.6961)
		(width 0.1524)
		(layer "In2.Cu")
		(net "M_A_ECC2")
	)
	(segment
		(start 159.4612 -58.6486)
		(end 160.917128 -58.6486)
		(width 0.1524)
		(layer "In2.Cu")
		(net "M_A_ECC2")
	)
	(segment
		(start 137.095738 -52.2478)
		(end 137.248138 -52.4002)
		(width 0.1524)
		(layer "In2.Cu")
		(net "M_A_ECC2")
	)
	(segment
		(start 135.266938 -52.451)
		(end 135.266938 -51.984656)
		(width 0.1524)
		(layer "In2.Cu")
		(net "M_A_ECC2")
	)
	(segment
		(start 151.372062 -58.2676)
		(end 151.524462 -58.42)
		(width 0.1524)
		(layer "In2.Cu")
		(net "M_A_ECC2")
	)
	(segment
		(start 163.904422 -64.389762)
		(end 164.06368 -64.54902)
		(width 0.1524)
		(layer "In2.Cu")
		(net "M_A_ECC2")
	)
	(segment
		(start 158.3563 -57.5437)
		(end 159.4612 -58.6486)
		(width 0.1524)
		(layer "In2.Cu")
		(net "M_A_ECC2")
	)
	(segment
		(start 137.857738 -51.832256)
		(end 142.014194 -51.832256)
		(width 0.1524)
		(layer "In2.Cu")
		(net "M_A_ECC2")
	)
	(segment
		(start 142.9512 -52.769262)
		(end 142.9512 -53.495194)
		(width 0.1524)
		(layer "In2.Cu")
		(net "M_A_ECC2")
	)
	(segment
		(start 157.04566 -57.6961)
		(end 157.04566 -57.9882)
		(width 0.1524)
		(layer "In2.Cu")
		(net "M_A_ECC2")
	)
	(segment
		(start 151.829262 -58.42)
		(end 151.981662 -58.2676)
		(width 0.1524)
		(layer "In2.Cu")
		(net "M_A_ECC2")
	)
	(segment
		(start 97.850198 -41.599866)
		(end 97.480374 -41.96969)
		(width 0.3048)
		(layer "F.Cu")
		(net "PVNN")
	)
	(segment
		(start 92.837 -37.813742)
		(end 93.050868 -37.599874)
		(width 0.3048)
		(layer "F.Cu")
		(net "PVNN")
	)
	(segment
		(start 99.451668 -41.600374)
		(end 99.451668 -41.601136)
		(width 0.3048)
		(layer "F.Cu")
		(net "PVNN")
	)
	(segment
		(start 94.278704 -40.427402)
		(end 94.278704 -40.37076)
		(width 0.3048)
		(layer "F.Cu")
		(net "PVNN")
	)
	(segment
		(start 97.048828 -41.599866)
		(end 96.992186 -41.599866)
		(width 0.3048)
		(layer "F.Cu")
		(net "PVNN")
	)
	(segment
		(start 42.0878 -64.516)
		(end 43.06697 -64.516)
		(width 0.508)
		(layer "F.Cu")
		(net "PVNN")
	)
	(segment
		(start 93.083126 -37.599874)
		(end 93.472 -37.211)
		(width 0.3048)
		(layer "F.Cu")
		(net "PVNN")
	)
	(segment
		(start 97.851468 -41.599866)
		(end 97.850198 -41.599866)
		(width 0.3048)
		(layer "F.Cu")
		(net "PVNN")
	)
	(segment
		(start 97.048828 -41.600374)
		(end 97.048828 -41.599866)
		(width 0.3048)
		(layer "F.Cu")
		(net "PVNN")
	)
	(segment
		(start 93.4593 -40.386)
		(end 93.436694 -40.386)
		(width 0.3048)
		(layer "F.Cu")
		(net "PVNN")
	)
	(segment
		(start 100.249228 -41.600374)
		(end 100.249228 -41.599866)
		(width 0.3048)
		(layer "F.Cu")
		(net "PVNN")
	)
	(segment
		(start 94.651068 -40.799766)
		(end 94.278704 -40.427402)
		(width 0.3048)
		(layer "F.Cu")
		(net "PVNN")
	)
	(segment
		(start 93.050868 -38.399974)
		(end 92.837 -38.186106)
		(width 0.3048)
		(layer "F.Cu")
		(net "PVNN")
	)
	(segment
		(start 94.651068 -39.999666)
		(end 94.279974 -40.37076)
		(width 0.3048)
		(layer "F.Cu")
		(net "PVNN")
	)
	(segment
		(start 93.050868 -37.599874)
		(end 93.083126 -37.599874)
		(width 0.3048)
		(layer "F.Cu")
		(net "PVNN")
	)
	(segment
		(start 94.651068 -40.800274)
		(end 94.651068 -40.799766)
		(width 0.3048)
		(layer "F.Cu")
		(net "PVNN")
	)
	(segment
		(start 100.192586 -41.599866)
		(end 99.821492 -41.97096)
		(width 0.3048)
		(layer "F.Cu")
		(net "PVNN")
	)
	(segment
		(start 93.4593 -40.4368)
		(end 93.4593 -40.386)
		(width 0.3048)
		(layer "F.Cu")
		(net "PVNN")
	)
	(segment
		(start 100.249228 -41.599866)
		(end 100.192586 -41.599866)
		(width 0.3048)
		(layer "F.Cu")
		(net "PVNN")
	)
	(segment
		(start 94.651068 -40.000174)
		(end 94.651068 -39.999666)
		(width 0.3048)
		(layer "F.Cu")
		(net "PVNN")
	)
	(segment
		(start 92.837 -38.186106)
		(end 92.837 -37.813742)
		(width 0.3048)
		(layer "F.Cu")
		(net "PVNN")
	)
	(segment
		(start 96.251268 -41.600374)
		(end 96.251268 -41.601136)
		(width 0.3048)
		(layer "F.Cu")
		(net "PVNN")
	)
	(segment
		(start 97.851468 -41.600374)
		(end 97.851468 -41.599866)
		(width 0.3048)
		(layer "F.Cu")
		(net "PVNN")
	)
	(segment
		(start 94.279974 -40.37076)
		(end 94.278704 -40.37076)
		(width 0.3048)
		(layer "F.Cu")
		(net "PVNN")
	)
	(segment
		(start 99.451668 -41.601136)
		(end 99.821492 -41.97096)
		(width 0.3048)
		(layer "F.Cu")
		(net "PVNN")
	)
	(segment
		(start 93.436694 -40.386)
		(end 93.050868 -40.000174)
		(width 0.3048)
		(layer "F.Cu")
		(net "PVNN")
	)
	(segment
		(start 96.992186 -41.599866)
		(end 96.621092 -41.97096)
		(width 0.3048)
		(layer "F.Cu")
		(net "PVNN")
	)
	(segment
		(start 96.251268 -41.601136)
		(end 96.621092 -41.97096)
		(width 0.3048)
		(layer "F.Cu")
		(net "PVNN")
	)
	(segment
		(start 43.06697 -64.516)
		(end 43.82897 -65.278)
		(width 0.508)
		(layer "F.Cu")
		(net "PVNN")
	)
	(via
		(at 94.273878 -41.22928)
		(size 0.4318)
		(drill 0.2032)
		(layers "F.Cu" "B.Cu")
		(net "PVNN")
	)
	(via
		(at 55.118 -64.2366)
		(size 0.7112)
		(drill 0.4064)
		(layers "F.Cu" "B.Cu")
		(net "PVNN")
	)
	(via
		(at 99.821492 -41.97096)
		(size 0.4318)
		(drill 0.2032)
		(layers "F.Cu" "B.Cu")
		(net "PVNN")
	)
	(via
		(at 93.4593 -40.4368)
		(size 0.4318)
		(drill 0.2032)
		(layers "F.Cu" "B.Cu")
		(net "PVNN")
	)
	(via
		(at 98.2472 -41.9862)
		(size 0.4318)
		(drill 0.2032)
		(layers "F.Cu" "B.Cu")
		(net "PVNN")
	)
	(via
		(at 19.1262 -66.0146)
		(size 0.508)
		(drill 0.254)
		(layers "F.Cu" "B.Cu")
		(net "PVNN")
	)
	(via
		(at 42.0878 -64.516)
		(size 0.508)
		(drill 0.254)
		(layers "F.Cu" "B.Cu")
		(net "PVNN")
	)
	(via
		(at 55.1688 -65.532)
		(size 0.7112)
		(drill 0.4064)
		(layers "F.Cu" "B.Cu")
		(net "PVNN")
	)
	(via
		(at 93.472 -37.211)
		(size 0.4318)
		(drill 0.2032)
		(layers "F.Cu" "B.Cu")
		(net "PVNN")
	)
	(via
		(at 76.4794 -63.1444)
		(size 0.7112)
		(drill 0.3556)
		(layers "F.Cu" "B.Cu")
		(net "PVNN")
	)
	(via
		(at 92.6084 -41.9862)
		(size 0.4318)
		(drill 0.2032)
		(layers "F.Cu" "B.Cu")
		(net "PVNN")
	)
	(via
		(at 76.8604 -64.4144)
		(size 0.508)
		(drill 0.254)
		(layers "F.Cu" "B.Cu")
		(net "PVNN")
	)
	(via
		(at 93.4974 -41.9862)
		(size 0.4318)
		(drill 0.2032)
		(layers "F.Cu" "B.Cu")
		(net "PVNN")
	)
	(via
		(at 96.621092 -41.97096)
		(size 0.4318)
		(drill 0.2032)
		(layers "F.Cu" "B.Cu")
		(net "PVNN")
	)
	(via
		(at 94.278704 -40.37076)
		(size 0.4318)
		(drill 0.2032)
		(layers "F.Cu" "B.Cu")
		(net "PVNN")
	)
	(via
		(at 97.480374 -41.96969)
		(size 0.4318)
		(drill 0.2032)
		(layers "F.Cu" "B.Cu")
		(net "PVNN")
	)
	(via
		(at 56.2102 -64.8716)
		(size 0.7112)
		(drill 0.4064)
		(layers "F.Cu" "B.Cu")
		(net "PVNN")
	)
	(segment
		(start 75.819 -62.484)
		(end 76.4794 -63.1444)
		(width 0.3048)
		(layer "B.Cu")
		(net "PVNN")
	)
	(segment
		(start 19.177 -65.9638)
		(end 19.1262 -66.0146)
		(width 0.2032)
		(layer "B.Cu")
		(net "PVNN")
	)
	(segment
		(start 76.8604 -64.4144)
		(end 76.8604 -63.5254)
		(width 0.3048)
		(layer "B.Cu")
		(net "PVNN")
	)
	(segment
		(start 76.8604 -63.5254)
		(end 76.4794 -63.1444)
		(width 0.3048)
		(layer "B.Cu")
		(net "PVNN")
	)
	(segment
		(start 19.177 -65.2018)
		(end 19.177 -65.9638)
		(width 0.2032)
		(layer "B.Cu")
		(net "PVNN")
	)
	(segment
		(start 75.819 -62.2808)
		(end 75.819 -62.484)
		(width 0.3048)
		(layer "B.Cu")
		(net "PVNN")
	)
	(segment
		(start 42.0878 -65.278)
		(end 42.0878 -64.516)
		(width 0.508)
		(layer "B.Cu")
		(net "PVNN")
	)
	(segment
		(start 20.581366 -70.0024)
		(end 20.073366 -69.4944)
		(width 0.2032)
		(layer "In2.Cu")
		(net "PVNN")
	)
	(segment
		(start 52.7558 -67.945)
		(end 47.117 -67.945)
		(width 0.2032)
		(layer "In2.Cu")
		(net "PVNN")
	)
	(segment
		(start 54.3306 -66.3702)
		(end 52.7558 -67.945)
		(width 0.2032)
		(layer "In2.Cu")
		(net "PVNN")
	)
	(segment
		(start 54.3306 -65.024)
		(end 54.3306 -66.3702)
		(width 0.2032)
		(layer "In2.Cu")
		(net "PVNN")
	)
	(segment
		(start 47.117 -67.945)
		(end 43.307 -71.755)
		(width 0.2032)
		(layer "In2.Cu")
		(net "PVNN")
	)
	(segment
		(start 20.051268 -69.4944)
		(end 19.3802 -68.823332)
		(width 0.2032)
		(layer "In2.Cu")
		(net "PVNN")
	)
	(segment
		(start 19.3802 -68.823332)
		(end 19.3802 -66.2686)
		(width 0.2032)
		(layer "In2.Cu")
		(net "PVNN")
	)
	(segment
		(start 43.307 -71.755)
		(end 27.5082 -71.755)
		(width 0.2032)
		(layer "In2.Cu")
		(net "PVNN")
	)
	(segment
		(start 27.5082 -71.755)
		(end 25.7556 -70.0024)
		(width 0.2032)
		(layer "In2.Cu")
		(net "PVNN")
	)
	(segment
		(start 25.7556 -70.0024)
		(end 20.581366 -70.0024)
		(width 0.2032)
		(layer "In2.Cu")
		(net "PVNN")
	)
	(segment
		(start 20.073366 -69.4944)
		(end 20.051268 -69.4944)
		(width 0.2032)
		(layer "In2.Cu")
		(net "PVNN")
	)
	(segment
		(start 19.3802 -66.2686)
		(end 19.1262 -66.0146)
		(width 0.2032)
		(layer "In2.Cu")
		(net "PVNN")
	)
	(segment
		(start 55.118 -64.2366)
		(end 54.3306 -65.024)
		(width 0.2032)
		(layer "In2.Cu")
		(net "PVNN")
	)
	(segment
		(start 189.250066 -63.892938)
		(end 189.086998 -64.056006)
		(width 0.1778)
		(layer "F.Cu")
		(net "M_A_DQ0")
	)
	(segment
		(start 189.250066 -62.59322)
		(end 189.250066 -63.892938)
		(width 0.1778)
		(layer "F.Cu")
		(net "M_A_DQ0")
	)
	(segment
		(start 105.004108 -41.656254)
		(end 104.564434 -42.095928)
		(width 0.1016)
		(layer "F.Cu")
		(net "M_A_DQ0")
	)
	(segment
		(start 104.564434 -42.095928)
		(end 104.484424 -42.095928)
		(width 0.1016)
		(layer "F.Cu")
		(net "M_A_DQ0")
	)
	(via
		(at 189.086998 -64.056006)
		(size 0.4318)
		(drill 0.2032)
		(layers "F.Cu" "B.Cu")
		(net "M_A_DQ0")
	)
	(via
		(at 104.484424 -42.095928)
		(size 0.4318)
		(drill 0.2032)
		(layers "F.Cu" "B.Cu")
		(net "M_A_DQ0")
	)
	(segment
		(start 188.950092 -63.9191)
		(end 189.086998 -64.056006)
		(width 0.1778)
		(layer "B.Cu")
		(net "M_A_DQ0")
	)
	(segment
		(start 188.950092 -62.599824)
		(end 188.950092 -63.9191)
		(width 0.1778)
		(layer "B.Cu")
		(net "M_A_DQ0")
	)
	(segment
		(start 111.11865 -40.424354)
		(end 111.11865 -40.61333)
		(width 0.1016)
		(layer "In7.Cu")
		(net "M_A_DQ0")
	)
	(segment
		(start 172.786294 -53.037232)
		(end 172.786294 -52.82184)
		(width 0.1524)
		(layer "In7.Cu")
		(net "M_A_DQ0")
	)
	(segment
		(start 182.2958 -59.4106)
		(end 182.080408 -59.4106)
		(width 0.1524)
		(layer "In7.Cu")
		(net "M_A_DQ0")
	)
	(segment
		(start 183.0324 -60.8838)
		(end 182.358792 -60.210192)
		(width 0.1524)
		(layer "In7.Cu")
		(net "M_A_DQ0")
	)
	(segment
		(start 119.173498 -40.839898)
		(end 118.8212 -40.4876)
		(width 0.1524)
		(layer "In7.Cu")
		(net "M_A_DQ0")
	)
	(segment
		(start 185.8772 -61.5696)
		(end 184.9882 -60.8838)
		(width 0.1524)
		(layer "In7.Cu")
		(net "M_A_DQ0")
	)
	(segment
		(start 169.583862 -49.8348)
		(end 169.573448 -49.82464)
		(width 0.1524)
		(layer "In7.Cu")
		(net "M_A_DQ0")
	)
	(segment
		(start 159.431482 -46.863)
		(end 153.40838 -40.839898)
		(width 0.1524)
		(layer "In7.Cu")
		(net "M_A_DQ0")
	)
	(segment
		(start 181.217824 -58.548016)
		(end 181.064916 -58.700924)
		(width 0.1524)
		(layer "In7.Cu")
		(net "M_A_DQ0")
	)
	(segment
		(start 172.13961 -52.390548)
		(end 171.92371 -52.174648)
		(width 0.1524)
		(layer "In7.Cu")
		(net "M_A_DQ0")
	)
	(segment
		(start 171.92371 -51.959256)
		(end 172.108622 -51.774344)
		(width 0.1524)
		(layer "In7.Cu")
		(net "M_A_DQ0")
	)
	(segment
		(start 182.5117 -59.841892)
		(end 182.5117 -59.6265)
		(width 0.1524)
		(layer "In7.Cu")
		(net "M_A_DQ0")
	)
	(segment
		(start 184.9882 -60.8838)
		(end 183.0324 -60.8838)
		(width 0.1524)
		(layer "In7.Cu")
		(net "M_A_DQ0")
	)
	(segment
		(start 181.649116 -58.979308)
		(end 181.649116 -58.763916)
		(width 0.1524)
		(layer "In7.Cu")
		(net "M_A_DQ0")
	)
	(segment
		(start 182.358792 -59.9948)
		(end 182.5117 -59.841892)
		(width 0.1524)
		(layer "In7.Cu")
		(net "M_A_DQ0")
	)
	(segment
		(start 118.8212 -40.4876)
		(end 113.0554 -40.4876)
		(width 0.1524)
		(layer "In7.Cu")
		(net "M_A_DQ0")
	)
	(segment
		(start 188.934598 -63.903606)
		(end 188.934598 -63.876936)
		(width 0.1524)
		(layer "In7.Cu")
		(net "M_A_DQ0")
	)
	(segment
		(start 172.355002 -52.390548)
		(end 172.13961 -52.390548)
		(width 0.1524)
		(layer "In7.Cu")
		(net "M_A_DQ0")
	)
	(segment
		(start 105.74909 -41.00068)
		(end 106.671618 -40.077898)
		(width 0.1016)
		(layer "In7.Cu")
		(net "M_A_DQ0")
	)
	(segment
		(start 164.23767 -46.863)
		(end 159.431482 -46.863)
		(width 0.1524)
		(layer "In7.Cu")
		(net "M_A_DQ0")
	)
	(segment
		(start 112.5982 -40.9448)
		(end 111.887 -40.9448)
		(width 0.1524)
		(layer "In7.Cu")
		(net "M_A_DQ0")
	)
	(segment
		(start 172.755306 -52.205636)
		(end 172.539914 -52.205636)
		(width 0.1524)
		(layer "In7.Cu")
		(net "M_A_DQ0")
	)
	(segment
		(start 172.971206 -52.636928)
		(end 172.971206 -52.421536)
		(width 0.1524)
		(layer "In7.Cu")
		(net "M_A_DQ0")
	)
	(segment
		(start 172.108622 -51.774344)
		(end 172.108622 -51.558952)
		(width 0.1524)
		(layer "In7.Cu")
		(net "M_A_DQ0")
	)
	(segment
		(start 171.492418 -51.527964)
		(end 171.277026 -51.527964)
		(width 0.1524)
		(layer "In7.Cu")
		(net "M_A_DQ0")
	)
	(segment
		(start 153.40838 -40.839898)
		(end 119.173498 -40.839898)
		(width 0.1524)
		(layer "In7.Cu")
		(net "M_A_DQ0")
	)
	(segment
		(start 181.496208 -59.347608)
		(end 181.496208 -59.132216)
		(width 0.1524)
		(layer "In7.Cu")
		(net "M_A_DQ0")
	)
	(segment
		(start 182.080408 -59.4106)
		(end 181.9275 -59.563508)
		(width 0.1524)
		(layer "In7.Cu")
		(net "M_A_DQ0")
	)
	(segment
		(start 174.821342 -53.764942)
		(end 173.514004 -53.764942)
		(width 0.1524)
		(layer "In7.Cu")
		(net "M_A_DQ0")
	)
	(segment
		(start 110.772194 -40.077898)
		(end 111.11865 -40.424354)
		(width 0.1016)
		(layer "In7.Cu")
		(net "M_A_DQ0")
	)
	(segment
		(start 189.086998 -64.056006)
		(end 188.934598 -63.903606)
		(width 0.1524)
		(layer "In7.Cu")
		(net "M_A_DQ0")
	)
	(segment
		(start 105.74909 -41.458642)
		(end 105.74909 -41.00068)
		(width 0.1016)
		(layer "In7.Cu")
		(net "M_A_DQ0")
	)
	(segment
		(start 172.108622 -51.558952)
		(end 171.892722 -51.343052)
		(width 0.1524)
		(layer "In7.Cu")
		(net "M_A_DQ0")
	)
	(segment
		(start 169.573448 -49.82464)
		(end 164.23767 -46.863)
		(width 0.1524)
		(layer "In7.Cu")
		(net "M_A_DQ0")
	)
	(segment
		(start 104.965246 -41.6687)
		(end 105.539032 -41.6687)
		(width 0.1016)
		(layer "In7.Cu")
		(net "M_A_DQ0")
	)
	(segment
		(start 181.496208 -59.132216)
		(end 181.649116 -58.979308)
		(width 0.1524)
		(layer "In7.Cu")
		(net "M_A_DQ0")
	)
	(segment
		(start 177.5206 -56.4642)
		(end 176.57064 -55.51424)
		(width 0.1524)
		(layer "In7.Cu")
		(net "M_A_DQ0")
	)
	(segment
		(start 176.57064 -55.51424)
		(end 176.57064 -55.03164)
		(width 0.1524)
		(layer "In7.Cu")
		(net "M_A_DQ0")
	)
	(segment
		(start 178.6128 -56.4642)
		(end 177.5206 -56.4642)
		(width 0.1524)
		(layer "In7.Cu")
		(net "M_A_DQ0")
	)
	(segment
		(start 181.9275 -59.563508)
		(end 181.712108 -59.563508)
		(width 0.1524)
		(layer "In7.Cu")
		(net "M_A_DQ0")
	)
	(segment
		(start 188.934598 -63.876936)
		(end 188.741304 -63.683642)
		(width 0.1524)
		(layer "In7.Cu")
		(net "M_A_DQ0")
	)
	(segment
		(start 182.5117 -59.6265)
		(end 182.2958 -59.4106)
		(width 0.1524)
		(layer "In7.Cu")
		(net "M_A_DQ0")
	)
	(segment
		(start 104.484424 -42.095928)
		(end 104.538018 -42.095928)
		(width 0.1016)
		(layer "In7.Cu")
		(net "M_A_DQ0")
	)
	(segment
		(start 172.971206 -52.421536)
		(end 172.755306 -52.205636)
		(width 0.1524)
		(layer "In7.Cu")
		(net "M_A_DQ0")
	)
	(segment
		(start 171.92371 -52.174648)
		(end 171.92371 -51.959256)
		(width 0.1524)
		(layer "In7.Cu")
		(net "M_A_DQ0")
	)
	(segment
		(start 188.741304 -63.683642)
		(end 185.8772 -61.5696)
		(width 0.1524)
		(layer "In7.Cu")
		(net "M_A_DQ0")
	)
	(segment
		(start 176.57064 -55.03164)
		(end 176.17694 -54.63794)
		(width 0.1524)
		(layer "In7.Cu")
		(net "M_A_DQ0")
	)
	(segment
		(start 105.539032 -41.6687)
		(end 105.74909 -41.458642)
		(width 0.1016)
		(layer "In7.Cu")
		(net "M_A_DQ0")
	)
	(segment
		(start 180.849524 -58.700924)
		(end 178.6128 -56.4642)
		(width 0.1524)
		(layer "In7.Cu")
		(net "M_A_DQ0")
	)
	(segment
		(start 182.358792 -60.210192)
		(end 182.358792 -59.9948)
		(width 0.1524)
		(layer "In7.Cu")
		(net "M_A_DQ0")
	)
	(segment
		(start 106.671618 -40.077898)
		(end 110.772194 -40.077898)
		(width 0.1016)
		(layer "In7.Cu")
		(net "M_A_DQ0")
	)
	(segment
		(start 171.67733 -51.343052)
		(end 171.492418 -51.527964)
		(width 0.1524)
		(layer "In7.Cu")
		(net "M_A_DQ0")
	)
	(segment
		(start 176.17694 -54.63794)
		(end 175.69434 -54.63794)
		(width 0.1524)
		(layer "In7.Cu")
		(net "M_A_DQ0")
	)
	(segment
		(start 181.433216 -58.548016)
		(end 181.217824 -58.548016)
		(width 0.1524)
		(layer "In7.Cu")
		(net "M_A_DQ0")
	)
	(segment
		(start 181.064916 -58.700924)
		(end 180.849524 -58.700924)
		(width 0.1524)
		(layer "In7.Cu")
		(net "M_A_DQ0")
	)
	(segment
		(start 171.892722 -51.343052)
		(end 171.67733 -51.343052)
		(width 0.1524)
		(layer "In7.Cu")
		(net "M_A_DQ0")
	)
	(segment
		(start 175.69434 -54.63794)
		(end 174.821342 -53.764942)
		(width 0.1524)
		(layer "In7.Cu")
		(net "M_A_DQ0")
	)
	(segment
		(start 171.277026 -51.527964)
		(end 169.583862 -49.8348)
		(width 0.1524)
		(layer "In7.Cu")
		(net "M_A_DQ0")
	)
	(segment
		(start 104.538018 -42.095928)
		(end 104.965246 -41.6687)
		(width 0.1016)
		(layer "In7.Cu")
		(net "M_A_DQ0")
	)
	(segment
		(start 111.45012 -40.9448)
		(end 111.887 -40.9448)
		(width 0.1016)
		(layer "In7.Cu")
		(net "M_A_DQ0")
	)
	(segment
		(start 181.649116 -58.763916)
		(end 181.433216 -58.548016)
		(width 0.1524)
		(layer "In7.Cu")
		(net "M_A_DQ0")
	)
	(segment
		(start 173.514004 -53.764942)
		(end 172.786294 -53.037232)
		(width 0.1524)
		(layer "In7.Cu")
		(net "M_A_DQ0")
	)
	(segment
		(start 113.0554 -40.4876)
		(end 112.5982 -40.9448)
		(width 0.1524)
		(layer "In7.Cu")
		(net "M_A_DQ0")
	)
	(segment
		(start 111.11865 -40.61333)
		(end 111.45012 -40.9448)
		(width 0.1016)
		(layer "In7.Cu")
		(net "M_A_DQ0")
	)
	(segment
		(start 181.712108 -59.563508)
		(end 181.496208 -59.347608)
		(width 0.1524)
		(layer "In7.Cu")
		(net "M_A_DQ0")
	)
	(segment
		(start 172.786294 -52.82184)
		(end 172.971206 -52.636928)
		(width 0.1524)
		(layer "In7.Cu")
		(net "M_A_DQ0")
	)
	(segment
		(start 172.539914 -52.205636)
		(end 172.355002 -52.390548)
		(width 0.1524)
		(layer "In7.Cu")
		(net "M_A_DQ0")
	)
	(segment
		(start 95.072454 -40.4241)
		(end 95.448628 -40.800274)
		(width 0.127)
		(layer "F.Cu")
		(net "TP_CPU_RSVD8")
	)
	(segment
		(start 95.0214 -40.4241)
		(end 95.072454 -40.4241)
		(width 0.127)
		(layer "F.Cu")
		(net "TP_CPU_RSVD8")
	)
	(via
		(at 95.0214 -40.4241)
		(size 0.4318)
		(drill 0.2032)
		(layers "F.Cu" "B.Cu")
		(net "TP_CPU_RSVD8")
	)
	(segment
		(start 94.4118 -39.867332)
		(end 94.4118 -39.73576)
		(width 0.127)
		(layer "B.Cu")
		(net "TP_CPU_RSVD8")
	)
	(segment
		(start 94.968568 -40.4241)
		(end 94.4118 -39.867332)
		(width 0.127)
		(layer "B.Cu")
		(net "TP_CPU_RSVD8")
	)
	(segment
		(start 95.0214 -40.4241)
		(end 94.968568 -40.4241)
		(width 0.127)
		(layer "B.Cu")
		(net "TP_CPU_RSVD8")
	)
	(segment
		(start 105.3973 -46.09084)
		(end 105.45064 -46.0375)
		(width 0.1016)
		(layer "F.Cu")
		(net "M_A_DQ22")
	)
	(segment
		(start 105.766108 -45.685456)
		(end 105.766108 -45.628814)
		(width 0.1016)
		(layer "F.Cu")
		(net "M_A_DQ22")
	)
	(segment
		(start 175.749966 -69.493638)
		(end 175.904398 -69.339206)
		(width 0.1778)
		(layer "F.Cu")
		(net "M_A_DQ22")
	)
	(segment
		(start 105.45064 -46.000924)
		(end 105.766108 -45.685456)
		(width 0.1016)
		(layer "F.Cu")
		(net "M_A_DQ22")
	)
	(segment
		(start 175.749966 -70.806564)
		(end 175.749966 -69.493638)
		(width 0.1778)
		(layer "F.Cu")
		(net "M_A_DQ22")
	)
	(segment
		(start 105.45064 -46.0375)
		(end 105.45064 -46.000924)
		(width 0.1016)
		(layer "F.Cu")
		(net "M_A_DQ22")
	)
	(via
		(at 175.904398 -69.339206)
		(size 0.4318)
		(drill 0.2032)
		(layers "F.Cu" "B.Cu")
		(net "M_A_DQ22")
	)
	(via
		(at 105.3973 -46.09084)
		(size 0.4318)
		(drill 0.2032)
		(layers "F.Cu" "B.Cu")
		(net "M_A_DQ22")
	)
	(segment
		(start 176.04994 -69.484748)
		(end 175.904398 -69.339206)
		(width 0.1778)
		(layer "B.Cu")
		(net "M_A_DQ22")
	)
	(segment
		(start 176.04994 -70.79996)
		(end 176.04994 -69.484748)
		(width 0.1778)
		(layer "B.Cu")
		(net "M_A_DQ22")
	)
	(segment
		(start 175.2346 -62.3062)
		(end 170.250866 -62.3062)
		(width 0.1524)
		(layer "In4.Cu")
		(net "M_A_DQ22")
	)
	(segment
		(start 111.032798 -49.332642)
		(end 111.021368 -49.332642)
		(width 0.1016)
		(layer "In4.Cu")
		(net "M_A_DQ22")
	)
	(segment
		(start 107.07878 -46.9519)
		(end 106.7562 -46.62932)
		(width 0.1016)
		(layer "In4.Cu")
		(net "M_A_DQ22")
	)
	(segment
		(start 176.6697 -65.6209)
		(end 176.6697 -63.7413)
		(width 0.1524)
		(layer "In4.Cu")
		(net "M_A_DQ22")
	)
	(segment
		(start 112.8268 -52.1716)
		(end 110.8964 -50.2412)
		(width 0.1524)
		(layer "In4.Cu")
		(net "M_A_DQ22")
	)
	(segment
		(start 144.442434 -52.3494)
		(end 142.766034 -50.673)
		(width 0.1524)
		(layer "In4.Cu")
		(net "M_A_DQ22")
	)
	(segment
		(start 175.904398 -69.339206)
		(end 175.904398 -68.852542)
		(width 0.1524)
		(layer "In4.Cu")
		(net "M_A_DQ22")
	)
	(segment
		(start 145.701004 -52.3494)
		(end 144.442434 -52.3494)
		(width 0.1524)
		(layer "In4.Cu")
		(net "M_A_DQ22")
	)
	(segment
		(start 110.236 -48.547274)
		(end 110.236 -48.1584)
		(width 0.1016)
		(layer "In4.Cu")
		(net "M_A_DQ22")
	)
	(segment
		(start 111.021368 -49.332642)
		(end 110.236 -48.547274)
		(width 0.1016)
		(layer "In4.Cu")
		(net "M_A_DQ22")
	)
	(segment
		(start 142.766034 -50.673)
		(end 123.149614 -50.673)
		(width 0.1524)
		(layer "In4.Cu")
		(net "M_A_DQ22")
	)
	(segment
		(start 175.904398 -68.852542)
		(end 176.1998 -68.55714)
		(width 0.1524)
		(layer "In4.Cu")
		(net "M_A_DQ22")
	)
	(segment
		(start 167.268906 -59.32424)
		(end 165.201092 -59.32424)
		(width 0.1524)
		(layer "In4.Cu")
		(net "M_A_DQ22")
	)
	(segment
		(start 176.1998 -68.55714)
		(end 176.1998 -66.0908)
		(width 0.1524)
		(layer "In4.Cu")
		(net "M_A_DQ22")
	)
	(segment
		(start 106.482896 -46.005496)
		(end 105.482644 -46.005496)
		(width 0.1016)
		(layer "In4.Cu")
		(net "M_A_DQ22")
	)
	(segment
		(start 149.942804 -56.5912)
		(end 145.701004 -52.3494)
		(width 0.1524)
		(layer "In4.Cu")
		(net "M_A_DQ22")
	)
	(segment
		(start 123.149614 -50.673)
		(end 122.692414 -51.1302)
		(width 0.1524)
		(layer "In4.Cu")
		(net "M_A_DQ22")
	)
	(segment
		(start 118.2878 -51.1302)
		(end 117.2464 -52.1716)
		(width 0.1524)
		(layer "In4.Cu")
		(net "M_A_DQ22")
	)
	(segment
		(start 162.468052 -56.5912)
		(end 149.942804 -56.5912)
		(width 0.1524)
		(layer "In4.Cu")
		(net "M_A_DQ22")
	)
	(segment
		(start 176.1998 -66.0908)
		(end 176.6697 -65.6209)
		(width 0.1524)
		(layer "In4.Cu")
		(net "M_A_DQ22")
	)
	(segment
		(start 117.2464 -52.1716)
		(end 112.8268 -52.1716)
		(width 0.1524)
		(layer "In4.Cu")
		(net "M_A_DQ22")
	)
	(segment
		(start 107.9246 -47.752)
		(end 107.6198 -47.4472)
		(width 0.1016)
		(layer "In4.Cu")
		(net "M_A_DQ22")
	)
	(segment
		(start 110.236 -48.1584)
		(end 109.8296 -47.752)
		(width 0.1016)
		(layer "In4.Cu")
		(net "M_A_DQ22")
	)
	(segment
		(start 107.6198 -47.1678)
		(end 107.4039 -46.9519)
		(width 0.1016)
		(layer "In4.Cu")
		(net "M_A_DQ22")
	)
	(segment
		(start 106.7562 -46.2788)
		(end 106.482896 -46.005496)
		(width 0.1016)
		(layer "In4.Cu")
		(net "M_A_DQ22")
	)
	(segment
		(start 176.6697 -63.7413)
		(end 175.2346 -62.3062)
		(width 0.1524)
		(layer "In4.Cu")
		(net "M_A_DQ22")
	)
	(segment
		(start 165.201092 -59.32424)
		(end 162.468052 -56.5912)
		(width 0.1524)
		(layer "In4.Cu")
		(net "M_A_DQ22")
	)
	(segment
		(start 111.07928 -49.379124)
		(end 111.032798 -49.332642)
		(width 0.1016)
		(layer "In4.Cu")
		(net "M_A_DQ22")
	)
	(segment
		(start 107.4039 -46.9519)
		(end 107.07878 -46.9519)
		(width 0.1016)
		(layer "In4.Cu")
		(net "M_A_DQ22")
	)
	(segment
		(start 109.8296 -47.752)
		(end 107.9246 -47.752)
		(width 0.1016)
		(layer "In4.Cu")
		(net "M_A_DQ22")
	)
	(segment
		(start 111.07928 -49.75352)
		(end 111.07928 -49.379124)
		(width 0.1016)
		(layer "In4.Cu")
		(net "M_A_DQ22")
	)
	(segment
		(start 106.7562 -46.62932)
		(end 106.7562 -46.2788)
		(width 0.1016)
		(layer "In4.Cu")
		(net "M_A_DQ22")
	)
	(segment
		(start 122.692414 -51.1302)
		(end 118.2878 -51.1302)
		(width 0.1524)
		(layer "In4.Cu")
		(net "M_A_DQ22")
	)
	(segment
		(start 107.6198 -47.4472)
		(end 107.6198 -47.1678)
		(width 0.1016)
		(layer "In4.Cu")
		(net "M_A_DQ22")
	)
	(segment
		(start 110.8964 -50.2412)
		(end 110.8964 -49.9364)
		(width 0.1016)
		(layer "In4.Cu")
		(net "M_A_DQ22")
	)
	(segment
		(start 105.482644 -46.005496)
		(end 105.3973 -46.09084)
		(width 0.1016)
		(layer "In4.Cu")
		(net "M_A_DQ22")
	)
	(segment
		(start 110.8964 -49.9364)
		(end 111.07928 -49.75352)
		(width 0.1016)
		(layer "In4.Cu")
		(net "M_A_DQ22")
	)
	(segment
		(start 170.250866 -62.3062)
		(end 167.268906 -59.32424)
		(width 0.1524)
		(layer "In4.Cu")
		(net "M_A_DQ22")
	)
	(segment
		(start 70.75805 -45.73905)
		(end 70.75805 -46.318424)
		(width 0.1143)
		(layer "F.Cu")
		(net "SMBUS_PECI_CLK")
	)
	(segment
		(start 73.832974 -46.223174)
		(end 74.78268 -46.223174)
		(width 0.1143)
		(layer "F.Cu")
		(net "SMBUS_PECI_CLK")
	)
	(segment
		(start 74.78268 -46.223174)
		(end 75.99045 -45.015404)
		(width 0.1143)
		(layer "F.Cu")
		(net "SMBUS_PECI_CLK")
	)
	(segment
		(start 80.017112 -42.813478)
		(end 80.043528 -42.839894)
		(width 0.1143)
		(layer "F.Cu")
		(net "SMBUS_PECI_CLK")
	)
	(segment
		(start 75.99045 -43.829732)
		(end 77.006704 -42.813478)
		(width 0.1143)
		(layer "F.Cu")
		(net "SMBUS_PECI_CLK")
	)
	(segment
		(start 73.42505 -46.58995)
		(end 73.8124 -46.2026)
		(width 0.1143)
		(layer "F.Cu")
		(net "SMBUS_PECI_CLK")
	)
	(segment
		(start 71.029576 -46.58995)
		(end 73.42505 -46.58995)
		(width 0.1143)
		(layer "F.Cu")
		(net "SMBUS_PECI_CLK")
	)
	(segment
		(start 75.99045 -45.015404)
		(end 75.99045 -43.829732)
		(width 0.1143)
		(layer "F.Cu")
		(net "SMBUS_PECI_CLK")
	)
	(segment
		(start 73.8124 -46.2026)
		(end 73.832974 -46.223174)
		(width 0.1143)
		(layer "F.Cu")
		(net "SMBUS_PECI_CLK")
	)
	(segment
		(start 70.75805 -46.318424)
		(end 71.029576 -46.58995)
		(width 0.1143)
		(layer "F.Cu")
		(net "SMBUS_PECI_CLK")
	)
	(segment
		(start 77.006704 -42.813478)
		(end 80.017112 -42.813478)
		(width 0.1143)
		(layer "F.Cu")
		(net "SMBUS_PECI_CLK")
	)
	(segment
		(start 69.5198 -45.3136)
		(end 70.3326 -45.3136)
		(width 0.1143)
		(layer "F.Cu")
		(net "SMBUS_PECI_CLK")
	)
	(segment
		(start 70.3326 -45.3136)
		(end 70.75805 -45.73905)
		(width 0.1143)
		(layer "F.Cu")
		(net "SMBUS_PECI_CLK")
	)
	(via
		(at 73.8124 -46.2026)
		(size 0.7112)
		(drill 0.3556)
		(layers "F.Cu" "B.Cu")
		(net "SMBUS_PECI_CLK")
	)
	(segment
		(start 17.272 -49.911)
		(end 17.272 -50.3682)
		(width 0.2032)
		(layer "F.Cu")
		(net "VR_PVCCP_COMP_RC")
	)
	(segment
		(start 16.9926 -48.895)
		(end 16.9926 -49.6316)
		(width 0.2032)
		(layer "F.Cu")
		(net "VR_PVCCP_COMP_RC")
	)
	(segment
		(start 17.272 -50.3682)
		(end 16.51 -50.3682)
		(width 0.2032)
		(layer "F.Cu")
		(net "VR_PVCCP_COMP_RC")
	)
	(segment
		(start 16.9926 -49.6316)
		(end 17.272 -49.911)
		(width 0.2032)
		(layer "F.Cu")
		(net "VR_PVCCP_COMP_RC")
	)
	(via
		(at 16.9926 -48.895)
		(size 0.7112)
		(drill 0.3556)
		(layers "F.Cu" "B.Cu")
		(net "VR_PVCCP_COMP_RC")
	)
	(segment
		(start 111.792258 -47.838106)
		(end 111.73206 -47.898304)
		(width 0.1016)
		(layer "F.Cu")
		(net "M_A_ECC3")
	)
	(segment
		(start 163.450016 -62.59322)
		(end 163.450016 -63.876936)
		(width 0.1778)
		(layer "F.Cu")
		(net "M_A_ECC3")
	)
	(segment
		(start 116.713 -50.9778)
		(end 116.2558 -51.435)
		(width 0.1016)
		(layer "F.Cu")
		(net "M_A_ECC3")
	)
	(segment
		(start 113.411 -49.159668)
		(end 112.089438 -47.838106)
		(width 0.1016)
		(layer "F.Cu")
		(net "M_A_ECC3")
	)
	(segment
		(start 111.216186 -47.640494)
		(end 110.645448 -47.640494)
		(width 0.1016)
		(layer "F.Cu")
		(net "M_A_ECC3")
	)
	(segment
		(start 116.2558 -51.435)
		(end 114.4778 -51.435)
		(width 0.1016)
		(layer "F.Cu")
		(net "M_A_ECC3")
	)
	(segment
		(start 114.4778 -51.435)
		(end 113.411 -50.3682)
		(width 0.1016)
		(layer "F.Cu")
		(net "M_A_ECC3")
	)
	(segment
		(start 163.450016 -63.876936)
		(end 163.271708 -64.055244)
		(width 0.1778)
		(layer "F.Cu")
		(net "M_A_ECC3")
	)
	(segment
		(start 111.473996 -47.898304)
		(end 111.216186 -47.640494)
		(width 0.1016)
		(layer "F.Cu")
		(net "M_A_ECC3")
	)
	(segment
		(start 111.73206 -47.898304)
		(end 111.473996 -47.898304)
		(width 0.1016)
		(layer "F.Cu")
		(net "M_A_ECC3")
	)
	(segment
		(start 112.089438 -47.838106)
		(end 111.792258 -47.838106)
		(width 0.1016)
		(layer "F.Cu")
		(net "M_A_ECC3")
	)
	(segment
		(start 113.411 -50.3682)
		(end 113.411 -49.159668)
		(width 0.1016)
		(layer "F.Cu")
		(net "M_A_ECC3")
	)
	(via
		(at 116.713 -50.9778)
		(size 0.4318)
		(drill 0.2032)
		(layers "F.Cu" "B.Cu")
		(net "M_A_ECC3")
	)
	(via
		(at 163.271708 -64.055244)
		(size 0.4318)
		(drill 0.2032)
		(layers "F.Cu" "B.Cu")
		(net "M_A_ECC3")
	)
	(segment
		(start 163.150042 -62.599824)
		(end 163.150042 -63.933578)
		(width 0.1778)
		(layer "B.Cu")
		(net "M_A_ECC3")
	)
	(segment
		(start 163.150042 -63.933578)
		(end 163.271708 -64.055244)
		(width 0.1778)
		(layer "B.Cu")
		(net "M_A_ECC3")
	)
	(segment
		(start 121.948448 -52.416456)
		(end 121.796048 -52.568856)
		(width 0.1524)
		(layer "In2.Cu")
		(net "M_A_ECC3")
	)
	(segment
		(start 119.510048 -52.416456)
		(end 119.357648 -52.568856)
		(width 0.1524)
		(layer "In2.Cu")
		(net "M_A_ECC3")
	)
	(segment
		(start 122.558048 -53.1876)
		(end 122.405648 -53.0352)
		(width 0.1524)
		(layer "In2.Cu")
		(net "M_A_ECC3")
	)
	(segment
		(start 126.672848 -52.568856)
		(end 126.672848 -53.0352)
		(width 0.1524)
		(layer "In2.Cu")
		(net "M_A_ECC3")
	)
	(segment
		(start 118.748048 -52.809648)
		(end 118.354856 -52.416456)
		(width 0.1524)
		(layer "In2.Cu")
		(net "M_A_ECC3")
	)
	(segment
		(start 129.111248 -53.0352)
		(end 128.958848 -53.1876)
		(width 0.1524)
		(layer "In2.Cu")
		(net "M_A_ECC3")
	)
	(segment
		(start 131.4196 -52.5526)
		(end 131.1148 -52.5526)
		(width 0.1524)
		(layer "In2.Cu")
		(net "M_A_ECC3")
	)
	(segment
		(start 127.434848 -53.1876)
		(end 127.282448 -53.0352)
		(width 0.1524)
		(layer "In2.Cu")
		(net "M_A_ECC3")
	)
	(segment
		(start 121.186448 -52.568856)
		(end 121.034048 -52.416456)
		(width 0.1524)
		(layer "In2.Cu")
		(net "M_A_ECC3")
	)
	(segment
		(start 123.777248 -53.1876)
		(end 123.624848 -53.0352)
		(width 0.1524)
		(layer "In2.Cu")
		(net "M_A_ECC3")
	)
	(segment
		(start 141.9098 -52.6034)
		(end 138.8618 -52.6034)
		(width 0.1524)
		(layer "In2.Cu")
		(net "M_A_ECC3")
	)
	(segment
		(start 122.405648 -53.0352)
		(end 122.405648 -52.568856)
		(width 0.1524)
		(layer "In2.Cu")
		(net "M_A_ECC3")
	)
	(segment
		(start 116.9162 -50.9778)
		(end 116.713 -50.9778)
		(width 0.1016)
		(layer "In2.Cu")
		(net "M_A_ECC3")
	)
	(segment
		(start 124.082048 -53.1876)
		(end 123.777248 -53.1876)
		(width 0.1524)
		(layer "In2.Cu")
		(net "M_A_ECC3")
	)
	(segment
		(start 120.576848 -53.0352)
		(end 120.424448 -53.1876)
		(width 0.1524)
		(layer "In2.Cu")
		(net "M_A_ECC3")
	)
	(segment
		(start 118.900448 -53.1876)
		(end 118.748048 -53.0352)
		(width 0.1524)
		(layer "In2.Cu")
		(net "M_A_ECC3")
	)
	(segment
		(start 130.81 -53.1876)
		(end 130.415538 -53.1876)
		(width 0.1524)
		(layer "In2.Cu")
		(net "M_A_ECC3")
	)
	(segment
		(start 121.796048 -52.568856)
		(end 121.796048 -53.0352)
		(width 0.1524)
		(layer "In2.Cu")
		(net "M_A_ECC3")
	)
	(segment
		(start 119.357648 -53.0352)
		(end 119.205248 -53.1876)
		(width 0.1524)
		(layer "In2.Cu")
		(net "M_A_ECC3")
	)
	(segment
		(start 126.520448 -53.1876)
		(end 126.215648 -53.1876)
		(width 0.1524)
		(layer "In2.Cu")
		(net "M_A_ECC3")
	)
	(segment
		(start 118.748048 -53.0352)
		(end 118.748048 -52.809648)
		(width 0.1524)
		(layer "In2.Cu")
		(net "M_A_ECC3")
	)
	(segment
		(start 163.271708 -64.055244)
		(end 163.271708 -61.829442)
		(width 0.1524)
		(layer "In2.Cu")
		(net "M_A_ECC3")
	)
	(segment
		(start 123.015248 -53.0352)
		(end 122.862848 -53.1876)
		(width 0.1524)
		(layer "In2.Cu")
		(net "M_A_ECC3")
	)
	(segment
		(start 122.405648 -52.568856)
		(end 122.253248 -52.416456)
		(width 0.1524)
		(layer "In2.Cu")
		(net "M_A_ECC3")
	)
	(segment
		(start 123.472448 -52.416456)
		(end 123.167648 -52.416456)
		(width 0.1524)
		(layer "In2.Cu")
		(net "M_A_ECC3")
	)
	(segment
		(start 125.453648 -53.0352)
		(end 125.301248 -53.1876)
		(width 0.1524)
		(layer "In2.Cu")
		(net "M_A_ECC3")
	)
	(segment
		(start 123.624848 -52.568856)
		(end 123.472448 -52.416456)
		(width 0.1524)
		(layer "In2.Cu")
		(net "M_A_ECC3")
	)
	(segment
		(start 119.814848 -52.416456)
		(end 119.510048 -52.416456)
		(width 0.1524)
		(layer "In2.Cu")
		(net "M_A_ECC3")
	)
	(segment
		(start 142.367 -53.737256)
		(end 142.367 -53.0606)
		(width 0.1524)
		(layer "In2.Cu")
		(net "M_A_ECC3")
	)
	(segment
		(start 128.501648 -52.568856)
		(end 128.349248 -52.416456)
		(width 0.1524)
		(layer "In2.Cu")
		(net "M_A_ECC3")
	)
	(segment
		(start 121.186448 -53.0352)
		(end 121.186448 -52.568856)
		(width 0.1524)
		(layer "In2.Cu")
		(net "M_A_ECC3")
	)
	(segment
		(start 138.2776 -53.1876)
		(end 131.7244 -53.1876)
		(width 0.1524)
		(layer "In2.Cu")
		(net "M_A_ECC3")
	)
	(segment
		(start 127.739648 -53.1876)
		(end 127.434848 -53.1876)
		(width 0.1524)
		(layer "In2.Cu")
		(net "M_A_ECC3")
	)
	(segment
		(start 127.282448 -52.568856)
		(end 127.130048 -52.416456)
		(width 0.1524)
		(layer "In2.Cu")
		(net "M_A_ECC3")
	)
	(segment
		(start 120.119648 -53.1876)
		(end 119.967248 -53.0352)
		(width 0.1524)
		(layer "In2.Cu")
		(net "M_A_ECC3")
	)
	(segment
		(start 125.910848 -52.416456)
		(end 125.606048 -52.416456)
		(width 0.1524)
		(layer "In2.Cu")
		(net "M_A_ECC3")
	)
	(segment
		(start 124.844048 -53.0352)
		(end 124.844048 -52.568856)
		(width 0.1524)
		(layer "In2.Cu")
		(net "M_A_ECC3")
	)
	(segment
		(start 121.796048 -53.0352)
		(end 121.643648 -53.1876)
		(width 0.1524)
		(layer "In2.Cu")
		(net "M_A_ECC3")
	)
	(segment
		(start 123.624848 -53.0352)
		(end 123.624848 -52.568856)
		(width 0.1524)
		(layer "In2.Cu")
		(net "M_A_ECC3")
	)
	(segment
		(start 127.892048 -52.568856)
		(end 127.892048 -53.0352)
		(width 0.1524)
		(layer "In2.Cu")
		(net "M_A_ECC3")
	)
	(segment
		(start 118.354856 -52.416456)
		(end 116.9162 -50.9778)
		(width 0.1016)
		(layer "In2.Cu")
		(net "M_A_ECC3")
	)
	(segment
		(start 130.263138 -53.0352)
		(end 130.263138 -52.568856)
		(width 0.1524)
		(layer "In2.Cu")
		(net "M_A_ECC3")
	)
	(segment
		(start 124.844048 -52.568856)
		(end 124.691648 -52.416456)
		(width 0.1524)
		(layer "In2.Cu")
		(net "M_A_ECC3")
	)
	(segment
		(start 119.205248 -53.1876)
		(end 118.900448 -53.1876)
		(width 0.1524)
		(layer "In2.Cu")
		(net "M_A_ECC3")
	)
	(segment
		(start 124.234448 -52.568856)
		(end 124.234448 -53.0352)
		(width 0.1524)
		(layer "In2.Cu")
		(net "M_A_ECC3")
	)
	(segment
		(start 120.424448 -53.1876)
		(end 120.119648 -53.1876)
		(width 0.1524)
		(layer "In2.Cu")
		(net "M_A_ECC3")
	)
	(segment
		(start 160.675066 -59.2328)
		(end 151.511 -59.2328)
		(width 0.1524)
		(layer "In2.Cu")
		(net "M_A_ECC3")
	)
	(segment
		(start 127.892048 -53.0352)
		(end 127.739648 -53.1876)
		(width 0.1524)
		(layer "In2.Cu")
		(net "M_A_ECC3")
	)
	(segment
		(start 131.572 -52.705)
		(end 131.4196 -52.5526)
		(width 0.1524)
		(layer "In2.Cu")
		(net "M_A_ECC3")
	)
	(segment
		(start 125.301248 -53.1876)
		(end 124.996448 -53.1876)
		(width 0.1524)
		(layer "In2.Cu")
		(net "M_A_ECC3")
	)
	(segment
		(start 121.643648 -53.1876)
		(end 121.338848 -53.1876)
		(width 0.1524)
		(layer "In2.Cu")
		(net "M_A_ECC3")
	)
	(segment
		(start 122.862848 -53.1876)
		(end 122.558048 -53.1876)
		(width 0.1524)
		(layer "In2.Cu")
		(net "M_A_ECC3")
	)
	(segment
		(start 163.271708 -61.829442)
		(end 160.675066 -59.2328)
		(width 0.1524)
		(layer "In2.Cu")
		(net "M_A_ECC3")
	)
	(segment
		(start 121.338848 -53.1876)
		(end 121.186448 -53.0352)
		(width 0.1524)
		(layer "In2.Cu")
		(net "M_A_ECC3")
	)
	(segment
		(start 128.501648 -53.0352)
		(end 128.501648 -52.568856)
		(width 0.1524)
		(layer "In2.Cu")
		(net "M_A_ECC3")
	)
	(segment
		(start 131.572 -53.0352)
		(end 131.572 -52.705)
		(width 0.1524)
		(layer "In2.Cu")
		(net "M_A_ECC3")
	)
	(segment
		(start 130.263138 -52.568856)
		(end 130.110738 -52.416456)
		(width 0.1524)
		(layer "In2.Cu")
		(net "M_A_ECC3")
	)
	(segment
		(start 129.263648 -52.416456)
		(end 129.111248 -52.568856)
		(width 0.1524)
		(layer "In2.Cu")
		(net "M_A_ECC3")
	)
	(segment
		(start 124.386848 -52.416456)
		(end 124.234448 -52.568856)
		(width 0.1524)
		(layer "In2.Cu")
		(net "M_A_ECC3")
	)
	(segment
		(start 130.415538 -53.1876)
		(end 130.263138 -53.0352)
		(width 0.1524)
		(layer "In2.Cu")
		(net "M_A_ECC3")
	)
	(segment
		(start 124.691648 -52.416456)
		(end 124.386848 -52.416456)
		(width 0.1524)
		(layer "In2.Cu")
		(net "M_A_ECC3")
	)
	(segment
		(start 126.063248 -52.568856)
		(end 125.910848 -52.416456)
		(width 0.1524)
		(layer "In2.Cu")
		(net "M_A_ECC3")
	)
	(segment
		(start 120.729248 -52.416456)
		(end 120.576848 -52.568856)
		(width 0.1524)
		(layer "In2.Cu")
		(net "M_A_ECC3")
	)
	(segment
		(start 121.034048 -52.416456)
		(end 120.729248 -52.416456)
		(width 0.1524)
		(layer "In2.Cu")
		(net "M_A_ECC3")
	)
	(segment
		(start 119.357648 -52.568856)
		(end 119.357648 -53.0352)
		(width 0.1524)
		(layer "In2.Cu")
		(net "M_A_ECC3")
	)
	(segment
		(start 131.1148 -52.5526)
		(end 130.9624 -52.705)
		(width 0.1524)
		(layer "In2.Cu")
		(net "M_A_ECC3")
	)
	(segment
		(start 130.110738 -52.416456)
		(end 129.263648 -52.416456)
		(width 0.1524)
		(layer "In2.Cu")
		(net "M_A_ECC3")
	)
	(segment
		(start 128.654048 -53.1876)
		(end 128.501648 -53.0352)
		(width 0.1524)
		(layer "In2.Cu")
		(net "M_A_ECC3")
	)
	(segment
		(start 126.825248 -52.416456)
		(end 126.672848 -52.568856)
		(width 0.1524)
		(layer "In2.Cu")
		(net "M_A_ECC3")
	)
	(segment
		(start 123.015248 -52.568856)
		(end 123.015248 -53.0352)
		(width 0.1524)
		(layer "In2.Cu")
		(net "M_A_ECC3")
	)
	(segment
		(start 146.757644 -58.1279)
		(end 142.367 -53.737256)
		(width 0.1524)
		(layer "In2.Cu")
		(net "M_A_ECC3")
	)
	(segment
		(start 124.996448 -53.1876)
		(end 124.844048 -53.0352)
		(width 0.1524)
		(layer "In2.Cu")
		(net "M_A_ECC3")
	)
	(segment
		(start 130.9624 -53.0352)
		(end 130.81 -53.1876)
		(width 0.1524)
		(layer "In2.Cu")
		(net "M_A_ECC3")
	)
	(segment
		(start 122.253248 -52.416456)
		(end 121.948448 -52.416456)
		(width 0.1524)
		(layer "In2.Cu")
		(net "M_A_ECC3")
	)
	(segment
		(start 119.967248 -52.568856)
		(end 119.814848 -52.416456)
		(width 0.1524)
		(layer "In2.Cu")
		(net "M_A_ECC3")
	)
	(segment
		(start 127.130048 -52.416456)
		(end 126.825248 -52.416456)
		(width 0.1524)
		(layer "In2.Cu")
		(net "M_A_ECC3")
	)
	(segment
		(start 126.063248 -53.0352)
		(end 126.063248 -52.568856)
		(width 0.1524)
		(layer "In2.Cu")
		(net "M_A_ECC3")
	)
	(segment
		(start 127.282448 -53.0352)
		(end 127.282448 -52.568856)
		(width 0.1524)
		(layer "In2.Cu")
		(net "M_A_ECC3")
	)
	(segment
		(start 128.044448 -52.416456)
		(end 127.892048 -52.568856)
		(width 0.1524)
		(layer "In2.Cu")
		(net "M_A_ECC3")
	)
	(segment
		(start 142.367 -53.0606)
		(end 141.9098 -52.6034)
		(width 0.1524)
		(layer "In2.Cu")
		(net "M_A_ECC3")
	)
	(segment
		(start 128.349248 -52.416456)
		(end 128.044448 -52.416456)
		(width 0.1524)
		(layer "In2.Cu")
		(net "M_A_ECC3")
	)
	(segment
		(start 126.215648 -53.1876)
		(end 126.063248 -53.0352)
		(width 0.1524)
		(layer "In2.Cu")
		(net "M_A_ECC3")
	)
	(segment
		(start 125.606048 -52.416456)
		(end 125.453648 -52.568856)
		(width 0.1524)
		(layer "In2.Cu")
		(net "M_A_ECC3")
	)
	(segment
		(start 126.672848 -53.0352)
		(end 126.520448 -53.1876)
		(width 0.1524)
		(layer "In2.Cu")
		(net "M_A_ECC3")
	)
	(segment
		(start 130.9624 -52.705)
		(end 130.9624 -53.0352)
		(width 0.1524)
		(layer "In2.Cu")
		(net "M_A_ECC3")
	)
	(segment
		(start 129.111248 -52.568856)
		(end 129.111248 -53.0352)
		(width 0.1524)
		(layer "In2.Cu")
		(net "M_A_ECC3")
	)
	(segment
		(start 151.511 -59.2328)
		(end 150.4061 -58.1279)
		(width 0.1524)
		(layer "In2.Cu")
		(net "M_A_ECC3")
	)
	(segment
		(start 119.967248 -53.0352)
		(end 119.967248 -52.568856)
		(width 0.1524)
		(layer "In2.Cu")
		(net "M_A_ECC3")
	)
	(segment
		(start 138.8618 -52.6034)
		(end 138.2776 -53.1876)
		(width 0.1524)
		(layer "In2.Cu")
		(net "M_A_ECC3")
	)
	(segment
		(start 150.4061 -58.1279)
		(end 146.757644 -58.1279)
		(width 0.1524)
		(layer "In2.Cu")
		(net "M_A_ECC3")
	)
	(segment
		(start 124.234448 -53.0352)
		(end 124.082048 -53.1876)
		(width 0.1524)
		(layer "In2.Cu")
		(net "M_A_ECC3")
	)
	(segment
		(start 123.167648 -52.416456)
		(end 123.015248 -52.568856)
		(width 0.1524)
		(layer "In2.Cu")
		(net "M_A_ECC3")
	)
	(segment
		(start 128.958848 -53.1876)
		(end 128.654048 -53.1876)
		(width 0.1524)
		(layer "In2.Cu")
		(net "M_A_ECC3")
	)
	(segment
		(start 125.453648 -52.568856)
		(end 125.453648 -53.0352)
		(width 0.1524)
		(layer "In2.Cu")
		(net "M_A_ECC3")
	)
	(segment
		(start 131.7244 -53.1876)
		(end 131.572 -53.0352)
		(width 0.1524)
		(layer "In2.Cu")
		(net "M_A_ECC3")
	)
	(segment
		(start 120.576848 -52.568856)
		(end 120.576848 -53.0352)
		(width 0.1524)
		(layer "In2.Cu")
		(net "M_A_ECC3")
	)
	(segment
		(start 87.838788 -38.730174)
		(end 87.504016 -39.0652)
		(width 0.1143)
		(layer "F.Cu")
		(net "CPU_UART_RXD_R")
	)
	(segment
		(start 87.504016 -39.0652)
		(end 87.4522 -39.0652)
		(width 0.1143)
		(layer "F.Cu")
		(net "CPU_UART_RXD_R")
	)
	(via
		(at 87.4522 -39.0652)
		(size 0.4318)
		(drill 0.2032)
		(layers "F.Cu" "B.Cu")
		(net "CPU_UART_RXD_R")
	)
	(via
		(at 83.064604 -26.054304)
		(size 0.7112)
		(drill 0.3556)
		(layers "F.Cu" "B.Cu")
		(net "CPU_UART_RXD_R")
	)
	(via
		(at 82.570574 -25.560274)
		(size 0.4318)
		(drill 0.2032)
		(layers "F.Cu" "B.Cu")
		(net "CPU_UART_RXD_R")
	)
	(segment
		(start 82.423 -24.9428)
		(end 82.423 -25.4127)
		(width 0.1143)
		(layer "B.Cu")
		(net "CPU_UART_RXD_R")
	)
	(segment
		(start 82.423 -25.4127)
		(end 82.570574 -25.560274)
		(width 0.1143)
		(layer "B.Cu")
		(net "CPU_UART_RXD_R")
	)
	(segment
		(start 83.064604 -26.054304)
		(end 82.570574 -25.560274)
		(width 0.1143)
		(layer "B.Cu")
		(net "CPU_UART_RXD_R")
	)
	(segment
		(start 85.582506 -35.260026)
		(end 85.79866 -35.47618)
		(width 0.0889)
		(layer "In2.Cu")
		(net "CPU_UART_RXD_R")
	)
	(segment
		(start 87.45347 -39.06393)
		(end 87.4522 -39.0652)
		(width 0.0889)
		(layer "In2.Cu")
		(net "CPU_UART_RXD_R")
	)
	(segment
		(start 87.45347 -36.72967)
		(end 87.45347 -39.06393)
		(width 0.0889)
		(layer "In2.Cu")
		(net "CPU_UART_RXD_R")
	)
	(segment
		(start 85.582506 -34.617914)
		(end 85.582506 -35.260026)
		(width 0.0889)
		(layer "In2.Cu")
		(net "CPU_UART_RXD_R")
	)
	(segment
		(start 84.325714 -27.81046)
		(end 85.21065 -28.695396)
		(width 0.0889)
		(layer "In2.Cu")
		(net "CPU_UART_RXD_R")
	)
	(segment
		(start 84.325714 -27.315414)
		(end 84.325714 -27.81046)
		(width 0.0889)
		(layer "In2.Cu")
		(net "CPU_UART_RXD_R")
	)
	(segment
		(start 85.573616 -34.609024)
		(end 85.582506 -34.617914)
		(width 0.0889)
		(layer "In2.Cu")
		(net "CPU_UART_RXD_R")
	)
	(segment
		(start 82.570574 -25.560274)
		(end 84.325714 -27.315414)
		(width 0.0889)
		(layer "In2.Cu")
		(net "CPU_UART_RXD_R")
	)
	(segment
		(start 86.19998 -35.47618)
		(end 87.45347 -36.72967)
		(width 0.0889)
		(layer "In2.Cu")
		(net "CPU_UART_RXD_R")
	)
	(segment
		(start 85.573616 -34.138616)
		(end 85.573616 -34.609024)
		(width 0.0889)
		(layer "In2.Cu")
		(net "CPU_UART_RXD_R")
	)
	(segment
		(start 85.21065 -33.77565)
		(end 85.573616 -34.138616)
		(width 0.0889)
		(layer "In2.Cu")
		(net "CPU_UART_RXD_R")
	)
	(segment
		(start 85.21065 -28.695396)
		(end 85.21065 -33.77565)
		(width 0.0889)
		(layer "In2.Cu")
		(net "CPU_UART_RXD_R")
	)
	(segment
		(start 85.79866 -35.47618)
		(end 86.19998 -35.47618)
		(width 0.0889)
		(layer "In2.Cu")
		(net "CPU_UART_RXD_R")
	)
	(segment
		(start 110.645448 -14.9479)
		(end 110.645448 -15.5067)
		(width 0.1143)
		(layer "F.Cu")
		(net "LPC_CPU_LAD0")
	)
	(segment
		(start 109.273848 -15.5067)
		(end 109.159548 -15.621)
		(width 0.1143)
		(layer "F.Cu")
		(net "LPC_CPU_LAD0")
	)
	(segment
		(start 111.216948 -14.8336)
		(end 110.759748 -14.8336)
		(width 0.1143)
		(layer "F.Cu")
		(net "LPC_CPU_LAD0")
	)
	(segment
		(start 107.216448 -15.5067)
		(end 107.216448 -14.9479)
		(width 0.1143)
		(layer "F.Cu")
		(net "LPC_CPU_LAD0")
	)
	(segment
		(start 105.730548 -14.8336)
		(end 105.273348 -14.8336)
		(width 0.1143)
		(layer "F.Cu")
		(net "LPC_CPU_LAD0")
	)
	(segment
		(start 110.073948 -15.621)
		(end 109.959648 -15.5067)
		(width 0.1143)
		(layer "F.Cu")
		(net "LPC_CPU_LAD0")
	)
	(segment
		(start 112.131348 -14.8336)
		(end 112.017048 -14.9479)
		(width 0.1143)
		(layer "F.Cu")
		(net "LPC_CPU_LAD0")
	)
	(segment
		(start 107.787948 -15.621)
		(end 107.330748 -15.621)
		(width 0.1143)
		(layer "F.Cu")
		(net "LPC_CPU_LAD0")
	)
	(segment
		(start 79.9592 -20.1168)
		(end 79.9592 -22.479)
		(width 0.1143)
		(layer "F.Cu")
		(net "LPC_CPU_LAD0")
	)
	(segment
		(start 107.102148 -14.8336)
		(end 106.644948 -14.8336)
		(width 0.1143)
		(layer "F.Cu")
		(net "LPC_CPU_LAD0")
	)
	(segment
		(start 107.902248 -14.9479)
		(end 107.902248 -15.5067)
		(width 0.1143)
		(layer "F.Cu")
		(net "LPC_CPU_LAD0")
	)
	(segment
		(start 100.807012 -17.3736)
		(end 96.901 -17.3736)
		(width 0.1143)
		(layer "F.Cu")
		(net "LPC_CPU_LAD0")
	)
	(segment
		(start 90.899488 -19.03095)
		(end 90.708988 -18.84045)
		(width 0.1143)
		(layer "F.Cu")
		(net "LPC_CPU_LAD0")
	)
	(segment
		(start 85.552788 -38.730174)
		(end 85.552788 -38.740842)
		(width 0.1143)
		(layer "F.Cu")
		(net "LPC_CPU_LAD0")
	)
	(segment
		(start 104.473248 -14.9479)
		(end 104.358948 -14.8336)
		(width 0.1143)
		(layer "F.Cu")
		(net "LPC_CPU_LAD0")
	)
	(segment
		(start 127.7112 -35.306)
		(end 127.247142 -35.306)
		(width 0.1143)
		(layer "F.Cu")
		(net "LPC_CPU_LAD0")
	)
	(segment
		(start 112.017048 -14.9479)
		(end 112.017048 -15.2527)
		(width 0.1143)
		(layer "F.Cu")
		(net "LPC_CPU_LAD0")
	)
	(segment
		(start 105.273348 -14.8336)
		(end 105.159048 -14.9479)
		(width 0.1143)
		(layer "F.Cu")
		(net "LPC_CPU_LAD0")
	)
	(segment
		(start 85.917532 -19.88439)
		(end 80.19161 -19.88439)
		(width 0.1143)
		(layer "F.Cu")
		(net "LPC_CPU_LAD0")
	)
	(segment
		(start 90.708988 -18.84045)
		(end 89.05621 -18.84045)
		(width 0.1143)
		(layer "F.Cu")
		(net "LPC_CPU_LAD0")
	)
	(segment
		(start 109.159548 -15.621)
		(end 108.702348 -15.621)
		(width 0.1143)
		(layer "F.Cu")
		(net "LPC_CPU_LAD0")
	)
	(segment
		(start 105.844848 -14.9479)
		(end 105.730548 -14.8336)
		(width 0.1143)
		(layer "F.Cu")
		(net "LPC_CPU_LAD0")
	)
	(segment
		(start 106.530648 -14.9479)
		(end 106.530648 -15.5067)
		(width 0.1143)
		(layer "F.Cu")
		(net "LPC_CPU_LAD0")
	)
	(segment
		(start 105.159048 -14.9479)
		(end 105.159048 -15.5067)
		(width 0.1143)
		(layer "F.Cu")
		(net "LPC_CPU_LAD0")
	)
	(segment
		(start 108.588048 -15.5067)
		(end 108.588048 -14.9479)
		(width 0.1143)
		(layer "F.Cu")
		(net "LPC_CPU_LAD0")
	)
	(segment
		(start 127.247142 -35.306)
		(end 115.857782 -23.91664)
		(width 0.1143)
		(layer "F.Cu")
		(net "LPC_CPU_LAD0")
	)
	(segment
		(start 106.416348 -15.621)
		(end 105.959148 -15.621)
		(width 0.1143)
		(layer "F.Cu")
		(net "LPC_CPU_LAD0")
	)
	(segment
		(start 105.959148 -15.621)
		(end 105.844848 -15.5067)
		(width 0.1143)
		(layer "F.Cu")
		(net "LPC_CPU_LAD0")
	)
	(segment
		(start 110.531148 -15.621)
		(end 110.073948 -15.621)
		(width 0.1143)
		(layer "F.Cu")
		(net "LPC_CPU_LAD0")
	)
	(segment
		(start 111.902748 -15.367)
		(end 111.445548 -15.367)
		(width 0.1143)
		(layer "F.Cu")
		(net "LPC_CPU_LAD0")
	)
	(segment
		(start 79.9592 -23.06955)
		(end 79.9592 -22.479)
		(width 0.1143)
		(layer "F.Cu")
		(net "LPC_CPU_LAD0")
	)
	(segment
		(start 96.3676 -17.907)
		(end 95.377 -17.907)
		(width 0.1143)
		(layer "F.Cu")
		(net "LPC_CPU_LAD0")
	)
	(segment
		(start 109.273848 -14.9479)
		(end 109.273848 -15.5067)
		(width 0.1143)
		(layer "F.Cu")
		(net "LPC_CPU_LAD0")
	)
	(segment
		(start 92.47505 -19.03095)
		(end 90.899488 -19.03095)
		(width 0.1143)
		(layer "F.Cu")
		(net "LPC_CPU_LAD0")
	)
	(segment
		(start 94.1324 -17.3736)
		(end 92.47505 -19.03095)
		(width 0.1143)
		(layer "F.Cu")
		(net "LPC_CPU_LAD0")
	)
	(segment
		(start 111.445548 -15.367)
		(end 111.331248 -15.2527)
		(width 0.1143)
		(layer "F.Cu")
		(net "LPC_CPU_LAD0")
	)
	(segment
		(start 80.19161 -19.88439)
		(end 79.9592 -20.1168)
		(width 0.1143)
		(layer "F.Cu")
		(net "LPC_CPU_LAD0")
	)
	(segment
		(start 111.331248 -14.9479)
		(end 111.216948 -14.8336)
		(width 0.1143)
		(layer "F.Cu")
		(net "LPC_CPU_LAD0")
	)
	(segment
		(start 107.216448 -14.9479)
		(end 107.102148 -14.8336)
		(width 0.1143)
		(layer "F.Cu")
		(net "LPC_CPU_LAD0")
	)
	(segment
		(start 95.377 -17.907)
		(end 94.8436 -17.3736)
		(width 0.1143)
		(layer "F.Cu")
		(net "LPC_CPU_LAD0")
	)
	(segment
		(start 105.159048 -15.5067)
		(end 105.044748 -15.621)
		(width 0.1143)
		(layer "F.Cu")
		(net "LPC_CPU_LAD0")
	)
	(segment
		(start 108.702348 -15.621)
		(end 108.588048 -15.5067)
		(width 0.1143)
		(layer "F.Cu")
		(net "LPC_CPU_LAD0")
	)
	(segment
		(start 108.016548 -14.8336)
		(end 107.902248 -14.9479)
		(width 0.1143)
		(layer "F.Cu")
		(net "LPC_CPU_LAD0")
	)
	(segment
		(start 88.271604 -19.625056)
		(end 86.176866 -19.625056)
		(width 0.1143)
		(layer "F.Cu")
		(net "LPC_CPU_LAD0")
	)
	(segment
		(start 115.857782 -23.91664)
		(end 115.857528 -23.91664)
		(width 0.1143)
		(layer "F.Cu")
		(net "LPC_CPU_LAD0")
	)
	(segment
		(start 106.644948 -14.8336)
		(end 106.530648 -14.9479)
		(width 0.1143)
		(layer "F.Cu")
		(net "LPC_CPU_LAD0")
	)
	(segment
		(start 104.587548 -15.621)
		(end 104.473248 -15.5067)
		(width 0.1143)
		(layer "F.Cu")
		(net "LPC_CPU_LAD0")
	)
	(segment
		(start 110.759748 -14.8336)
		(end 110.645448 -14.9479)
		(width 0.1143)
		(layer "F.Cu")
		(net "LPC_CPU_LAD0")
	)
	(segment
		(start 115.277646 -17.422622)
		(end 112.688624 -14.8336)
		(width 0.1143)
		(layer "F.Cu")
		(net "LPC_CPU_LAD0")
	)
	(segment
		(start 109.959648 -15.5067)
		(end 109.959648 -14.9479)
		(width 0.1143)
		(layer "F.Cu")
		(net "LPC_CPU_LAD0")
	)
	(segment
		(start 104.473248 -15.5067)
		(end 104.473248 -14.9479)
		(width 0.1143)
		(layer "F.Cu")
		(net "LPC_CPU_LAD0")
	)
	(segment
		(start 107.902248 -15.5067)
		(end 107.787948 -15.621)
		(width 0.1143)
		(layer "F.Cu")
		(net "LPC_CPU_LAD0")
	)
	(segment
		(start 80.6704 -23.78075)
		(end 79.9592 -23.06955)
		(width 0.1143)
		(layer "F.Cu")
		(net "LPC_CPU_LAD0")
	)
	(segment
		(start 115.857528 -23.91664)
		(end 115.277646 -23.336758)
		(width 0.1143)
		(layer "F.Cu")
		(net "LPC_CPU_LAD0")
	)
	(segment
		(start 103.347012 -14.8336)
		(end 100.807012 -17.3736)
		(width 0.1143)
		(layer "F.Cu")
		(net "LPC_CPU_LAD0")
	)
	(segment
		(start 85.552788 -38.740842)
		(end 85.216746 -39.076884)
		(width 0.1143)
		(layer "F.Cu")
		(net "LPC_CPU_LAD0")
	)
	(segment
		(start 105.044748 -15.621)
		(end 104.587548 -15.621)
		(width 0.1143)
		(layer "F.Cu")
		(net "LPC_CPU_LAD0")
	)
	(segment
		(start 109.845348 -14.8336)
		(end 109.388148 -14.8336)
		(width 0.1143)
		(layer "F.Cu")
		(net "LPC_CPU_LAD0")
	)
	(segment
		(start 111.331248 -15.2527)
		(end 111.331248 -14.9479)
		(width 0.1143)
		(layer "F.Cu")
		(net "LPC_CPU_LAD0")
	)
	(segment
		(start 94.8436 -17.3736)
		(end 94.1324 -17.3736)
		(width 0.1143)
		(layer "F.Cu")
		(net "LPC_CPU_LAD0")
	)
	(segment
		(start 89.05621 -18.84045)
		(end 88.271604 -19.625056)
		(width 0.1143)
		(layer "F.Cu")
		(net "LPC_CPU_LAD0")
	)
	(segment
		(start 108.473748 -14.8336)
		(end 108.016548 -14.8336)
		(width 0.1143)
		(layer "F.Cu")
		(net "LPC_CPU_LAD0")
	)
	(segment
		(start 104.358948 -14.8336)
		(end 103.347012 -14.8336)
		(width 0.1143)
		(layer "F.Cu")
		(net "LPC_CPU_LAD0")
	)
	(segment
		(start 107.330748 -15.621)
		(end 107.216448 -15.5067)
		(width 0.1143)
		(layer "F.Cu")
		(net "LPC_CPU_LAD0")
	)
	(segment
		(start 108.588048 -14.9479)
		(end 108.473748 -14.8336)
		(width 0.1143)
		(layer "F.Cu")
		(net "LPC_CPU_LAD0")
	)
	(segment
		(start 115.277646 -23.336758)
		(end 115.277646 -17.422622)
		(width 0.1143)
		(layer "F.Cu")
		(net "LPC_CPU_LAD0")
	)
	(segment
		(start 109.959648 -14.9479)
		(end 109.845348 -14.8336)
		(width 0.1143)
		(layer "F.Cu")
		(net "LPC_CPU_LAD0")
	)
	(segment
		(start 110.645448 -15.5067)
		(end 110.531148 -15.621)
		(width 0.1143)
		(layer "F.Cu")
		(net "LPC_CPU_LAD0")
	)
	(segment
		(start 106.530648 -15.5067)
		(end 106.416348 -15.621)
		(width 0.1143)
		(layer "F.Cu")
		(net "LPC_CPU_LAD0")
	)
	(segment
		(start 105.844848 -15.5067)
		(end 105.844848 -14.9479)
		(width 0.1143)
		(layer "F.Cu")
		(net "LPC_CPU_LAD0")
	)
	(segment
		(start 109.388148 -14.8336)
		(end 109.273848 -14.9479)
		(width 0.1143)
		(layer "F.Cu")
		(net "LPC_CPU_LAD0")
	)
	(segment
		(start 96.901 -17.3736)
		(end 96.3676 -17.907)
		(width 0.1143)
		(layer "F.Cu")
		(net "LPC_CPU_LAD0")
	)
	(segment
		(start 112.688624 -14.8336)
		(end 112.131348 -14.8336)
		(width 0.1143)
		(layer "F.Cu")
		(net "LPC_CPU_LAD0")
	)
	(segment
		(start 86.176866 -19.625056)
		(end 85.917532 -19.88439)
		(width 0.1143)
		(layer "F.Cu")
		(net "LPC_CPU_LAD0")
	)
	(segment
		(start 112.017048 -15.2527)
		(end 111.902748 -15.367)
		(width 0.1143)
		(layer "F.Cu")
		(net "LPC_CPU_LAD0")
	)
	(via
		(at 79.9592 -22.479)
		(size 0.7112)
		(drill 0.3556)
		(layers "F.Cu" "B.Cu")
		(net "LPC_CPU_LAD0")
	)
	(via
		(at 85.216746 -39.076884)
		(size 0.4318)
		(drill 0.2032)
		(layers "F.Cu" "B.Cu")
		(net "LPC_CPU_LAD0")
	)
	(via
		(at 80.6704 -23.78075)
		(size 0.4318)
		(drill 0.2032)
		(layers "F.Cu" "B.Cu")
		(net "LPC_CPU_LAD0")
	)
	(segment
		(start 80.518 -39.497)
		(end 80.264 -39.751)
		(width 0.0889)
		(layer "In9.Cu")
		(net "LPC_CPU_LAD0")
	)
	(segment
		(start 80.38465 -23.495)
		(end 80.05445 -23.495)
		(width 0.0889)
		(layer "In9.Cu")
		(net "LPC_CPU_LAD0")
	)
	(segment
		(start 80.1878 -32.258)
		(end 79.629 -32.258)
		(width 0.0889)
		(layer "In9.Cu")
		(net "LPC_CPU_LAD0")
	)
	(segment
		(start 79.94015 -23.6093)
		(end 79.94015 -24.06015)
		(width 0.0889)
		(layer "In9.Cu")
		(net "LPC_CPU_LAD0")
	)
	(segment
		(start 80.01 -30.2514)
		(end 80.6958 -30.9372)
		(width 0.0889)
		(layer "In9.Cu")
		(net "LPC_CPU_LAD0")
	)
	(segment
		(start 83.439 -39.9542)
		(end 83.693 -39.7002)
		(width 0.0889)
		(layer "In9.Cu")
		(net "LPC_CPU_LAD0")
	)
	(segment
		(start 83.312 -40.513)
		(end 83.439 -40.386)
		(width 0.0889)
		(layer "In9.Cu")
		(net "LPC_CPU_LAD0")
	)
	(segment
		(start 80.264 -38.862)
		(end 80.518 -39.116)
		(width 0.0889)
		(layer "In9.Cu")
		(net "LPC_CPU_LAD0")
	)
	(segment
		(start 80.391 -29.602938)
		(end 80.01 -29.983938)
		(width 0.0889)
		(layer "In9.Cu")
		(net "LPC_CPU_LAD0")
	)
	(segment
		(start 79.629 -27.9527)
		(end 79.629 -28.3337)
		(width 0.0889)
		(layer "In9.Cu")
		(net "LPC_CPU_LAD0")
	)
	(segment
		(start 79.517494 -36.3347)
		(end 79.631794 -36.449)
		(width 0.0889)
		(layer "In9.Cu")
		(net "LPC_CPU_LAD0")
	)
	(segment
		(start 79.631794 -36.449)
		(end 79.936594 -36.449)
		(width 0.0889)
		(layer "In9.Cu")
		(net "LPC_CPU_LAD0")
	)
	(segment
		(start 80.264 -40.132)
		(end 80.518 -40.386)
		(width 0.0889)
		(layer "In9.Cu")
		(net "LPC_CPU_LAD0")
	)
	(segment
		(start 80.137 -26.67)
		(end 80.264 -26.797)
		(width 0.0889)
		(layer "In9.Cu")
		(net "LPC_CPU_LAD0")
	)
	(segment
		(start 79.502 -32.385)
		(end 79.502 -32.6771)
		(width 0.0889)
		(layer "In9.Cu")
		(net "LPC_CPU_LAD0")
	)
	(segment
		(start 79.517494 -37.039804)
		(end 79.517494 -37.353494)
		(width 0.0889)
		(layer "In9.Cu")
		(net "LPC_CPU_LAD0")
	)
	(segment
		(start 80.518 -40.386)
		(end 80.645 -40.386)
		(width 0.0889)
		(layer "In9.Cu")
		(net "LPC_CPU_LAD0")
	)
	(segment
		(start 80.6704 -23.78075)
		(end 80.38465 -23.495)
		(width 0.0889)
		(layer "In9.Cu")
		(net "LPC_CPU_LAD0")
	)
	(segment
		(start 80.61325 -25.908)
		(end 80.137 -26.38425)
		(width 0.0889)
		(layer "In9.Cu")
		(net "LPC_CPU_LAD0")
	)
	(segment
		(start 81.3308 -39.7002)
		(end 82.6262 -39.7002)
		(width 0.0889)
		(layer "In9.Cu")
		(net "LPC_CPU_LAD0")
	)
	(segment
		(start 80.495394 -36.950904)
		(end 79.606394 -36.950904)
		(width 0.0889)
		(layer "In9.Cu")
		(net "LPC_CPU_LAD0")
	)
	(segment
		(start 79.606394 -36.950904)
		(end 79.517494 -37.039804)
		(width 0.0889)
		(layer "In9.Cu")
		(net "LPC_CPU_LAD0")
	)
	(segment
		(start 80.518 -26.797)
		(end 80.645 -26.924)
		(width 0.0889)
		(layer "In9.Cu")
		(net "LPC_CPU_LAD0")
	)
	(segment
		(start 79.88935 -27.69235)
		(end 79.629 -27.9527)
		(width 0.0889)
		(layer "In9.Cu")
		(net "LPC_CPU_LAD0")
	)
	(segment
		(start 80.61325 -24.73325)
		(end 80.61325 -25.908)
		(width 0.0889)
		(layer "In9.Cu")
		(net "LPC_CPU_LAD0")
	)
	(segment
		(start 80.518 -39.116)
		(end 80.518 -39.497)
		(width 0.0889)
		(layer "In9.Cu")
		(net "LPC_CPU_LAD0")
	)
	(segment
		(start 80.050894 -35.5473)
		(end 80.165194 -35.433)
		(width 0.0889)
		(layer "In9.Cu")
		(net "LPC_CPU_LAD0")
	)
	(segment
		(start 80.6958 -30.9372)
		(end 80.6958 -31.75)
		(width 0.0889)
		(layer "In9.Cu")
		(net "LPC_CPU_LAD0")
	)
	(segment
		(start 80.469994 -35.433)
		(end 80.584294 -35.5473)
		(width 0.0889)
		(layer "In9.Cu")
		(net "LPC_CPU_LAD0")
	)
	(segment
		(start 79.94015 -24.06015)
		(end 80.61325 -24.73325)
		(width 0.0889)
		(layer "In9.Cu")
		(net "LPC_CPU_LAD0")
	)
	(segment
		(start 80.584294 -36.862004)
		(end 80.495394 -36.950904)
		(width 0.0889)
		(layer "In9.Cu")
		(net "LPC_CPU_LAD0")
	)
	(segment
		(start 80.365092 -33.248092)
		(end 80.365092 -34.518092)
		(width 0.0889)
		(layer "In9.Cu")
		(net "LPC_CPU_LAD0")
	)
	(segment
		(start 80.050894 -36.3347)
		(end 80.050894 -35.5473)
		(width 0.0889)
		(layer "In9.Cu")
		(net "LPC_CPU_LAD0")
	)
	(segment
		(start 79.517494 -35.36569)
		(end 79.517494 -36.3347)
		(width 0.0889)
		(layer "In9.Cu")
		(net "LPC_CPU_LAD0")
	)
	(segment
		(start 83.693 -39.7002)
		(end 85.0138 -39.7002)
		(width 0.0889)
		(layer "In9.Cu")
		(net "LPC_CPU_LAD0")
	)
	(segment
		(start 80.01 -29.983938)
		(end 80.01 -30.2514)
		(width 0.0889)
		(layer "In9.Cu")
		(net "LPC_CPU_LAD0")
	)
	(segment
		(start 79.517494 -37.353494)
		(end 80.264 -38.1)
		(width 0.0889)
		(layer "In9.Cu")
		(net "LPC_CPU_LAD0")
	)
	(segment
		(start 80.264 -26.797)
		(end 80.518 -26.797)
		(width 0.0889)
		(layer "In9.Cu")
		(net "LPC_CPU_LAD0")
	)
	(segment
		(start 82.6262 -39.7002)
		(end 82.804 -39.878)
		(width 0.0889)
		(layer "In9.Cu")
		(net "LPC_CPU_LAD0")
	)
	(segment
		(start 85.216746 -39.497254)
		(end 85.216746 -39.076884)
		(width 0.0889)
		(layer "In9.Cu")
		(net "LPC_CPU_LAD0")
	)
	(segment
		(start 79.629 -32.258)
		(end 79.502 -32.385)
		(width 0.0889)
		(layer "In9.Cu")
		(net "LPC_CPU_LAD0")
	)
	(segment
		(start 79.502 -32.6771)
		(end 79.7179 -32.893)
		(width 0.0889)
		(layer "In9.Cu")
		(net "LPC_CPU_LAD0")
	)
	(segment
		(start 80.264 -38.1)
		(end 80.264 -38.862)
		(width 0.0889)
		(layer "In9.Cu")
		(net "LPC_CPU_LAD0")
	)
	(segment
		(start 80.6958 -31.75)
		(end 80.1878 -32.258)
		(width 0.0889)
		(layer "In9.Cu")
		(net "LPC_CPU_LAD0")
	)
	(segment
		(start 80.584294 -35.5473)
		(end 80.584294 -36.862004)
		(width 0.0889)
		(layer "In9.Cu")
		(net "LPC_CPU_LAD0")
	)
	(segment
		(start 80.365092 -34.518092)
		(end 79.517494 -35.36569)
		(width 0.0889)
		(layer "In9.Cu")
		(net "LPC_CPU_LAD0")
	)
	(segment
		(start 83.439 -40.386)
		(end 83.439 -39.9542)
		(width 0.0889)
		(layer "In9.Cu")
		(net "LPC_CPU_LAD0")
	)
	(segment
		(start 80.38465 -27.69235)
		(end 79.88935 -27.69235)
		(width 0.0889)
		(layer "In9.Cu")
		(net "LPC_CPU_LAD0")
	)
	(segment
		(start 83.058 -40.513)
		(end 83.312 -40.513)
		(width 0.0889)
		(layer "In9.Cu")
		(net "LPC_CPU_LAD0")
	)
	(segment
		(start 80.645 -27.432)
		(end 80.38465 -27.69235)
		(width 0.0889)
		(layer "In9.Cu")
		(net "LPC_CPU_LAD0")
	)
	(segment
		(start 80.01 -32.893)
		(end 80.365092 -33.248092)
		(width 0.0889)
		(layer "In9.Cu")
		(net "LPC_CPU_LAD0")
	)
	(segment
		(start 80.05445 -23.495)
		(end 79.94015 -23.6093)
		(width 0.0889)
		(layer "In9.Cu")
		(net "LPC_CPU_LAD0")
	)
	(segment
		(start 82.804 -40.259)
		(end 83.058 -40.513)
		(width 0.0889)
		(layer "In9.Cu")
		(net "LPC_CPU_LAD0")
	)
	(segment
		(start 80.165194 -35.433)
		(end 80.469994 -35.433)
		(width 0.0889)
		(layer "In9.Cu")
		(net "LPC_CPU_LAD0")
	)
	(segment
		(start 79.7179 -32.893)
		(end 80.01 -32.893)
		(width 0.0889)
		(layer "In9.Cu")
		(net "LPC_CPU_LAD0")
	)
	(segment
		(start 79.936594 -36.449)
		(end 80.050894 -36.3347)
		(width 0.0889)
		(layer "In9.Cu")
		(net "LPC_CPU_LAD0")
	)
	(segment
		(start 80.645 -40.386)
		(end 81.3308 -39.7002)
		(width 0.0889)
		(layer "In9.Cu")
		(net "LPC_CPU_LAD0")
	)
	(segment
		(start 85.0138 -39.7002)
		(end 85.216746 -39.497254)
		(width 0.0889)
		(layer "In9.Cu")
		(net "LPC_CPU_LAD0")
	)
	(segment
		(start 80.645 -26.924)
		(end 80.645 -27.432)
		(width 0.0889)
		(layer "In9.Cu")
		(net "LPC_CPU_LAD0")
	)
	(segment
		(start 80.137 -26.38425)
		(end 80.137 -26.67)
		(width 0.0889)
		(layer "In9.Cu")
		(net "LPC_CPU_LAD0")
	)
	(segment
		(start 79.629 -28.3337)
		(end 80.391 -29.0957)
		(width 0.0889)
		(layer "In9.Cu")
		(net "LPC_CPU_LAD0")
	)
	(segment
		(start 80.264 -39.751)
		(end 80.264 -40.132)
		(width 0.0889)
		(layer "In9.Cu")
		(net "LPC_CPU_LAD0")
	)
	(segment
		(start 82.804 -39.878)
		(end 82.804 -40.259)
		(width 0.0889)
		(layer "In9.Cu")
		(net "LPC_CPU_LAD0")
	)
	(segment
		(start 80.391 -29.0957)
		(end 80.391 -29.602938)
		(width 0.0889)
		(layer "In9.Cu")
		(net "LPC_CPU_LAD0")
	)
	(segment
		(start 6.514846 -49.923954)
		(end 6.3246 -50.1142)
		(width 0.1143)
		(layer "F.Cu")
		(net "TEMP_1_A0")
	)
	(segment
		(start 6.3246 -50.1142)
		(end 5.5626 -50.1142)
		(width 0.1143)
		(layer "F.Cu")
		(net "TEMP_1_A0")
	)
	(segment
		(start 6.514846 -48.471328)
		(end 6.514846 -49.923954)
		(width 0.1143)
		(layer "F.Cu")
		(net "TEMP_1_A0")
	)
	(segment
		(start 17.533874 -25.280874)
		(end 17.58569 -25.33269)
		(width 0.254)
		(layer "F.Cu")
		(net "P1V0_ROVP")
	)
	(segment
		(start 16.292322 -25.280874)
		(end 17.533874 -25.280874)
		(width 0.254)
		(layer "F.Cu")
		(net "P1V0_ROVP")
	)
	(via
		(at 17.58569 -25.33269)
		(size 0.508)
		(drill 0.254)
		(layers "F.Cu" "B.Cu")
		(net "P1V0_ROVP")
	)
	(via
		(at 18.4658 -25.7556)
		(size 0.7112)
		(drill 0.3556)
		(layers "F.Cu" "B.Cu")
		(net "P1V0_ROVP")
	)
	(segment
		(start 18.4658 -24.8666)
		(end 18.3642 -24.765)
		(width 0.254)
		(layer "B.Cu")
		(net "P1V0_ROVP")
	)
	(segment
		(start 18.3642 -23.2664)
		(end 18.3388 -23.241)
		(width 0.254)
		(layer "B.Cu")
		(net "P1V0_ROVP")
	)
	(segment
		(start 18.0086 -25.7556)
		(end 18.4658 -25.7556)
		(width 0.254)
		(layer "B.Cu")
		(net "P1V0_ROVP")
	)
	(segment
		(start 18.4658 -25.7556)
		(end 18.4658 -24.8666)
		(width 0.254)
		(layer "B.Cu")
		(net "P1V0_ROVP")
	)
	(segment
		(start 18.3642 -24.765)
		(end 18.3642 -24.003)
		(width 0.254)
		(layer "B.Cu")
		(net "P1V0_ROVP")
	)
	(segment
		(start 18.3642 -24.003)
		(end 18.3642 -23.2664)
		(width 0.254)
		(layer "B.Cu")
		(net "P1V0_ROVP")
	)
	(segment
		(start 17.58569 -25.33269)
		(end 18.0086 -25.7556)
		(width 0.254)
		(layer "B.Cu")
		(net "P1V0_ROVP")
	)
	(segment
		(start 16.2052 -52.1462)
		(end 15.4178 -52.1462)
		(width 0.2032)
		(layer "F.Cu")
		(net "VR_PVCCP_COMP")
	)
	(segment
		(start 19.263106 -55.356506)
		(end 19.263106 -55.547006)
		(width 0.2032)
		(layer "F.Cu")
		(net "VR_PVCCP_COMP")
	)
	(segment
		(start 15.5956 -51.9176)
		(end 15.3924 -52.1208)
		(width 0.2032)
		(layer "F.Cu")
		(net "VR_PVCCP_COMP")
	)
	(segment
		(start 18.047208 -53.810662)
		(end 18.047208 -54.140608)
		(width 0.2032)
		(layer "F.Cu")
		(net "VR_PVCCP_COMP")
	)
	(segment
		(start 17.1196 -52.197)
		(end 17.0688 -52.1462)
		(width 0.2032)
		(layer "F.Cu")
		(net "VR_PVCCP_COMP")
	)
	(segment
		(start 17.0688 -52.1462)
		(end 16.2052 -52.1462)
		(width 0.2032)
		(layer "F.Cu")
		(net "VR_PVCCP_COMP")
	)
	(segment
		(start 17.3482 -53.111654)
		(end 18.047208 -53.810662)
		(width 0.2032)
		(layer "F.Cu")
		(net "VR_PVCCP_COMP")
	)
	(segment
		(start 15.5956 -51.2572)
		(end 15.5956 -51.9176)
		(width 0.2032)
		(layer "F.Cu")
		(net "VR_PVCCP_COMP")
	)
	(segment
		(start 17.3482 -52.4256)
		(end 17.3482 -53.111654)
		(width 0.2032)
		(layer "F.Cu")
		(net "VR_PVCCP_COMP")
	)
	(segment
		(start 17.1196 -52.197)
		(end 17.3482 -52.4256)
		(width 0.2032)
		(layer "F.Cu")
		(net "VR_PVCCP_COMP")
	)
	(segment
		(start 15.5956 -51.2572)
		(end 15.5956 -50.3682)
		(width 0.2032)
		(layer "F.Cu")
		(net "VR_PVCCP_COMP")
	)
	(segment
		(start 18.047208 -54.140608)
		(end 19.263106 -55.356506)
		(width 0.2032)
		(layer "F.Cu")
		(net "VR_PVCCP_COMP")
	)
	(segment
		(start 15.4178 -52.1462)
		(end 15.3924 -52.1208)
		(width 0.2032)
		(layer "F.Cu")
		(net "VR_PVCCP_COMP")
	)
	(via
		(at 17.1196 -52.197)
		(size 0.7112)
		(drill 0.3556)
		(layers "F.Cu" "B.Cu")
		(net "VR_PVCCP_COMP")
	)
	(segment
		(start 95.0722 -39.623746)
		(end 95.0722 -39.5732)
		(width 0.127)
		(layer "F.Cu")
		(net "TP_CPU_RSVD9")
	)
	(segment
		(start 95.448628 -40.000174)
		(end 95.0722 -39.623746)
		(width 0.127)
		(layer "F.Cu")
		(net "TP_CPU_RSVD9")
	)
	(via
		(at 95.0722 -39.5732)
		(size 0.4318)
		(drill 0.2032)
		(layers "F.Cu" "B.Cu")
		(net "TP_CPU_RSVD9")
	)
	(segment
		(start 95.0722 -39.5732)
		(end 95.0722 -39.5478)
		(width 0.127)
		(layer "B.Cu")
		(net "TP_CPU_RSVD9")
	)
	(segment
		(start 95.0722 -39.5478)
		(end 95.9358 -38.6842)
		(width 0.127)
		(layer "B.Cu")
		(net "TP_CPU_RSVD9")
	)
	(segment
		(start 19.6088 -63.4492)
		(end 19.6088 -63.0682)
		(width 0.2032)
		(layer "F.Cu")
		(net "VR_PVNN_VSEN")
	)
	(segment
		(start 20.062952 -61.292994)
		(end 20.062952 -61.826648)
		(width 0.2032)
		(layer "F.Cu")
		(net "VR_PVNN_VSEN")
	)
	(segment
		(start 20.062952 -61.826648)
		(end 19.2278 -62.6618)
		(width 0.2032)
		(layer "F.Cu")
		(net "VR_PVNN_VSEN")
	)
	(segment
		(start 19.2278 -62.6618)
		(end 19.2024 -62.6618)
		(width 0.2032)
		(layer "F.Cu")
		(net "VR_PVNN_VSEN")
	)
	(segment
		(start 19.6088 -63.0682)
		(end 19.2024 -62.6618)
		(width 0.2032)
		(layer "F.Cu")
		(net "VR_PVNN_VSEN")
	)
	(segment
		(start 19.6088 -64.1604)
		(end 19.6088 -63.4492)
		(width 0.2032)
		(layer "F.Cu")
		(net "VR_PVNN_VSEN")
	)
	(segment
		(start 19.7358 -64.2874)
		(end 19.6088 -64.1604)
		(width 0.2032)
		(layer "F.Cu")
		(net "VR_PVNN_VSEN")
	)
	(via
		(at 19.2024 -62.6618)
		(size 0.508)
		(drill 0.254)
		(layers "F.Cu" "B.Cu")
		(net "VR_PVNN_VSEN")
	)
	(via
		(at 18.669 -63.4492)
		(size 0.7112)
		(drill 0.3556)
		(layers "F.Cu" "B.Cu")
		(net "VR_PVNN_VSEN")
	)
	(segment
		(start 18.669 -63.1952)
		(end 19.2024 -62.6618)
		(width 0.2032)
		(layer "B.Cu")
		(net "VR_PVNN_VSEN")
	)
	(segment
		(start 19.177 -64.3382)
		(end 18.669 -63.8302)
		(width 0.2032)
		(layer "B.Cu")
		(net "VR_PVNN_VSEN")
	)
	(segment
		(start 18.669 -63.8302)
		(end 18.669 -63.4492)
		(width 0.2032)
		(layer "B.Cu")
		(net "VR_PVNN_VSEN")
	)
	(segment
		(start 18.669 -63.4492)
		(end 18.669 -63.1952)
		(width 0.2032)
		(layer "B.Cu")
		(net "VR_PVNN_VSEN")
	)
	(segment
		(start 144.55013 -69.72427)
		(end 144.8308 -69.4436)
		(width 0.1778)
		(layer "F.Cu")
		(net "M_A_DQ38")
	)
	(segment
		(start 97.63506 -49.86274)
		(end 97.62998 -49.85766)
		(width 0.1016)
		(layer "F.Cu")
		(net "M_A_DQ38")
	)
	(segment
		(start 144.8308 -69.4436)
		(end 144.8308 -69.3674)
		(width 0.1778)
		(layer "F.Cu")
		(net "M_A_DQ38")
	)
	(segment
		(start 97.62998 -49.85766)
		(end 97.62998 -49.601882)
		(width 0.1016)
		(layer "F.Cu")
		(net "M_A_DQ38")
	)
	(segment
		(start 144.55013 -70.806564)
		(end 144.55013 -69.72427)
		(width 0.1778)
		(layer "F.Cu")
		(net "M_A_DQ38")
	)
	(segment
		(start 97.63506 -49.90338)
		(end 97.63506 -49.86274)
		(width 0.1016)
		(layer "F.Cu")
		(net "M_A_DQ38")
	)
	(segment
		(start 97.62998 -49.601882)
		(end 98.067368 -49.164494)
		(width 0.1016)
		(layer "F.Cu")
		(net "M_A_DQ38")
	)
	(via
		(at 144.8308 -69.3674)
		(size 0.4318)
		(drill 0.2032)
		(layers "F.Cu" "B.Cu")
		(net "M_A_DQ38")
	)
	(via
		(at 97.63506 -49.90338)
		(size 0.4318)
		(drill 0.2032)
		(layers "F.Cu" "B.Cu")
		(net "M_A_DQ38")
	)
	(segment
		(start 144.8816 -69.4182)
		(end 144.8308 -69.3674)
		(width 0.1778)
		(layer "B.Cu")
		(net "M_A_DQ38")
	)
	(segment
		(start 145.450052 -70.79996)
		(end 145.450052 -70.012052)
		(width 0.1778)
		(layer "B.Cu")
		(net "M_A_DQ38")
	)
	(segment
		(start 145.450052 -70.012052)
		(end 144.8816 -69.4436)
		(width 0.1778)
		(layer "B.Cu")
		(net "M_A_DQ38")
	)
	(segment
		(start 144.8816 -69.4436)
		(end 144.8816 -69.4182)
		(width 0.1778)
		(layer "B.Cu")
		(net "M_A_DQ38")
	)
	(segment
		(start 138.58621 -61.75121)
		(end 138.262614 -61.427614)
		(width 0.1524)
		(layer "In4.Cu")
		(net "M_A_DQ38")
	)
	(segment
		(start 126.365 -58.801)
		(end 126.0475 -58.4835)
		(width 0.1524)
		(layer "In4.Cu")
		(net "M_A_DQ38")
	)
	(segment
		(start 146.14144 -67.7037)
		(end 140.579094 -67.7037)
		(width 0.1524)
		(layer "In4.Cu")
		(net "M_A_DQ38")
	)
	(segment
		(start 98.2218 -52.0446)
		(end 97.9678 -51.7906)
		(width 0.1016)
		(layer "In4.Cu")
		(net "M_A_DQ38")
	)
	(segment
		(start 132.4864 -59.0804)
		(end 131.8895 -58.4835)
		(width 0.1524)
		(layer "In4.Cu")
		(net "M_A_DQ38")
	)
	(segment
		(start 101.347778 -53.3908)
		(end 99.5934 -53.3908)
		(width 0.1016)
		(layer "In4.Cu")
		(net "M_A_DQ38")
	)
	(segment
		(start 99.5426 -53.34)
		(end 98.8314 -53.34)
		(width 0.1016)
		(layer "In4.Cu")
		(net "M_A_DQ38")
	)
	(segment
		(start 140.5382 -66.1162)
		(end 141.2494 -66.1162)
		(width 0.1524)
		(layer "In4.Cu")
		(net "M_A_DQ38")
	)
	(segment
		(start 139.48029 -62.36589)
		(end 139.48029 -62.150498)
		(width 0.1524)
		(layer "In4.Cu")
		(net "M_A_DQ38")
	)
	(segment
		(start 102.87 -54.2798)
		(end 102.405434 -53.815234)
		(width 0.1524)
		(layer "In4.Cu")
		(net "M_A_DQ38")
	)
	(segment
		(start 105.2957 -58.4835)
		(end 104.2162 -57.404)
		(width 0.1524)
		(layer "In4.Cu")
		(net "M_A_DQ38")
	)
	(segment
		(start 139.9413 -62.8269)
		(end 139.48029 -62.36589)
		(width 0.1524)
		(layer "In4.Cu")
		(net "M_A_DQ38")
	)
	(segment
		(start 126.0475 -58.4835)
		(end 105.2957 -58.4835)
		(width 0.1524)
		(layer "In4.Cu")
		(net "M_A_DQ38")
	)
	(segment
		(start 139.28471 -61.268102)
		(end 138.801602 -61.75121)
		(width 0.1524)
		(layer "In4.Cu")
		(net "M_A_DQ38")
	)
	(segment
		(start 144.8308 -69.1642)
		(end 145.143728 -68.851272)
		(width 0.1524)
		(layer "In4.Cu")
		(net "M_A_DQ38")
	)
	(segment
		(start 139.823698 -61.80709)
		(end 139.823698 -61.591698)
		(width 0.1524)
		(layer "In4.Cu")
		(net "M_A_DQ38")
	)
	(segment
		(start 138.262614 -61.212222)
		(end 138.745722 -60.729114)
		(width 0.1524)
		(layer "In4.Cu")
		(net "M_A_DQ38")
	)
	(segment
		(start 138.262614 -61.427614)
		(end 138.262614 -61.212222)
		(width 0.1524)
		(layer "In4.Cu")
		(net "M_A_DQ38")
	)
	(segment
		(start 141.478 -65.8876)
		(end 141.478 -63.3222)
		(width 0.1524)
		(layer "In4.Cu")
		(net "M_A_DQ38")
	)
	(segment
		(start 98.8314 -53.34)
		(end 98.7298 -53.4416)
		(width 0.1016)
		(layer "In4.Cu")
		(net "M_A_DQ38")
	)
	(segment
		(start 141.478 -63.3222)
		(end 140.9827 -62.8269)
		(width 0.1524)
		(layer "In4.Cu")
		(net "M_A_DQ38")
	)
	(segment
		(start 144.8308 -69.3674)
		(end 144.8308 -69.1642)
		(width 0.1524)
		(layer "In4.Cu")
		(net "M_A_DQ38")
	)
	(segment
		(start 104.1146 -55.5244)
		(end 104.1146 -54.7878)
		(width 0.1524)
		(layer "In4.Cu")
		(net "M_A_DQ38")
	)
	(segment
		(start 103.6066 -54.2798)
		(end 102.87 -54.2798)
		(width 0.1524)
		(layer "In4.Cu")
		(net "M_A_DQ38")
	)
	(segment
		(start 140.3858 -66.2686)
		(end 140.5382 -66.1162)
		(width 0.1524)
		(layer "In4.Cu")
		(net "M_A_DQ38")
	)
	(segment
		(start 104.1146 -54.7878)
		(end 103.6066 -54.2798)
		(width 0.1524)
		(layer "In4.Cu")
		(net "M_A_DQ38")
	)
	(segment
		(start 98.1456 -54.229)
		(end 97.681796 -53.765196)
		(width 0.1016)
		(layer "In4.Cu")
		(net "M_A_DQ38")
	)
	(segment
		(start 98.7298 -53.4416)
		(end 98.7298 -53.8988)
		(width 0.1016)
		(layer "In4.Cu")
		(net "M_A_DQ38")
	)
	(segment
		(start 137.863326 -60.533534)
		(end 137.647934 -60.533534)
		(width 0.1524)
		(layer "In4.Cu")
		(net "M_A_DQ38")
	)
	(segment
		(start 128.778 -58.4835)
		(end 128.4605 -58.801)
		(width 0.1524)
		(layer "In4.Cu")
		(net "M_A_DQ38")
	)
	(segment
		(start 138.422126 -60.190126)
		(end 138.206734 -60.190126)
		(width 0.1524)
		(layer "In4.Cu")
		(net "M_A_DQ38")
	)
	(segment
		(start 138.745722 -60.729114)
		(end 138.745722 -60.513722)
		(width 0.1524)
		(layer "In4.Cu")
		(net "M_A_DQ38")
	)
	(segment
		(start 146.43354 -67.9958)
		(end 146.14144 -67.7037)
		(width 0.1524)
		(layer "In4.Cu")
		(net "M_A_DQ38")
	)
	(segment
		(start 127.889 -58.801)
		(end 127.5715 -58.4835)
		(width 0.1524)
		(layer "In4.Cu")
		(net "M_A_DQ38")
	)
	(segment
		(start 139.48029 -62.150498)
		(end 139.823698 -61.80709)
		(width 0.1524)
		(layer "In4.Cu")
		(net "M_A_DQ38")
	)
	(segment
		(start 146.248628 -68.851272)
		(end 146.43354 -68.66636)
		(width 0.1524)
		(layer "In4.Cu")
		(net "M_A_DQ38")
	)
	(segment
		(start 98.7298 -53.8988)
		(end 98.3996 -54.229)
		(width 0.1016)
		(layer "In4.Cu")
		(net "M_A_DQ38")
	)
	(segment
		(start 137.647934 -60.533534)
		(end 136.1948 -59.0804)
		(width 0.1524)
		(layer "In4.Cu")
		(net "M_A_DQ38")
	)
	(segment
		(start 138.745722 -60.513722)
		(end 138.422126 -60.190126)
		(width 0.1524)
		(layer "In4.Cu")
		(net "M_A_DQ38")
	)
	(segment
		(start 126.8095 -58.801)
		(end 126.365 -58.801)
		(width 0.1524)
		(layer "In4.Cu")
		(net "M_A_DQ38")
	)
	(segment
		(start 139.823698 -61.591698)
		(end 139.500102 -61.268102)
		(width 0.1524)
		(layer "In4.Cu")
		(net "M_A_DQ38")
	)
	(segment
		(start 146.43354 -68.66636)
		(end 146.43354 -67.9958)
		(width 0.1524)
		(layer "In4.Cu")
		(net "M_A_DQ38")
	)
	(segment
		(start 97.9678 -50.23612)
		(end 97.63506 -49.90338)
		(width 0.1016)
		(layer "In4.Cu")
		(net "M_A_DQ38")
	)
	(segment
		(start 140.9827 -62.8269)
		(end 139.9413 -62.8269)
		(width 0.1524)
		(layer "In4.Cu")
		(net "M_A_DQ38")
	)
	(segment
		(start 140.3858 -67.510406)
		(end 140.3858 -66.2686)
		(width 0.1524)
		(layer "In4.Cu")
		(net "M_A_DQ38")
	)
	(segment
		(start 139.500102 -61.268102)
		(end 139.28471 -61.268102)
		(width 0.1524)
		(layer "In4.Cu")
		(net "M_A_DQ38")
	)
	(segment
		(start 104.2162 -55.626)
		(end 104.1146 -55.5244)
		(width 0.1524)
		(layer "In4.Cu")
		(net "M_A_DQ38")
	)
	(segment
		(start 97.9678 -51.7906)
		(end 97.9678 -50.23612)
		(width 0.1016)
		(layer "In4.Cu")
		(net "M_A_DQ38")
	)
	(segment
		(start 97.681796 -53.549804)
		(end 98.2218 -53.0098)
		(width 0.1016)
		(layer "In4.Cu")
		(net "M_A_DQ38")
	)
	(segment
		(start 97.681796 -53.765196)
		(end 97.681796 -53.549804)
		(width 0.1016)
		(layer "In4.Cu")
		(net "M_A_DQ38")
	)
	(segment
		(start 138.801602 -61.75121)
		(end 138.58621 -61.75121)
		(width 0.1524)
		(layer "In4.Cu")
		(net "M_A_DQ38")
	)
	(segment
		(start 128.4605 -58.801)
		(end 127.889 -58.801)
		(width 0.1524)
		(layer "In4.Cu")
		(net "M_A_DQ38")
	)
	(segment
		(start 104.2162 -57.404)
		(end 104.2162 -55.626)
		(width 0.1524)
		(layer "In4.Cu")
		(net "M_A_DQ38")
	)
	(segment
		(start 145.143728 -68.851272)
		(end 146.248628 -68.851272)
		(width 0.1524)
		(layer "In4.Cu")
		(net "M_A_DQ38")
	)
	(segment
		(start 98.3996 -54.229)
		(end 98.1456 -54.229)
		(width 0.1016)
		(layer "In4.Cu")
		(net "M_A_DQ38")
	)
	(segment
		(start 98.2218 -53.0098)
		(end 98.2218 -52.0446)
		(width 0.1016)
		(layer "In4.Cu")
		(net "M_A_DQ38")
	)
	(segment
		(start 136.1948 -59.0804)
		(end 132.4864 -59.0804)
		(width 0.1524)
		(layer "In4.Cu")
		(net "M_A_DQ38")
	)
	(segment
		(start 141.2494 -66.1162)
		(end 141.478 -65.8876)
		(width 0.1524)
		(layer "In4.Cu")
		(net "M_A_DQ38")
	)
	(segment
		(start 140.579094 -67.7037)
		(end 140.3858 -67.510406)
		(width 0.1524)
		(layer "In4.Cu")
		(net "M_A_DQ38")
	)
	(segment
		(start 127.5715 -58.4835)
		(end 127.127 -58.4835)
		(width 0.1524)
		(layer "In4.Cu")
		(net "M_A_DQ38")
	)
	(segment
		(start 101.772212 -53.815234)
		(end 101.347778 -53.3908)
		(width 0.1016)
		(layer "In4.Cu")
		(net "M_A_DQ38")
	)
	(segment
		(start 131.8895 -58.4835)
		(end 128.778 -58.4835)
		(width 0.1524)
		(layer "In4.Cu")
		(net "M_A_DQ38")
	)
	(segment
		(start 99.5934 -53.3908)
		(end 99.5426 -53.34)
		(width 0.1016)
		(layer "In4.Cu")
		(net "M_A_DQ38")
	)
	(segment
		(start 127.127 -58.4835)
		(end 126.8095 -58.801)
		(width 0.1524)
		(layer "In4.Cu")
		(net "M_A_DQ38")
	)
	(segment
		(start 102.405434 -53.815234)
		(end 101.772212 -53.815234)
		(width 0.1016)
		(layer "In4.Cu")
		(net "M_A_DQ38")
	)
	(segment
		(start 138.206734 -60.190126)
		(end 137.863326 -60.533534)
		(width 0.1524)
		(layer "In4.Cu")
		(net "M_A_DQ38")
	)
	(segment
		(start 76.044552 -39.301928)
		(end 77.282548 -39.301928)
		(width 0.1143)
		(layer "F.Cu")
		(net "RTC_X2PAD")
	)
	(segment
		(start 73.9394 -40.0812)
		(end 73.2028 -39.3446)
		(width 0.1143)
		(layer "F.Cu")
		(net "RTC_X2PAD")
	)
	(segment
		(start 71.944484 -39.3446)
		(end 73.025 -39.3446)
		(width 0.1143)
		(layer "F.Cu")
		(net "RTC_X2PAD")
	)
	(segment
		(start 71.374 -38.774116)
		(end 71.944484 -39.3446)
		(width 0.1143)
		(layer "F.Cu")
		(net "RTC_X2PAD")
	)
	(segment
		(start 75.64628 -39.7002)
		(end 75.874118 -39.472362)
		(width 0.1143)
		(layer "F.Cu")
		(net "RTC_X2PAD")
	)
	(segment
		(start 75.874118 -39.472362)
		(end 76.044552 -39.301928)
		(width 0.1143)
		(layer "F.Cu")
		(net "RTC_X2PAD")
	)
	(segment
		(start 74.8792 -39.7002)
		(end 75.64628 -39.7002)
		(width 0.1143)
		(layer "F.Cu")
		(net "RTC_X2PAD")
	)
	(segment
		(start 73.2028 -39.3446)
		(end 73.025 -39.3446)
		(width 0.1143)
		(layer "F.Cu")
		(net "RTC_X2PAD")
	)
	(segment
		(start 74.4982 -40.0812)
		(end 73.9394 -40.0812)
		(width 0.1143)
		(layer "F.Cu")
		(net "RTC_X2PAD")
	)
	(segment
		(start 78.855062 -39.661084)
		(end 79.811372 -39.661084)
		(width 0.1143)
		(layer "F.Cu")
		(net "RTC_X2PAD")
	)
	(segment
		(start 80.2259 -39.506144)
		(end 80.48371 -39.763954)
		(width 0.1143)
		(layer "F.Cu")
		(net "RTC_X2PAD")
	)
	(segment
		(start 79.811372 -39.661084)
		(end 79.92745 -39.54526)
		(width 0.1143)
		(layer "F.Cu")
		(net "RTC_X2PAD")
	)
	(segment
		(start 80.48371 -39.763954)
		(end 81.054448 -39.763954)
		(width 0.1143)
		(layer "F.Cu")
		(net "RTC_X2PAD")
	)
	(segment
		(start 79.92745 -39.54526)
		(end 79.96682 -39.506144)
		(width 0.1143)
		(layer "F.Cu")
		(net "RTC_X2PAD")
	)
	(segment
		(start 78.63332 -39.439342)
		(end 78.855062 -39.661084)
		(width 0.1143)
		(layer "F.Cu")
		(net "RTC_X2PAD")
	)
	(segment
		(start 77.419962 -39.439342)
		(end 78.63332 -39.439342)
		(width 0.1143)
		(layer "F.Cu")
		(net "RTC_X2PAD")
	)
	(segment
		(start 77.282548 -39.301928)
		(end 77.419962 -39.439342)
		(width 0.1143)
		(layer "F.Cu")
		(net "RTC_X2PAD")
	)
	(segment
		(start 74.4982 -40.0812)
		(end 74.8792 -39.7002)
		(width 0.1143)
		(layer "F.Cu")
		(net "RTC_X2PAD")
	)
	(segment
		(start 79.96682 -39.506144)
		(end 80.2259 -39.506144)
		(width 0.1143)
		(layer "F.Cu")
		(net "RTC_X2PAD")
	)
	(via
		(at 75.874118 -39.472362)
		(size 0.7112)
		(drill 0.3556)
		(layers "F.Cu" "B.Cu")
		(net "RTC_X2PAD")
	)
	(segment
		(start 23.8506 -65.66408)
		(end 23.8506 -66.4718)
		(width 0.508)
		(layer "F.Cu")
		(net "VR_PVNN_BOOT_R")
	)
	(segment
		(start 23.98268 -65.532)
		(end 23.8506 -65.66408)
		(width 0.508)
		(layer "F.Cu")
		(net "VR_PVNN_BOOT_R")
	)
	(segment
		(start 118.364 -47.117)
		(end 114.427 -47.117)
		(width 0.1016)
		(layer "F.Cu")
		(net "M_A_ECC4")
	)
	(segment
		(start 112.269524 -44.959524)
		(end 111.126778 -44.959524)
		(width 0.1016)
		(layer "F.Cu")
		(net "M_A_ECC4")
	)
	(segment
		(start 114.427 -47.117)
		(end 112.269524 -44.959524)
		(width 0.1016)
		(layer "F.Cu")
		(net "M_A_ECC4")
	)
	(segment
		(start 111.126778 -44.959524)
		(end 111.097568 -44.988734)
		(width 0.1016)
		(layer "F.Cu")
		(net "M_A_ECC4")
	)
	(segment
		(start 169.749978 -70.029578)
		(end 168.9862 -69.2658)
		(width 0.1778)
		(layer "F.Cu")
		(net "M_A_ECC4")
	)
	(segment
		(start 169.749978 -70.806564)
		(end 169.749978 -70.029578)
		(width 0.1778)
		(layer "F.Cu")
		(net "M_A_ECC4")
	)
	(segment
		(start 168.9862 -69.2658)
		(end 168.9354 -69.2658)
		(width 0.1778)
		(layer "F.Cu")
		(net "M_A_ECC4")
	)
	(via
		(at 168.9354 -69.2658)
		(size 0.4318)
		(drill 0.2032)
		(layers "F.Cu" "B.Cu")
		(net "M_A_ECC4")
	)
	(via
		(at 118.364 -47.117)
		(size 0.4318)
		(drill 0.2032)
		(layers "F.Cu" "B.Cu")
		(net "M_A_ECC4")
	)
	(segment
		(start 168.850056 -70.003416)
		(end 168.67124 -69.8246)
		(width 0.1778)
		(layer "B.Cu")
		(net "M_A_ECC4")
	)
	(segment
		(start 168.67124 -69.52996)
		(end 168.9354 -69.2658)
		(width 0.1778)
		(layer "B.Cu")
		(net "M_A_ECC4")
	)
	(segment
		(start 168.67124 -69.8246)
		(end 168.67124 -69.52996)
		(width 0.1778)
		(layer "B.Cu")
		(net "M_A_ECC4")
	)
	(segment
		(start 168.850056 -70.79996)
		(end 168.850056 -70.003416)
		(width 0.1778)
		(layer "B.Cu")
		(net "M_A_ECC4")
	)
	(segment
		(start 169.073576 -60.42279)
		(end 169.073576 -62.418976)
		(width 0.1524)
		(layer "In2.Cu")
		(net "M_A_ECC4")
	)
	(segment
		(start 121.3358 -47.371)
		(end 148.298662 -47.371)
		(width 0.1524)
		(layer "In2.Cu")
		(net "M_A_ECC4")
	)
	(segment
		(start 169.74312 -65.96888)
		(end 169.274998 -66.437002)
		(width 0.1524)
		(layer "In2.Cu")
		(net "M_A_ECC4")
	)
	(segment
		(start 161.381186 -52.7304)
		(end 169.073576 -60.42279)
		(width 0.1524)
		(layer "In2.Cu")
		(net "M_A_ECC4")
	)
	(segment
		(start 118.8212 -46.6598)
		(end 118.364 -47.117)
		(width 0.1016)
		(layer "In2.Cu")
		(net "M_A_ECC4")
	)
	(segment
		(start 153.482802 -51.308)
		(end 158.496 -51.308)
		(width 0.1524)
		(layer "In2.Cu")
		(net "M_A_ECC4")
	)
	(segment
		(start 120.6246 -46.6598)
		(end 118.8212 -46.6598)
		(width 0.1016)
		(layer "In2.Cu")
		(net "M_A_ECC4")
	)
	(segment
		(start 169.274998 -66.437002)
		(end 169.274998 -68.926202)
		(width 0.1524)
		(layer "In2.Cu")
		(net "M_A_ECC4")
	)
	(segment
		(start 153.311352 -51.13655)
		(end 153.482802 -51.308)
		(width 0.1524)
		(layer "In2.Cu")
		(net "M_A_ECC4")
	)
	(segment
		(start 169.74312 -63.08852)
		(end 169.74312 -65.96888)
		(width 0.1524)
		(layer "In2.Cu")
		(net "M_A_ECC4")
	)
	(segment
		(start 152.064212 -51.13655)
		(end 153.311352 -51.13655)
		(width 0.1524)
		(layer "In2.Cu")
		(net "M_A_ECC4")
	)
	(segment
		(start 158.496 -51.308)
		(end 159.9184 -52.7304)
		(width 0.1524)
		(layer "In2.Cu")
		(net "M_A_ECC4")
	)
	(segment
		(start 169.073576 -62.418976)
		(end 169.74312 -63.08852)
		(width 0.1524)
		(layer "In2.Cu")
		(net "M_A_ECC4")
	)
	(segment
		(start 121.3358 -47.371)
		(end 120.6246 -46.6598)
		(width 0.1016)
		(layer "In2.Cu")
		(net "M_A_ECC4")
	)
	(segment
		(start 159.9184 -52.7304)
		(end 161.381186 -52.7304)
		(width 0.1524)
		(layer "In2.Cu")
		(net "M_A_ECC4")
	)
	(segment
		(start 169.274998 -68.926202)
		(end 168.9354 -69.2658)
		(width 0.1524)
		(layer "In2.Cu")
		(net "M_A_ECC4")
	)
	(segment
		(start 148.298662 -47.371)
		(end 152.064212 -51.13655)
		(width 0.1524)
		(layer "In2.Cu")
		(net "M_A_ECC4")
	)
	(segment
		(start 23.263098 -61.69914)
		(end 23.263098 -61.292994)
		(width 0.2032)
		(layer "F.Cu")
		(net "VR_PVNN_PHASE")
	)
	(segment
		(start 38.46703 -64.516)
		(end 37.70503 -65.278)
		(width 0.508)
		(layer "F.Cu")
		(net "VR_PVNN_PHASE")
	)
	(segment
		(start 24.7904 -62.3316)
		(end 24.384 -61.9252)
		(width 0.2032)
		(layer "F.Cu")
		(net "VR_PVNN_PHASE")
	)
	(segment
		(start 23.8506 -67.3354)
		(end 24.638 -67.3354)
		(width 0.508)
		(layer "F.Cu")
		(net "VR_PVNN_PHASE")
	)
	(segment
		(start 23.489158 -61.9252)
		(end 23.263098 -61.69914)
		(width 0.2032)
		(layer "F.Cu")
		(net "VR_PVNN_PHASE")
	)
	(segment
		(start 25.4 -67.9196)
		(end 24.8158 -67.3354)
		(width 0.508)
		(layer "F.Cu")
		(net "VR_PVNN_PHASE")
	)
	(segment
		(start 39.4462 -64.516)
		(end 38.46703 -64.516)
		(width 0.508)
		(layer "F.Cu")
		(net "VR_PVNN_PHASE")
	)
	(segment
		(start 24.8158 -67.3354)
		(end 24.638 -67.3354)
		(width 0.508)
		(layer "F.Cu")
		(net "VR_PVNN_PHASE")
	)
	(segment
		(start 24.7904 -62.611)
		(end 24.7904 -62.3316)
		(width 0.2032)
		(layer "F.Cu")
		(net "VR_PVNN_PHASE")
	)
	(segment
		(start 24.384 -61.9252)
		(end 23.489158 -61.9252)
		(width 0.2032)
		(layer "F.Cu")
		(net "VR_PVNN_PHASE")
	)
	(via
		(at 24.7904 -62.611)
		(size 0.508)
		(drill 0.254)
		(layers "F.Cu" "B.Cu")
		(net "VR_PVNN_PHASE")
	)
	(via
		(at 39.4462 -64.516)
		(size 0.508)
		(drill 0.254)
		(layers "F.Cu" "B.Cu")
		(net "VR_PVNN_PHASE")
	)
	(via
		(at 35.814 -69.215)
		(size 0.7112)
		(drill 0.3556)
		(layers "F.Cu" "B.Cu")
		(net "VR_PVNN_PHASE")
	)
	(via
		(at 36.6268 -68.7578)
		(size 0.508)
		(drill 0.254)
		(layers "F.Cu" "B.Cu")
		(net "VR_PVNN_PHASE")
	)
	(via
		(at 25.4 -67.9196)
		(size 0.7112)
		(drill 0.4064)
		(layers "F.Cu" "B.Cu")
		(net "VR_PVNN_PHASE")
	)
	(segment
		(start 39.4462 -65.278)
		(end 39.4462 -64.516)
		(width 0.508)
		(layer "B.Cu")
		(net "VR_PVNN_PHASE")
	)
	(segment
		(start 34.798 -70.5866)
		(end 28.067 -70.5866)
		(width 0.508)
		(layer "In2.Cu")
		(net "VR_PVNN_PHASE")
	)
	(segment
		(start 24.6634 -62.738)
		(end 24.7904 -62.611)
		(width 0.508)
		(layer "In2.Cu")
		(net "VR_PVNN_PHASE")
	)
	(segment
		(start 28.067 -70.5866)
		(end 25.4 -67.9196)
		(width 0.508)
		(layer "In2.Cu")
		(net "VR_PVNN_PHASE")
	)
	(segment
		(start 25.4 -67.9196)
		(end 24.6634 -67.183)
		(width 0.508)
		(layer "In2.Cu")
		(net "VR_PVNN_PHASE")
	)
	(segment
		(start 24.6634 -67.183)
		(end 24.6634 -62.738)
		(width 0.508)
		(layer "In2.Cu")
		(net "VR_PVNN_PHASE")
	)
	(segment
		(start 36.6268 -68.7578)
		(end 34.798 -70.5866)
		(width 0.508)
		(layer "In2.Cu")
		(net "VR_PVNN_PHASE")
	)
	(segment
		(start 98.8314 -56.896)
		(end 98.6536 -56.7182)
		(width 0.1016)
		(layer "F.Cu")
		(net "M_A_DQ54")
	)
	(segment
		(start 98.532188 -52.608988)
		(end 98.532188 -52.28844)
		(width 0.1016)
		(layer "F.Cu")
		(net "M_A_DQ54")
	)
	(segment
		(start 98.532188 -52.28844)
		(end 98.892868 -51.92776)
		(width 0.1016)
		(layer "F.Cu")
		(net "M_A_DQ54")
	)
	(segment
		(start 98.6536 -52.7304)
		(end 98.532188 -52.608988)
		(width 0.1016)
		(layer "F.Cu")
		(net "M_A_DQ54")
	)
	(segment
		(start 135.42772 -68.99148)
		(end 135.6614 -68.7578)
		(width 0.1778)
		(layer "F.Cu")
		(net "M_A_DQ54")
	)
	(segment
		(start 134.949946 -70.806564)
		(end 134.949946 -69.856858)
		(width 0.1778)
		(layer "F.Cu")
		(net "M_A_DQ54")
	)
	(segment
		(start 98.892868 -51.92776)
		(end 98.892868 -51.620674)
		(width 0.1016)
		(layer "F.Cu")
		(net "M_A_DQ54")
	)
	(segment
		(start 98.6536 -56.7182)
		(end 98.6536 -52.7304)
		(width 0.1016)
		(layer "F.Cu")
		(net "M_A_DQ54")
	)
	(segment
		(start 134.949946 -69.856858)
		(end 135.42772 -69.379084)
		(width 0.1778)
		(layer "F.Cu")
		(net "M_A_DQ54")
	)
	(segment
		(start 98.892868 -51.620674)
		(end 99.065588 -51.447954)
		(width 0.1016)
		(layer "F.Cu")
		(net "M_A_DQ54")
	)
	(segment
		(start 135.42772 -69.379084)
		(end 135.42772 -68.99148)
		(width 0.1778)
		(layer "F.Cu")
		(net "M_A_DQ54")
	)
	(via
		(at 98.8314 -56.896)
		(size 0.4318)
		(drill 0.2032)
		(layers "F.Cu" "B.Cu")
		(net "M_A_DQ54")
	)
	(via
		(at 135.6614 -68.7578)
		(size 0.4318)
		(drill 0.2032)
		(layers "F.Cu" "B.Cu")
		(net "M_A_DQ54")
	)
	(segment
		(start 135.42772 -69.539358)
		(end 135.42772 -68.99148)
		(width 0.1778)
		(layer "B.Cu")
		(net "M_A_DQ54")
	)
	(segment
		(start 135.850122 -70.79996)
		(end 135.850122 -69.96176)
		(width 0.1778)
		(layer "B.Cu")
		(net "M_A_DQ54")
	)
	(segment
		(start 135.42772 -68.99148)
		(end 135.6614 -68.7578)
		(width 0.1778)
		(layer "B.Cu")
		(net "M_A_DQ54")
	)
	(segment
		(start 135.850122 -69.96176)
		(end 135.42772 -69.539358)
		(width 0.1778)
		(layer "B.Cu")
		(net "M_A_DQ54")
	)
	(segment
		(start 108.32846 -66.127122)
		(end 104.206548 -66.127122)
		(width 0.1524)
		(layer "In4.Cu")
		(net "M_A_DQ54")
	)
	(segment
		(start 135.3312 -62.9412)
		(end 127.7112 -62.9412)
		(width 0.1524)
		(layer "In4.Cu")
		(net "M_A_DQ54")
	)
	(segment
		(start 125.3744 -63.373)
		(end 121.7168 -63.373)
		(width 0.1524)
		(layer "In4.Cu")
		(net "M_A_DQ54")
	)
	(segment
		(start 99.2886 -59.8932)
		(end 99.2886 -57.3532)
		(width 0.1016)
		(layer "In4.Cu")
		(net "M_A_DQ54")
	)
	(segment
		(start 127.7112 -62.9412)
		(end 126.8222 -63.8302)
		(width 0.1524)
		(layer "In4.Cu")
		(net "M_A_DQ54")
	)
	(segment
		(start 98.963226 -60.8838)
		(end 98.963226 -60.218574)
		(width 0.1524)
		(layer "In4.Cu")
		(net "M_A_DQ54")
	)
	(segment
		(start 121.7168 -63.373)
		(end 118.24335 -66.84645)
		(width 0.1524)
		(layer "In4.Cu")
		(net "M_A_DQ54")
	)
	(segment
		(start 136.3726 -63.9826)
		(end 135.3312 -62.9412)
		(width 0.1524)
		(layer "In4.Cu")
		(net "M_A_DQ54")
	)
	(segment
		(start 135.391398 -66.310002)
		(end 136.3726 -65.3288)
		(width 0.1524)
		(layer "In4.Cu")
		(net "M_A_DQ54")
	)
	(segment
		(start 126.8222 -63.8302)
		(end 125.8316 -63.8302)
		(width 0.1524)
		(layer "In4.Cu")
		(net "M_A_DQ54")
	)
	(segment
		(start 109.047788 -66.84645)
		(end 108.32846 -66.127122)
		(width 0.1524)
		(layer "In4.Cu")
		(net "M_A_DQ54")
	)
	(segment
		(start 99.2886 -57.3532)
		(end 98.8314 -56.896)
		(width 0.1016)
		(layer "In4.Cu")
		(net "M_A_DQ54")
	)
	(segment
		(start 135.391398 -68.487798)
		(end 135.391398 -66.310002)
		(width 0.1524)
		(layer "In4.Cu")
		(net "M_A_DQ54")
	)
	(segment
		(start 104.206548 -66.127122)
		(end 98.963226 -60.8838)
		(width 0.1524)
		(layer "In4.Cu")
		(net "M_A_DQ54")
	)
	(segment
		(start 135.6614 -68.7578)
		(end 135.391398 -68.487798)
		(width 0.1524)
		(layer "In4.Cu")
		(net "M_A_DQ54")
	)
	(segment
		(start 136.3726 -65.3288)
		(end 136.3726 -63.9826)
		(width 0.1524)
		(layer "In4.Cu")
		(net "M_A_DQ54")
	)
	(segment
		(start 125.8316 -63.8302)
		(end 125.3744 -63.373)
		(width 0.1524)
		(layer "In4.Cu")
		(net "M_A_DQ54")
	)
	(segment
		(start 98.963226 -60.218574)
		(end 99.2886 -59.8932)
		(width 0.1524)
		(layer "In4.Cu")
		(net "M_A_DQ54")
	)
	(segment
		(start 118.24335 -66.84645)
		(end 109.047788 -66.84645)
		(width 0.1524)
		(layer "In4.Cu")
		(net "M_A_DQ54")
	)
	(segment
		(start 169.15003 -70.806564)
		(end 169.15003 -70.16623)
		(width 0.1778)
		(layer "F.Cu")
		(net "M_A_ECC5")
	)
	(segment
		(start 168.5798 -69.596)
		(end 167.513 -69.596)
		(width 0.1778)
		(layer "F.Cu")
		(net "M_A_ECC5")
	)
	(segment
		(start 120.1674 -47.117)
		(end 119.7356 -47.5488)
		(width 0.1016)
		(layer "F.Cu")
		(net "M_A_ECC5")
	)
	(segment
		(start 112.174274 -45.245274)
		(end 112.098328 -45.245274)
		(width 0.1016)
		(layer "F.Cu")
		(net "M_A_ECC5")
	)
	(segment
		(start 114.4778 -47.5488)
		(end 112.174274 -45.245274)
		(width 0.1016)
		(layer "F.Cu")
		(net "M_A_ECC5")
	)
	(segment
		(start 119.7356 -47.5488)
		(end 114.4778 -47.5488)
		(width 0.1016)
		(layer "F.Cu")
		(net "M_A_ECC5")
	)
	(segment
		(start 169.15003 -70.16623)
		(end 168.5798 -69.596)
		(width 0.1778)
		(layer "F.Cu")
		(net "M_A_ECC5")
	)
	(via
		(at 120.1674 -47.117)
		(size 0.4318)
		(drill 0.2032)
		(layers "F.Cu" "B.Cu")
		(net "M_A_ECC5")
	)
	(via
		(at 167.513 -69.596)
		(size 0.4318)
		(drill 0.2032)
		(layers "F.Cu" "B.Cu")
		(net "M_A_ECC5")
	)
	(segment
		(start 165.850062 -70.192138)
		(end 166.4462 -69.596)
		(width 0.1778)
		(layer "B.Cu")
		(net "M_A_ECC5")
	)
	(segment
		(start 165.850062 -70.79996)
		(end 165.850062 -70.192138)
		(width 0.1778)
		(layer "B.Cu")
		(net "M_A_ECC5")
	)
	(segment
		(start 166.4462 -69.596)
		(end 167.513 -69.596)
		(width 0.1778)
		(layer "B.Cu")
		(net "M_A_ECC5")
	)
	(segment
		(start 169.46372 -63.62192)
		(end 168.301162 -62.459362)
		(width 0.1524)
		(layer "In2.Cu")
		(net "M_A_ECC5")
	)
	(segment
		(start 167.513 -69.088)
		(end 168.8592 -67.7418)
		(width 0.1524)
		(layer "In2.Cu")
		(net "M_A_ECC5")
	)
	(segment
		(start 120.4468 -47.117)
		(end 120.1674 -47.117)
		(width 0.1016)
		(layer "In2.Cu")
		(net "M_A_ECC5")
	)
	(segment
		(start 168.8592 -65.659)
		(end 169.46372 -65.05448)
		(width 0.1524)
		(layer "In2.Cu")
		(net "M_A_ECC5")
	)
	(segment
		(start 161.139124 -53.3146)
		(end 158.3436 -53.3146)
		(width 0.1524)
		(layer "In2.Cu")
		(net "M_A_ECC5")
	)
	(segment
		(start 145.444718 -48.895)
		(end 144.581118 -48.0314)
		(width 0.1524)
		(layer "In2.Cu")
		(net "M_A_ECC5")
	)
	(segment
		(start 169.46372 -65.05448)
		(end 169.46372 -63.62192)
		(width 0.1524)
		(layer "In2.Cu")
		(net "M_A_ECC5")
	)
	(segment
		(start 157.9499 -52.6161)
		(end 157.607 -52.2732)
		(width 0.1524)
		(layer "In2.Cu")
		(net "M_A_ECC5")
	)
	(segment
		(start 152.3746 -52.2732)
		(end 148.9964 -48.895)
		(width 0.1524)
		(layer "In2.Cu")
		(net "M_A_ECC5")
	)
	(segment
		(start 148.9964 -48.895)
		(end 145.444718 -48.895)
		(width 0.1524)
		(layer "In2.Cu")
		(net "M_A_ECC5")
	)
	(segment
		(start 121.3612 -48.0314)
		(end 120.4468 -47.117)
		(width 0.1016)
		(layer "In2.Cu")
		(net "M_A_ECC5")
	)
	(segment
		(start 167.513 -69.596)
		(end 167.513 -69.088)
		(width 0.1524)
		(layer "In2.Cu")
		(net "M_A_ECC5")
	)
	(segment
		(start 158.3436 -53.3146)
		(end 157.9499 -52.9209)
		(width 0.1524)
		(layer "In2.Cu")
		(net "M_A_ECC5")
	)
	(segment
		(start 168.301162 -60.476638)
		(end 161.139124 -53.3146)
		(width 0.1524)
		(layer "In2.Cu")
		(net "M_A_ECC5")
	)
	(segment
		(start 144.581118 -48.0314)
		(end 121.3612 -48.0314)
		(width 0.1524)
		(layer "In2.Cu")
		(net "M_A_ECC5")
	)
	(segment
		(start 168.301162 -62.459362)
		(end 168.301162 -60.476638)
		(width 0.1524)
		(layer "In2.Cu")
		(net "M_A_ECC5")
	)
	(segment
		(start 157.9499 -52.9209)
		(end 157.9499 -52.6161)
		(width 0.1524)
		(layer "In2.Cu")
		(net "M_A_ECC5")
	)
	(segment
		(start 157.607 -52.2732)
		(end 152.3746 -52.2732)
		(width 0.1524)
		(layer "In2.Cu")
		(net "M_A_ECC5")
	)
	(segment
		(start 168.8592 -67.7418)
		(end 168.8592 -65.659)
		(width 0.1524)
		(layer "In2.Cu")
		(net "M_A_ECC5")
	)
	(segment
		(start 102.743 -18.542)
		(end 103.185976 -18.099024)
		(width 0.1143)
		(layer "F.Cu")
		(net "LPC_CPU_LAD2")
	)
	(segment
		(start 86.546944 -20.463256)
		(end 86.1314 -20.8788)
		(width 0.1143)
		(layer "F.Cu")
		(net "LPC_CPU_LAD2")
	)
	(segment
		(start 90.34018 -20.463256)
		(end 89.513664 -20.463256)
		(width 0.1143)
		(layer "F.Cu")
		(net "LPC_CPU_LAD2")
	)
	(segment
		(start 104.2924 -16.7894)
		(end 103.8733 -16.7894)
		(width 0.1143)
		(layer "F.Cu")
		(net "LPC_CPU_LAD2")
	)
	(segment
		(start 90.934286 -19.86915)
		(end 90.34018 -20.463256)
		(width 0.1143)
		(layer "F.Cu")
		(net "LPC_CPU_LAD2")
	)
	(segment
		(start 103.420164 -19.05)
		(end 102.997 -19.05)
		(width 0.1143)
		(layer "F.Cu")
		(net "LPC_CPU_LAD2")
	)
	(segment
		(start 98.986848 -18.996152)
		(end 93.678248 -18.996152)
		(width 0.1143)
		(layer "F.Cu")
		(net "LPC_CPU_LAD2")
	)
	(segment
		(start 93.678248 -18.996152)
		(end 92.80525 -19.86915)
		(width 0.1143)
		(layer "F.Cu")
		(net "LPC_CPU_LAD2")
	)
	(segment
		(start 105.3084 -17.145)
		(end 104.648 -17.145)
		(width 0.1143)
		(layer "F.Cu")
		(net "LPC_CPU_LAD2")
	)
	(segment
		(start 85.933788 -40.716454)
		(end 85.902546 -40.716454)
		(width 0.1143)
		(layer "F.Cu")
		(net "LPC_CPU_LAD2")
	)
	(segment
		(start 104.648 -17.145)
		(end 104.2924 -16.7894)
		(width 0.1143)
		(layer "F.Cu")
		(net "LPC_CPU_LAD2")
	)
	(segment
		(start 101.237542 -18.128742)
		(end 101.237542 -18.290286)
		(width 0.1143)
		(layer "F.Cu")
		(net "LPC_CPU_LAD2")
	)
	(segment
		(start 102.1461 -18.06702)
		(end 101.984556 -18.06702)
		(width 0.1143)
		(layer "F.Cu")
		(net "LPC_CPU_LAD2")
	)
	(segment
		(start 104.0257 -18.444464)
		(end 103.420164 -19.05)
		(width 0.1143)
		(layer "F.Cu")
		(net "LPC_CPU_LAD2")
	)
	(segment
		(start 101.237542 -18.290286)
		(end 101.4095 -18.462244)
		(width 0.1143)
		(layer "F.Cu")
		(net "LPC_CPU_LAD2")
	)
	(segment
		(start 84.2264 -20.8788)
		(end 82.9564 -20.8788)
		(width 0.1143)
		(layer "F.Cu")
		(net "LPC_CPU_LAD2")
	)
	(segment
		(start 103.759 -16.9037)
		(end 103.759 -17.606264)
		(width 0.1143)
		(layer "F.Cu")
		(net "LPC_CPU_LAD2")
	)
	(segment
		(start 89.513664 -20.463256)
		(end 89.268808 -20.2184)
		(width 0.1143)
		(layer "F.Cu")
		(net "LPC_CPU_LAD2")
	)
	(segment
		(start 103.071676 -16.7894)
		(end 102.576884 -16.7894)
		(width 0.1143)
		(layer "F.Cu")
		(net "LPC_CPU_LAD2")
	)
	(segment
		(start 105.664 -16.7894)
		(end 105.3084 -17.145)
		(width 0.1143)
		(layer "F.Cu")
		(net "LPC_CPU_LAD2")
	)
	(segment
		(start 81.407 -24.892)
		(end 81.0006 -24.892)
		(width 0.1143)
		(layer "F.Cu")
		(net "LPC_CPU_LAD2")
	)
	(segment
		(start 114.439446 -17.770094)
		(end 113.458752 -16.7894)
		(width 0.1143)
		(layer "F.Cu")
		(net "LPC_CPU_LAD2")
	)
	(segment
		(start 114.439446 -23.856442)
		(end 114.439446 -17.770094)
		(width 0.1143)
		(layer "F.Cu")
		(net "LPC_CPU_LAD2")
	)
	(segment
		(start 103.8733 -16.7894)
		(end 103.759 -16.9037)
		(width 0.1143)
		(layer "F.Cu")
		(net "LPC_CPU_LAD2")
	)
	(segment
		(start 82.44713 -23.85187)
		(end 81.407 -24.892)
		(width 0.1143)
		(layer "F.Cu")
		(net "LPC_CPU_LAD2")
	)
	(segment
		(start 92.80525 -19.86915)
		(end 90.934286 -19.86915)
		(width 0.1143)
		(layer "F.Cu")
		(net "LPC_CPU_LAD2")
	)
	(segment
		(start 102.207822 -17.158462)
		(end 102.207822 -17.320006)
		(width 0.1143)
		(layer "F.Cu")
		(net "LPC_CPU_LAD2")
	)
	(segment
		(start 103.185976 -18.099024)
		(end 103.185976 -16.9037)
		(width 0.1143)
		(layer "F.Cu")
		(net "LPC_CPU_LAD2")
	)
	(segment
		(start 82.2198 -22.170136)
		(end 82.2198 -23.0124)
		(width 0.1143)
		(layer "F.Cu")
		(net "LPC_CPU_LAD2")
	)
	(segment
		(start 103.185976 -16.9037)
		(end 103.071676 -16.7894)
		(width 0.1143)
		(layer "F.Cu")
		(net "LPC_CPU_LAD2")
	)
	(segment
		(start 103.759 -17.606264)
		(end 104.0257 -17.872964)
		(width 0.1143)
		(layer "F.Cu")
		(net "LPC_CPU_LAD2")
	)
	(segment
		(start 82.2198 -23.0124)
		(end 82.44713 -23.23973)
		(width 0.1143)
		(layer "F.Cu")
		(net "LPC_CPU_LAD2")
	)
	(segment
		(start 102.469696 -17.58188)
		(end 102.469696 -17.743424)
		(width 0.1143)
		(layer "F.Cu")
		(net "LPC_CPU_LAD2")
	)
	(segment
		(start 113.458752 -16.7894)
		(end 105.664 -16.7894)
		(width 0.1143)
		(layer "F.Cu")
		(net "LPC_CPU_LAD2")
	)
	(segment
		(start 99.7712 -18.2118)
		(end 98.986848 -18.996152)
		(width 0.1143)
		(layer "F.Cu")
		(net "LPC_CPU_LAD2")
	)
	(segment
		(start 101.4095 -18.623788)
		(end 101.143054 -18.890488)
		(width 0.1143)
		(layer "F.Cu")
		(net "LPC_CPU_LAD2")
	)
	(segment
		(start 89.268808 -20.2184)
		(end 88.863932 -20.2184)
		(width 0.1143)
		(layer "F.Cu")
		(net "LPC_CPU_LAD2")
	)
	(segment
		(start 101.561138 -17.805146)
		(end 101.237542 -18.128742)
		(width 0.1143)
		(layer "F.Cu")
		(net "LPC_CPU_LAD2")
	)
	(segment
		(start 100.303076 -18.2118)
		(end 99.7712 -18.2118)
		(width 0.1143)
		(layer "F.Cu")
		(net "LPC_CPU_LAD2")
	)
	(segment
		(start 82.44713 -23.23973)
		(end 82.44713 -23.85187)
		(width 0.1143)
		(layer "F.Cu")
		(net "LPC_CPU_LAD2")
	)
	(segment
		(start 102.997 -19.05)
		(end 102.743 -18.796)
		(width 0.1143)
		(layer "F.Cu")
		(net "LPC_CPU_LAD2")
	)
	(segment
		(start 127.7112 -36.83)
		(end 127.413004 -36.83)
		(width 0.1143)
		(layer "F.Cu")
		(net "LPC_CPU_LAD2")
	)
	(segment
		(start 127.413004 -36.83)
		(end 114.439446 -23.856442)
		(width 0.1143)
		(layer "F.Cu")
		(net "LPC_CPU_LAD2")
	)
	(segment
		(start 82.804 -21.0312)
		(end 82.804 -21.585936)
		(width 0.1143)
		(layer "F.Cu")
		(net "LPC_CPU_LAD2")
	)
	(segment
		(start 102.576884 -16.7894)
		(end 102.207822 -17.158462)
		(width 0.1143)
		(layer "F.Cu")
		(net "LPC_CPU_LAD2")
	)
	(segment
		(start 85.902546 -40.716454)
		(end 85.5726 -41.0464)
		(width 0.1143)
		(layer "F.Cu")
		(net "LPC_CPU_LAD2")
	)
	(segment
		(start 101.143054 -18.890488)
		(end 100.981764 -18.890488)
		(width 0.1143)
		(layer "F.Cu")
		(net "LPC_CPU_LAD2")
	)
	(segment
		(start 101.722682 -17.805146)
		(end 101.561138 -17.805146)
		(width 0.1143)
		(layer "F.Cu")
		(net "LPC_CPU_LAD2")
	)
	(segment
		(start 86.1314 -20.8788)
		(end 84.2264 -20.8788)
		(width 0.1143)
		(layer "F.Cu")
		(net "LPC_CPU_LAD2")
	)
	(segment
		(start 82.9564 -20.8788)
		(end 82.804 -21.0312)
		(width 0.1143)
		(layer "F.Cu")
		(net "LPC_CPU_LAD2")
	)
	(segment
		(start 102.743 -18.796)
		(end 102.743 -18.542)
		(width 0.1143)
		(layer "F.Cu")
		(net "LPC_CPU_LAD2")
	)
	(segment
		(start 104.0257 -17.872964)
		(end 104.0257 -18.444464)
		(width 0.1143)
		(layer "F.Cu")
		(net "LPC_CPU_LAD2")
	)
	(segment
		(start 101.4095 -18.462244)
		(end 101.4095 -18.623788)
		(width 0.1143)
		(layer "F.Cu")
		(net "LPC_CPU_LAD2")
	)
	(segment
		(start 88.863932 -20.2184)
		(end 88.619076 -20.463256)
		(width 0.1143)
		(layer "F.Cu")
		(net "LPC_CPU_LAD2")
	)
	(segment
		(start 102.469696 -17.743424)
		(end 102.1461 -18.06702)
		(width 0.1143)
		(layer "F.Cu")
		(net "LPC_CPU_LAD2")
	)
	(segment
		(start 88.619076 -20.463256)
		(end 86.546944 -20.463256)
		(width 0.1143)
		(layer "F.Cu")
		(net "LPC_CPU_LAD2")
	)
	(segment
		(start 100.981764 -18.890488)
		(end 100.303076 -18.2118)
		(width 0.1143)
		(layer "F.Cu")
		(net "LPC_CPU_LAD2")
	)
	(segment
		(start 82.804 -21.585936)
		(end 82.2198 -22.170136)
		(width 0.1143)
		(layer "F.Cu")
		(net "LPC_CPU_LAD2")
	)
	(segment
		(start 102.207822 -17.320006)
		(end 102.469696 -17.58188)
		(width 0.1143)
		(layer "F.Cu")
		(net "LPC_CPU_LAD2")
	)
	(segment
		(start 101.984556 -18.06702)
		(end 101.722682 -17.805146)
		(width 0.1143)
		(layer "F.Cu")
		(net "LPC_CPU_LAD2")
	)
	(via
		(at 84.2264 -20.8788)
		(size 0.7112)
		(drill 0.3556)
		(layers "F.Cu" "B.Cu")
		(net "LPC_CPU_LAD2")
	)
	(via
		(at 85.5726 -41.0464)
		(size 0.4318)
		(drill 0.2032)
		(layers "F.Cu" "B.Cu")
		(net "LPC_CPU_LAD2")
	)
	(via
		(at 81.0006 -24.892)
		(size 0.4318)
		(drill 0.2032)
		(layers "F.Cu" "B.Cu")
		(net "LPC_CPU_LAD2")
	)
	(segment
		(start 81.0006 -26.797)
		(end 80.645 -26.4414)
		(width 0.0889)
		(layer "In9.Cu")
		(net "LPC_CPU_LAD2")
	)
	(segment
		(start 80.899 -29.420566)
		(end 80.65008 -29.171646)
		(width 0.0889)
		(layer "In9.Cu")
		(net "LPC_CPU_LAD2")
	)
	(segment
		(start 86.233 -40.64)
		(end 86.233 -40.100758)
		(width 0.0889)
		(layer "In9.Cu")
		(net "LPC_CPU_LAD2")
	)
	(segment
		(start 81.0387 -24.892)
		(end 81.0006 -24.892)
		(width 0.0889)
		(layer "In9.Cu")
		(net "LPC_CPU_LAD2")
	)
	(segment
		(start 81.5086 -37.6682)
		(end 81.407 -37.5666)
		(width 0.0889)
		(layer "In9.Cu")
		(net "LPC_CPU_LAD2")
	)
	(segment
		(start 81.0006 -27.432)
		(end 81.0006 -26.797)
		(width 0.0889)
		(layer "In9.Cu")
		(net "LPC_CPU_LAD2")
	)
	(segment
		(start 85.596984 -39.775384)
		(end 85.596984 -38.7985)
		(width 0.0889)
		(layer "In9.Cu")
		(net "LPC_CPU_LAD2")
	)
	(segment
		(start 81.0006 -36.195)
		(end 81.350358 -36.195)
		(width 0.0889)
		(layer "In9.Cu")
		(net "LPC_CPU_LAD2")
	)
	(segment
		(start 80.518 -32.893)
		(end 80.518 -32.5374)
		(width 0.0889)
		(layer "In9.Cu")
		(net "LPC_CPU_LAD2")
	)
	(segment
		(start 85.596984 -38.7985)
		(end 85.495384 -38.6969)
		(width 0.0889)
		(layer "In9.Cu")
		(net "LPC_CPU_LAD2")
	)
	(segment
		(start 80.899 -36.576)
		(end 80.899 -36.2966)
		(width 0.0889)
		(layer "In9.Cu")
		(net "LPC_CPU_LAD2")
	)
	(segment
		(start 81.0006 -36.6776)
		(end 80.899 -36.576)
		(width 0.0889)
		(layer "In9.Cu")
		(net "LPC_CPU_LAD2")
	)
	(segment
		(start 81.788 -37.0078)
		(end 81.788 -36.7792)
		(width 0.0889)
		(layer "In9.Cu")
		(net "LPC_CPU_LAD2")
	)
	(segment
		(start 81.6864 -36.6776)
		(end 81.0006 -36.6776)
		(width 0.0889)
		(layer "In9.Cu")
		(net "LPC_CPU_LAD2")
	)
	(segment
		(start 81.153 -25.8191)
		(end 81.153 -25.0063)
		(width 0.0889)
		(layer "In9.Cu")
		(net "LPC_CPU_LAD2")
	)
	(segment
		(start 80.783684 -33.158684)
		(end 80.518 -32.893)
		(width 0.0889)
		(layer "In9.Cu")
		(net "LPC_CPU_LAD2")
	)
	(segment
		(start 79.838296 -37.255704)
		(end 79.952596 -37.141404)
		(width 0.0889)
		(layer "In9.Cu")
		(net "LPC_CPU_LAD2")
	)
	(segment
		(start 80.899 -36.2966)
		(end 81.0006 -36.195)
		(width 0.0889)
		(layer "In9.Cu")
		(net "LPC_CPU_LAD2")
	)
	(segment
		(start 81.0006 -30.8102)
		(end 80.5307 -30.3403)
		(width 0.0889)
		(layer "In9.Cu")
		(net "LPC_CPU_LAD2")
	)
	(segment
		(start 81.5594 -31.0642)
		(end 81.3054 -30.8102)
		(width 0.0889)
		(layer "In9.Cu")
		(net "LPC_CPU_LAD2")
	)
	(segment
		(start 80.857344 -25.9334)
		(end 81.0387 -25.9334)
		(width 0.0889)
		(layer "In9.Cu")
		(net "LPC_CPU_LAD2")
	)
	(segment
		(start 81.0387 -25.9334)
		(end 81.153 -25.8191)
		(width 0.0889)
		(layer "In9.Cu")
		(net "LPC_CPU_LAD2")
	)
	(segment
		(start 81.6102 -38.66515)
		(end 81.5086 -38.56355)
		(width 0.0889)
		(layer "In9.Cu")
		(net "LPC_CPU_LAD2")
	)
	(segment
		(start 81.3054 -30.8102)
		(end 81.0006 -30.8102)
		(width 0.0889)
		(layer "In9.Cu")
		(net "LPC_CPU_LAD2")
	)
	(segment
		(start 85.8266 -41.0464)
		(end 86.233 -40.64)
		(width 0.0889)
		(layer "In9.Cu")
		(net "LPC_CPU_LAD2")
	)
	(segment
		(start 80.762856 -28.459684)
		(end 81.0006 -28.22194)
		(width 0.0889)
		(layer "In9.Cu")
		(net "LPC_CPU_LAD2")
	)
	(segment
		(start 81.5594 -31.496)
		(end 81.5594 -31.0642)
		(width 0.0889)
		(layer "In9.Cu")
		(net "LPC_CPU_LAD2")
	)
	(segment
		(start 81.654396 -37.141404)
		(end 81.788 -37.0078)
		(width 0.0889)
		(layer "In9.Cu")
		(net "LPC_CPU_LAD2")
	)
	(segment
		(start 80.518 -32.5374)
		(end 81.5594 -31.496)
		(width 0.0889)
		(layer "In9.Cu")
		(net "LPC_CPU_LAD2")
	)
	(segment
		(start 82.9818 -38.5953)
		(end 82.9818 -38.3921)
		(width 0.0889)
		(layer "In9.Cu")
		(net "LPC_CPU_LAD2")
	)
	(segment
		(start 81.5086 -38.56355)
		(end 81.5086 -37.6682)
		(width 0.0889)
		(layer "In9.Cu")
		(net "LPC_CPU_LAD2")
	)
	(segment
		(start 82.16011 -37.9984)
		(end 82.0166 -37.9984)
		(width 0.0889)
		(layer "In9.Cu")
		(net "LPC_CPU_LAD2")
	)
	(segment
		(start 81.407 -37.5666)
		(end 80.000094 -37.5666)
		(width 0.0889)
		(layer "In9.Cu")
		(net "LPC_CPU_LAD2")
	)
	(segment
		(start 85.495384 -38.6969)
		(end 83.0834 -38.6969)
		(width 0.0889)
		(layer "In9.Cu")
		(net "LPC_CPU_LAD2")
	)
	(segment
		(start 80.645 -35.192716)
		(end 80.645 -34.798)
		(width 0.0889)
		(layer "In9.Cu")
		(net "LPC_CPU_LAD2")
	)
	(segment
		(start 80.783684 -34.659316)
		(end 80.783684 -33.158684)
		(width 0.0889)
		(layer "In9.Cu")
		(net "LPC_CPU_LAD2")
	)
	(segment
		(start 82.5373 -38.66515)
		(end 82.3595 -38.66515)
		(width 0.0889)
		(layer "In9.Cu")
		(net "LPC_CPU_LAD2")
	)
	(segment
		(start 80.885284 -35.433)
		(end 80.645 -35.192716)
		(width 0.0889)
		(layer "In9.Cu")
		(net "LPC_CPU_LAD2")
	)
	(segment
		(start 81.8261 -38.66515)
		(end 81.6102 -38.66515)
		(width 0.0889)
		(layer "In9.Cu")
		(net "LPC_CPU_LAD2")
	)
	(segment
		(start 80.645 -26.145744)
		(end 80.857344 -25.9334)
		(width 0.0889)
		(layer "In9.Cu")
		(net "LPC_CPU_LAD2")
	)
	(segment
		(start 82.8929 -38.3032)
		(end 82.7151 -38.3032)
		(width 0.0889)
		(layer "In9.Cu")
		(net "LPC_CPU_LAD2")
	)
	(segment
		(start 85.5726 -41.0464)
		(end 85.8266 -41.0464)
		(width 0.0889)
		(layer "In9.Cu")
		(net "LPC_CPU_LAD2")
	)
	(segment
		(start 81.350358 -35.433)
		(end 80.885284 -35.433)
		(width 0.0889)
		(layer "In9.Cu")
		(net "LPC_CPU_LAD2")
	)
	(segment
		(start 81.0006 -28.22194)
		(end 81.0006 -27.9146)
		(width 0.0889)
		(layer "In9.Cu")
		(net "LPC_CPU_LAD2")
	)
	(segment
		(start 80.899 -27.5336)
		(end 81.0006 -27.432)
		(width 0.0889)
		(layer "In9.Cu")
		(net "LPC_CPU_LAD2")
	)
	(segment
		(start 80.899 -29.634434)
		(end 80.899 -29.420566)
		(width 0.0889)
		(layer "In9.Cu")
		(net "LPC_CPU_LAD2")
	)
	(segment
		(start 82.6262 -38.3921)
		(end 82.6262 -38.57625)
		(width 0.0889)
		(layer "In9.Cu")
		(net "LPC_CPU_LAD2")
	)
	(segment
		(start 81.451958 -35.5346)
		(end 81.350358 -35.433)
		(width 0.0889)
		(layer "In9.Cu")
		(net "LPC_CPU_LAD2")
	)
	(segment
		(start 85.6996 -39.878)
		(end 85.596984 -39.775384)
		(width 0.0889)
		(layer "In9.Cu")
		(net "LPC_CPU_LAD2")
	)
	(segment
		(start 80.65008 -28.572968)
		(end 80.762856 -28.459684)
		(width 0.0889)
		(layer "In9.Cu")
		(net "LPC_CPU_LAD2")
	)
	(segment
		(start 83.0834 -38.6969)
		(end 82.9818 -38.5953)
		(width 0.0889)
		(layer "In9.Cu")
		(net "LPC_CPU_LAD2")
	)
	(segment
		(start 82.0166 -37.9984)
		(end 81.915 -38.1)
		(width 0.0889)
		(layer "In9.Cu")
		(net "LPC_CPU_LAD2")
	)
	(segment
		(start 82.3595 -38.66515)
		(end 82.2706 -38.57625)
		(width 0.0889)
		(layer "In9.Cu")
		(net "LPC_CPU_LAD2")
	)
	(segment
		(start 79.952596 -37.141404)
		(end 81.654396 -37.141404)
		(width 0.0889)
		(layer "In9.Cu")
		(net "LPC_CPU_LAD2")
	)
	(segment
		(start 79.838296 -37.404802)
		(end 79.838296 -37.255704)
		(width 0.0889)
		(layer "In9.Cu")
		(net "LPC_CPU_LAD2")
	)
	(segment
		(start 80.65008 -29.171646)
		(end 80.65008 -28.572968)
		(width 0.0889)
		(layer "In9.Cu")
		(net "LPC_CPU_LAD2")
	)
	(segment
		(start 82.2706 -38.10889)
		(end 82.16011 -37.9984)
		(width 0.0889)
		(layer "In9.Cu")
		(net "LPC_CPU_LAD2")
	)
	(segment
		(start 81.915 -38.57625)
		(end 81.8261 -38.66515)
		(width 0.0889)
		(layer "In9.Cu")
		(net "LPC_CPU_LAD2")
	)
	(segment
		(start 80.899 -27.813)
		(end 80.899 -27.5336)
		(width 0.0889)
		(layer "In9.Cu")
		(net "LPC_CPU_LAD2")
	)
	(segment
		(start 81.0006 -27.9146)
		(end 80.899 -27.813)
		(width 0.0889)
		(layer "In9.Cu")
		(net "LPC_CPU_LAD2")
	)
	(segment
		(start 86.233 -40.100758)
		(end 86.010242 -39.878)
		(width 0.0889)
		(layer "In9.Cu")
		(net "LPC_CPU_LAD2")
	)
	(segment
		(start 80.5307 -30.002734)
		(end 80.899 -29.634434)
		(width 0.0889)
		(layer "In9.Cu")
		(net "LPC_CPU_LAD2")
	)
	(segment
		(start 80.000094 -37.5666)
		(end 79.838296 -37.404802)
		(width 0.0889)
		(layer "In9.Cu")
		(net "LPC_CPU_LAD2")
	)
	(segment
		(start 80.5307 -30.3403)
		(end 80.5307 -30.002734)
		(width 0.0889)
		(layer "In9.Cu")
		(net "LPC_CPU_LAD2")
	)
	(segment
		(start 81.451958 -36.0934)
		(end 81.451958 -35.5346)
		(width 0.0889)
		(layer "In9.Cu")
		(net "LPC_CPU_LAD2")
	)
	(segment
		(start 82.7151 -38.3032)
		(end 82.6262 -38.3921)
		(width 0.0889)
		(layer "In9.Cu")
		(net "LPC_CPU_LAD2")
	)
	(segment
		(start 81.788 -36.7792)
		(end 81.6864 -36.6776)
		(width 0.0889)
		(layer "In9.Cu")
		(net "LPC_CPU_LAD2")
	)
	(segment
		(start 80.645 -26.4414)
		(end 80.645 -26.145744)
		(width 0.0889)
		(layer "In9.Cu")
		(net "LPC_CPU_LAD2")
	)
	(segment
		(start 82.2706 -38.57625)
		(end 82.2706 -38.10889)
		(width 0.0889)
		(layer "In9.Cu")
		(net "LPC_CPU_LAD2")
	)
	(segment
		(start 82.9818 -38.3921)
		(end 82.8929 -38.3032)
		(width 0.0889)
		(layer "In9.Cu")
		(net "LPC_CPU_LAD2")
	)
	(segment
		(start 81.350358 -36.195)
		(end 81.451958 -36.0934)
		(width 0.0889)
		(layer "In9.Cu")
		(net "LPC_CPU_LAD2")
	)
	(segment
		(start 82.6262 -38.57625)
		(end 82.5373 -38.66515)
		(width 0.0889)
		(layer "In9.Cu")
		(net "LPC_CPU_LAD2")
	)
	(segment
		(start 81.915 -38.1)
		(end 81.915 -38.57625)
		(width 0.0889)
		(layer "In9.Cu")
		(net "LPC_CPU_LAD2")
	)
	(segment
		(start 86.010242 -39.878)
		(end 85.6996 -39.878)
		(width 0.0889)
		(layer "In9.Cu")
		(net "LPC_CPU_LAD2")
	)
	(segment
		(start 81.153 -25.0063)
		(end 81.0387 -24.892)
		(width 0.0889)
		(layer "In9.Cu")
		(net "LPC_CPU_LAD2")
	)
	(segment
		(start 80.645 -34.798)
		(end 80.783684 -34.659316)
		(width 0.0889)
		(layer "In9.Cu")
		(net "LPC_CPU_LAD2")
	)
	(segment
		(start 80.007968 -40.884094)
		(end 79.854298 -41.037764)
		(width 0.1143)
		(layer "F.Cu")
		(net "CPU_ERR_N0")
	)
	(segment
		(start 78.651608 -41.037764)
		(end 77.900784 -40.28694)
		(width 0.1143)
		(layer "F.Cu")
		(net "CPU_ERR_N0")
	)
	(segment
		(start 125.3998 -27.4828)
		(end 122.71121 -27.4828)
		(width 0.1143)
		(layer "F.Cu")
		(net "CPU_ERR_N0")
	)
	(segment
		(start 129.71145 -31.79445)
		(end 125.3998 -27.4828)
		(width 0.1143)
		(layer "F.Cu")
		(net "CPU_ERR_N0")
	)
	(segment
		(start 117.601746 -22.373336)
		(end 117.601746 -16.459454)
		(width 0.1143)
		(layer "F.Cu")
		(net "CPU_ERR_N0")
	)
	(segment
		(start 122.71121 -27.4828)
		(end 117.601746 -22.373336)
		(width 0.1143)
		(layer "F.Cu")
		(net "CPU_ERR_N0")
	)
	(segment
		(start 75.057 -43.307)
		(end 77.900784 -40.463216)
		(width 0.1143)
		(layer "F.Cu")
		(net "CPU_ERR_N0")
	)
	(segment
		(start 111.732568 -10.797032)
		(end 110.09249 -10.797032)
		(width 0.1143)
		(layer "F.Cu")
		(net "CPU_ERR_N0")
	)
	(segment
		(start 80.211168 -40.884094)
		(end 80.007968 -40.884094)
		(width 0.1143)
		(layer "F.Cu")
		(net "CPU_ERR_N0")
	)
	(segment
		(start 111.939324 -10.797032)
		(end 111.732568 -10.797032)
		(width 0.1143)
		(layer "F.Cu")
		(net "CPU_ERR_N0")
	)
	(segment
		(start 74.5998 -43.307)
		(end 75.057 -43.307)
		(width 0.1143)
		(layer "F.Cu")
		(net "CPU_ERR_N0")
	)
	(segment
		(start 77.900784 -40.463216)
		(end 77.900784 -40.28694)
		(width 0.1143)
		(layer "F.Cu")
		(net "CPU_ERR_N0")
	)
	(segment
		(start 79.854298 -41.037764)
		(end 78.651608 -41.037764)
		(width 0.1143)
		(layer "F.Cu")
		(net "CPU_ERR_N0")
	)
	(segment
		(start 110.09249 -10.797032)
		(end 108.295694 -9.000236)
		(width 0.1143)
		(layer "F.Cu")
		(net "CPU_ERR_N0")
	)
	(segment
		(start 117.601746 -16.459454)
		(end 111.939324 -10.797032)
		(width 0.1143)
		(layer "F.Cu")
		(net "CPU_ERR_N0")
	)
	(segment
		(start 108.295694 -9.000236)
		(end 108.295694 -8.397748)
		(width 0.1143)
		(layer "F.Cu")
		(net "CPU_ERR_N0")
	)
	(segment
		(start 132.1308 -31.79445)
		(end 129.71145 -31.79445)
		(width 0.1143)
		(layer "F.Cu")
		(net "CPU_ERR_N0")
	)
	(segment
		(start 108.295694 -8.397748)
		(end 107.848146 -7.9502)
		(width 0.1143)
		(layer "F.Cu")
		(net "CPU_ERR_N0")
	)
	(via
		(at 77.900784 -40.28694)
		(size 0.4318)
		(drill 0.2032)
		(layers "F.Cu" "B.Cu")
		(net "CPU_ERR_N0")
	)
	(via
		(at 111.732568 -10.797032)
		(size 0.7112)
		(drill 0.3556)
		(layers "F.Cu" "B.Cu")
		(net "CPU_ERR_N0")
	)
	(via
		(at 107.848146 -7.9502)
		(size 0.508)
		(drill 0.254)
		(layers "F.Cu" "B.Cu")
		(net "CPU_ERR_N0")
	)
	(segment
		(start 88.1888 -31.514796)
		(end 88.1888 -32.4866)
		(width 0.0889)
		(layer "In2.Cu")
		(net "CPU_ERR_N0")
	)
	(segment
		(start 106.987594 -11.488928)
		(end 105.106216 -13.370306)
		(width 0.0889)
		(layer "In2.Cu")
		(net "CPU_ERR_N0")
	)
	(segment
		(start 88.485726 -38.826694)
		(end 88.485726 -39.970964)
		(width 0.0889)
		(layer "In2.Cu")
		(net "CPU_ERR_N0")
	)
	(segment
		(start 85.422486 -40.68445)
		(end 85.132418 -40.974518)
		(width 0.0889)
		(layer "In2.Cu")
		(net "CPU_ERR_N0")
	)
	(segment
		(start 84.87791 -41.414446)
		(end 84.5312 -41.761156)
		(width 0.0889)
		(layer "In2.Cu")
		(net "CPU_ERR_N0")
	)
	(segment
		(start 82.148172 -41.904666)
		(end 79.51851 -41.904666)
		(width 0.0889)
		(layer "In2.Cu")
		(net "CPU_ERR_N0")
	)
	(segment
		(start 84.920582 -41.414446)
		(end 84.87791 -41.414446)
		(width 0.0889)
		(layer "In2.Cu")
		(net "CPU_ERR_N0")
	)
	(segment
		(start 85.132418 -41.20261)
		(end 84.920582 -41.414446)
		(width 0.0889)
		(layer "In2.Cu")
		(net "CPU_ERR_N0")
	)
	(segment
		(start 84.224114 -42.14495)
		(end 82.698844 -42.14495)
		(width 0.0889)
		(layer "In2.Cu")
		(net "CPU_ERR_N0")
	)
	(segment
		(start 88.662764 -32.960564)
		(end 88.662764 -35.708844)
		(width 0.0889)
		(layer "In2.Cu")
		(net "CPU_ERR_N0")
	)
	(segment
		(start 88.1888 -32.4866)
		(end 88.662764 -32.960564)
		(width 0.0889)
		(layer "In2.Cu")
		(net "CPU_ERR_N0")
	)
	(segment
		(start 106.987594 -8.849106)
		(end 106.987594 -11.488928)
		(width 0.0889)
		(layer "In2.Cu")
		(net "CPU_ERR_N0")
	)
	(segment
		(start 88.662764 -35.708844)
		(end 89.133172 -36.179252)
		(width 0.0889)
		(layer "In2.Cu")
		(net "CPU_ERR_N0")
	)
	(segment
		(start 107.848146 -7.9502)
		(end 107.848146 -7.988554)
		(width 0.0889)
		(layer "In2.Cu")
		(net "CPU_ERR_N0")
	)
	(segment
		(start 86.614 -15.9258)
		(end 85.14715 -17.39265)
		(width 0.0889)
		(layer "In2.Cu")
		(net "CPU_ERR_N0")
	)
	(segment
		(start 87.122 -26.9494)
		(end 88.39835 -28.22575)
		(width 0.0889)
		(layer "In2.Cu")
		(net "CPU_ERR_N0")
	)
	(segment
		(start 85.671914 -40.68445)
		(end 85.422486 -40.68445)
		(width 0.0889)
		(layer "In2.Cu")
		(net "CPU_ERR_N0")
	)
	(segment
		(start 85.14715 -20.93595)
		(end 87.122 -22.9108)
		(width 0.0889)
		(layer "In2.Cu")
		(net "CPU_ERR_N0")
	)
	(segment
		(start 89.133172 -36.179252)
		(end 89.133172 -38.179248)
		(width 0.0889)
		(layer "In2.Cu")
		(net "CPU_ERR_N0")
	)
	(segment
		(start 90.470228 -15.9258)
		(end 86.614 -15.9258)
		(width 0.0889)
		(layer "In2.Cu")
		(net "CPU_ERR_N0")
	)
	(segment
		(start 79.51851 -41.904666)
		(end 77.900784 -40.28694)
		(width 0.0889)
		(layer "In2.Cu")
		(net "CPU_ERR_N0")
	)
	(segment
		(start 85.14715 -17.39265)
		(end 85.14715 -20.93595)
		(width 0.0889)
		(layer "In2.Cu")
		(net "CPU_ERR_N0")
	)
	(segment
		(start 85.944964 -40.4114)
		(end 85.671914 -40.68445)
		(width 0.0889)
		(layer "In2.Cu")
		(net "CPU_ERR_N0")
	)
	(segment
		(start 82.45348 -41.899586)
		(end 82.153252 -41.899586)
		(width 0.0889)
		(layer "In2.Cu")
		(net "CPU_ERR_N0")
	)
	(segment
		(start 107.848146 -7.988554)
		(end 106.987594 -8.849106)
		(width 0.0889)
		(layer "In2.Cu")
		(net "CPU_ERR_N0")
	)
	(segment
		(start 88.39835 -28.22575)
		(end 88.39835 -31.305246)
		(width 0.0889)
		(layer "In2.Cu")
		(net "CPU_ERR_N0")
	)
	(segment
		(start 105.106216 -13.370306)
		(end 93.025722 -13.370306)
		(width 0.0889)
		(layer "In2.Cu")
		(net "CPU_ERR_N0")
	)
	(segment
		(start 85.132418 -40.974518)
		(end 85.132418 -41.20261)
		(width 0.0889)
		(layer "In2.Cu")
		(net "CPU_ERR_N0")
	)
	(segment
		(start 84.5312 -41.837864)
		(end 84.224114 -42.14495)
		(width 0.0889)
		(layer "In2.Cu")
		(net "CPU_ERR_N0")
	)
	(segment
		(start 93.025722 -13.370306)
		(end 90.470228 -15.9258)
		(width 0.0889)
		(layer "In2.Cu")
		(net "CPU_ERR_N0")
	)
	(segment
		(start 82.698844 -42.14495)
		(end 82.45348 -41.899586)
		(width 0.0889)
		(layer "In2.Cu")
		(net "CPU_ERR_N0")
	)
	(segment
		(start 82.153252 -41.899586)
		(end 82.148172 -41.904666)
		(width 0.0889)
		(layer "In2.Cu")
		(net "CPU_ERR_N0")
	)
	(segment
		(start 88.39835 -31.305246)
		(end 88.1888 -31.514796)
		(width 0.0889)
		(layer "In2.Cu")
		(net "CPU_ERR_N0")
	)
	(segment
		(start 88.04529 -40.4114)
		(end 85.944964 -40.4114)
		(width 0.0889)
		(layer "In2.Cu")
		(net "CPU_ERR_N0")
	)
	(segment
		(start 84.5312 -41.761156)
		(end 84.5312 -41.837864)
		(width 0.0889)
		(layer "In2.Cu")
		(net "CPU_ERR_N0")
	)
	(segment
		(start 89.133172 -38.179248)
		(end 88.485726 -38.826694)
		(width 0.0889)
		(layer "In2.Cu")
		(net "CPU_ERR_N0")
	)
	(segment
		(start 88.485726 -39.970964)
		(end 88.04529 -40.4114)
		(width 0.0889)
		(layer "In2.Cu")
		(net "CPU_ERR_N0")
	)
	(segment
		(start 87.122 -22.9108)
		(end 87.122 -26.9494)
		(width 0.0889)
		(layer "In2.Cu")
		(net "CPU_ERR_N0")
	)
	(segment
		(start 22.5806 -62.6618)
		(end 22.062948 -62.144148)
		(width 0.2032)
		(layer "F.Cu")
		(net "VR_PVNN_PROG2")
	)
	(segment
		(start 22.062948 -62.144148)
		(end 22.062948 -61.292994)
		(width 0.2032)
		(layer "F.Cu")
		(net "VR_PVNN_PROG2")
	)
	(via
		(at 22.352 -63.4238)
		(size 0.7112)
		(drill 0.3556)
		(layers "F.Cu" "B.Cu")
		(net "VR_PVNN_PROG2")
	)
	(via
		(at 22.5806 -62.6618)
		(size 0.508)
		(drill 0.254)
		(layers "F.Cu" "B.Cu")
		(net "VR_PVNN_PROG2")
	)
	(segment
		(start 22.352 -63.4238)
		(end 22.352 -62.8904)
		(width 0.2032)
		(layer "B.Cu")
		(net "VR_PVNN_PROG2")
	)
	(segment
		(start 22.352 -64.3382)
		(end 22.352 -63.4238)
		(width 0.2032)
		(layer "B.Cu")
		(net "VR_PVNN_PROG2")
	)
	(segment
		(start 22.352 -62.8904)
		(end 22.5806 -62.6618)
		(width 0.2032)
		(layer "B.Cu")
		(net "VR_PVNN_PROG2")
	)
	(segment
		(start 152.1968 -69.640958)
		(end 152.1968 -67.6402)
		(width 0.2413)
		(layer "F.Cu")
		(net "M_A_BS0")
	)
	(segment
		(start 106.296714 -50.8254)
		(end 105.8926 -50.8254)
		(width 0.1016)
		(layer "F.Cu")
		(net "M_A_BS0")
	)
	(segment
		(start 152.349962 -69.79412)
		(end 152.1968 -69.640958)
		(width 0.2413)
		(layer "F.Cu")
		(net "M_A_BS0")
	)
	(segment
		(start 152.349962 -70.806564)
		(end 152.349962 -69.79412)
		(width 0.2413)
		(layer "F.Cu")
		(net "M_A_BS0")
	)
	(segment
		(start 152.1968 -67.6402)
		(end 151.9682 -67.4116)
		(width 0.2413)
		(layer "F.Cu")
		(net "M_A_BS0")
	)
	(segment
		(start 106.571288 -51.099974)
		(end 106.296714 -50.8254)
		(width 0.1016)
		(layer "F.Cu")
		(net "M_A_BS0")
	)
	(via
		(at 151.9682 -67.4116)
		(size 0.4318)
		(drill 0.2032)
		(layers "F.Cu" "B.Cu")
		(net "M_A_BS0")
	)
	(via
		(at 105.8926 -50.8254)
		(size 0.4318)
		(drill 0.2032)
		(layers "F.Cu" "B.Cu")
		(net "M_A_BS0")
	)
	(segment
		(start 151.9682 -67.351402)
		(end 151.9682 -67.4116)
		(width 0.2413)
		(layer "B.Cu")
		(net "M_A_BS0")
	)
	(segment
		(start 151.501348 -66.88455)
		(end 151.9682 -67.351402)
		(width 0.2413)
		(layer "B.Cu")
		(net "M_A_BS0")
	)
	(segment
		(start 152.349962 -64.690244)
		(end 151.501348 -65.538858)
		(width 0.2413)
		(layer "B.Cu")
		(net "M_A_BS0")
	)
	(segment
		(start 152.349962 -62.599824)
		(end 152.349962 -64.690244)
		(width 0.2413)
		(layer "B.Cu")
		(net "M_A_BS0")
	)
	(segment
		(start 151.501348 -65.538858)
		(end 151.501348 -66.88455)
		(width 0.2413)
		(layer "B.Cu")
		(net "M_A_BS0")
	)
	(segment
		(start 151.765 -63.373)
		(end 150.9268 -62.5348)
		(width 0.1905)
		(layer "In9.Cu")
		(net "M_A_BS0")
	)
	(segment
		(start 105.8926 -50.8254)
		(end 105.613962 -50.8254)
		(width 0.1016)
		(layer "In9.Cu")
		(net "M_A_BS0")
	)
	(segment
		(start 151.9682 -67.4116)
		(end 151.7142 -67.4116)
		(width 0.1905)
		(layer "In9.Cu")
		(net "M_A_BS0")
	)
	(segment
		(start 106.1974 -53.6194)
		(end 106.1974 -53.8734)
		(width 0.1016)
		(layer "In9.Cu")
		(net "M_A_BS0")
	)
	(segment
		(start 117.46484 -58.0136)
		(end 116.97589 -58.0136)
		(width 0.1905)
		(layer "In9.Cu")
		(net "M_A_BS0")
	)
	(segment
		(start 114.55654 -57.74055)
		(end 114.28349 -58.0136)
		(width 0.1905)
		(layer "In9.Cu")
		(net "M_A_BS0")
	)
	(segment
		(start 105.3338 -53.086)
		(end 105.5878 -53.34)
		(width 0.1016)
		(layer "In9.Cu")
		(net "M_A_BS0")
	)
	(segment
		(start 117.73789 -57.74055)
		(end 117.46484 -58.0136)
		(width 0.1905)
		(layer "In9.Cu")
		(net "M_A_BS0")
	)
	(segment
		(start 116.97589 -58.0136)
		(end 116.70284 -57.74055)
		(width 0.1905)
		(layer "In9.Cu")
		(net "M_A_BS0")
	)
	(segment
		(start 138.75131 -58.5216)
		(end 137.82929 -58.5216)
		(width 0.1905)
		(layer "In9.Cu")
		(net "M_A_BS0")
	)
	(segment
		(start 105.918 -53.34)
		(end 106.1974 -53.6194)
		(width 0.1016)
		(layer "In9.Cu")
		(net "M_A_BS0")
	)
	(segment
		(start 115.31854 -58.0136)
		(end 115.04549 -57.74055)
		(width 0.1905)
		(layer "In9.Cu")
		(net "M_A_BS0")
	)
	(segment
		(start 116.08054 -57.74055)
		(end 115.80749 -58.0136)
		(width 0.1905)
		(layer "In9.Cu")
		(net "M_A_BS0")
	)
	(segment
		(start 111.99749 -57.74055)
		(end 111.50854 -57.74055)
		(width 0.1905)
		(layer "In9.Cu")
		(net "M_A_BS0")
	)
	(segment
		(start 106.1974 -53.8734)
		(end 107.0864 -54.7624)
		(width 0.1016)
		(layer "In9.Cu")
		(net "M_A_BS0")
	)
	(segment
		(start 108.94949 -57.74055)
		(end 108.46054 -57.74055)
		(width 0.1905)
		(layer "In9.Cu")
		(net "M_A_BS0")
	)
	(segment
		(start 151.526748 -67.224148)
		(end 151.526748 -65.921128)
		(width 0.1905)
		(layer "In9.Cu")
		(net "M_A_BS0")
	)
	(segment
		(start 109.22254 -58.0136)
		(end 108.94949 -57.74055)
		(width 0.1905)
		(layer "In9.Cu")
		(net "M_A_BS0")
	)
	(segment
		(start 109.71149 -58.0136)
		(end 109.22254 -58.0136)
		(width 0.1905)
		(layer "In9.Cu")
		(net "M_A_BS0")
	)
	(segment
		(start 133.369304 -58.5216)
		(end 132.664454 -57.81675)
		(width 0.1905)
		(layer "In9.Cu")
		(net "M_A_BS0")
	)
	(segment
		(start 138.96086 -58.31205)
		(end 138.75131 -58.5216)
		(width 0.1905)
		(layer "In9.Cu")
		(net "M_A_BS0")
	)
	(segment
		(start 121.62155 -57.74055)
		(end 117.73789 -57.74055)
		(width 0.1905)
		(layer "In9.Cu")
		(net "M_A_BS0")
	)
	(segment
		(start 140.4366 -58.5216)
		(end 139.6746 -58.5216)
		(width 0.1905)
		(layer "In9.Cu")
		(net "M_A_BS0")
	)
	(segment
		(start 150.4696 -62.5348)
		(end 150.2537 -62.3189)
		(width 0.1905)
		(layer "In9.Cu")
		(net "M_A_BS0")
	)
	(segment
		(start 107.0864 -54.7624)
		(end 107.0864 -57.6326)
		(width 0.1016)
		(layer "In9.Cu")
		(net "M_A_BS0")
	)
	(segment
		(start 136.787636 -58.148728)
		(end 136.41451 -58.5216)
		(width 0.1905)
		(layer "In9.Cu")
		(net "M_A_BS0")
	)
	(segment
		(start 105.385362 -51.054)
		(end 105.385362 -51.435)
		(width 0.1016)
		(layer "In9.Cu")
		(net "M_A_BS0")
	)
	(segment
		(start 108.18749 -58.0136)
		(end 107.4674 -58.0136)
		(width 0.1905)
		(layer "In9.Cu")
		(net "M_A_BS0")
	)
	(segment
		(start 137.456418 -58.148728)
		(end 136.787636 -58.148728)
		(width 0.1905)
		(layer "In9.Cu")
		(net "M_A_BS0")
	)
	(segment
		(start 150.2537 -61.8617)
		(end 148.336 -59.944)
		(width 0.1905)
		(layer "In9.Cu")
		(net "M_A_BS0")
	)
	(segment
		(start 148.336 -59.944)
		(end 146.2278 -59.944)
		(width 0.1905)
		(layer "In9.Cu")
		(net "M_A_BS0")
	)
	(segment
		(start 109.98454 -57.74055)
		(end 109.71149 -58.0136)
		(width 0.1905)
		(layer "In9.Cu")
		(net "M_A_BS0")
	)
	(segment
		(start 105.385362 -51.435)
		(end 105.664 -51.713638)
		(width 0.1016)
		(layer "In9.Cu")
		(net "M_A_BS0")
	)
	(segment
		(start 110.47349 -57.74055)
		(end 109.98454 -57.74055)
		(width 0.1905)
		(layer "In9.Cu")
		(net "M_A_BS0")
	)
	(segment
		(start 150.9268 -62.5348)
		(end 150.4696 -62.5348)
		(width 0.1905)
		(layer "In9.Cu")
		(net "M_A_BS0")
	)
	(segment
		(start 145.158714 -58.874914)
		(end 142.077948 -58.874914)
		(width 0.1905)
		(layer "In9.Cu")
		(net "M_A_BS0")
	)
	(segment
		(start 112.75949 -58.0136)
		(end 112.27054 -58.0136)
		(width 0.1905)
		(layer "In9.Cu")
		(net "M_A_BS0")
	)
	(segment
		(start 151.526748 -65.921128)
		(end 151.765 -65.682876)
		(width 0.1905)
		(layer "In9.Cu")
		(net "M_A_BS0")
	)
	(segment
		(start 105.613962 -50.8254)
		(end 105.385362 -51.054)
		(width 0.1016)
		(layer "In9.Cu")
		(net "M_A_BS0")
	)
	(segment
		(start 129.55143 -57.81675)
		(end 128.94818 -58.42)
		(width 0.1905)
		(layer "In9.Cu")
		(net "M_A_BS0")
	)
	(segment
		(start 115.04549 -57.74055)
		(end 114.55654 -57.74055)
		(width 0.1905)
		(layer "In9.Cu")
		(net "M_A_BS0")
	)
	(segment
		(start 108.46054 -57.74055)
		(end 108.18749 -58.0136)
		(width 0.1905)
		(layer "In9.Cu")
		(net "M_A_BS0")
	)
	(segment
		(start 122.301 -58.42)
		(end 121.62155 -57.74055)
		(width 0.1905)
		(layer "In9.Cu")
		(net "M_A_BS0")
	)
	(segment
		(start 132.664454 -57.81675)
		(end 129.55143 -57.81675)
		(width 0.1905)
		(layer "In9.Cu")
		(net "M_A_BS0")
	)
	(segment
		(start 128.94818 -58.42)
		(end 122.301 -58.42)
		(width 0.1905)
		(layer "In9.Cu")
		(net "M_A_BS0")
	)
	(segment
		(start 141.515084 -58.31205)
		(end 140.64615 -58.31205)
		(width 0.1905)
		(layer "In9.Cu")
		(net "M_A_BS0")
	)
	(segment
		(start 116.70284 -57.74055)
		(end 116.08054 -57.74055)
		(width 0.1905)
		(layer "In9.Cu")
		(net "M_A_BS0")
	)
	(segment
		(start 105.3338 -52.2986)
		(end 105.3338 -53.086)
		(width 0.1016)
		(layer "In9.Cu")
		(net "M_A_BS0")
	)
	(segment
		(start 151.765 -65.682876)
		(end 151.765 -63.373)
		(width 0.1905)
		(layer "In9.Cu")
		(net "M_A_BS0")
	)
	(segment
		(start 139.46505 -58.31205)
		(end 138.96086 -58.31205)
		(width 0.1905)
		(layer "In9.Cu")
		(net "M_A_BS0")
	)
	(segment
		(start 110.74654 -58.0136)
		(end 110.47349 -57.74055)
		(width 0.1905)
		(layer "In9.Cu")
		(net "M_A_BS0")
	)
	(segment
		(start 140.64615 -58.31205)
		(end 140.4366 -58.5216)
		(width 0.1905)
		(layer "In9.Cu")
		(net "M_A_BS0")
	)
	(segment
		(start 115.80749 -58.0136)
		(end 115.31854 -58.0136)
		(width 0.1905)
		(layer "In9.Cu")
		(net "M_A_BS0")
	)
	(segment
		(start 142.077948 -58.874914)
		(end 141.515084 -58.31205)
		(width 0.1905)
		(layer "In9.Cu")
		(net "M_A_BS0")
	)
	(segment
		(start 113.03254 -57.74055)
		(end 112.75949 -58.0136)
		(width 0.1905)
		(layer "In9.Cu")
		(net "M_A_BS0")
	)
	(segment
		(start 114.28349 -58.0136)
		(end 113.79454 -58.0136)
		(width 0.1905)
		(layer "In9.Cu")
		(net "M_A_BS0")
	)
	(segment
		(start 112.27054 -58.0136)
		(end 111.99749 -57.74055)
		(width 0.1905)
		(layer "In9.Cu")
		(net "M_A_BS0")
	)
	(segment
		(start 139.6746 -58.5216)
		(end 139.46505 -58.31205)
		(width 0.1905)
		(layer "In9.Cu")
		(net "M_A_BS0")
	)
	(segment
		(start 113.52149 -57.74055)
		(end 113.03254 -57.74055)
		(width 0.1905)
		(layer "In9.Cu")
		(net "M_A_BS0")
	)
	(segment
		(start 150.2537 -62.3189)
		(end 150.2537 -61.8617)
		(width 0.1905)
		(layer "In9.Cu")
		(net "M_A_BS0")
	)
	(segment
		(start 136.41451 -58.5216)
		(end 133.369304 -58.5216)
		(width 0.1905)
		(layer "In9.Cu")
		(net "M_A_BS0")
	)
	(segment
		(start 105.664 -51.9684)
		(end 105.3338 -52.2986)
		(width 0.1016)
		(layer "In9.Cu")
		(net "M_A_BS0")
	)
	(segment
		(start 137.82929 -58.5216)
		(end 137.456418 -58.148728)
		(width 0.1905)
		(layer "In9.Cu")
		(net "M_A_BS0")
	)
	(segment
		(start 113.79454 -58.0136)
		(end 113.52149 -57.74055)
		(width 0.1905)
		(layer "In9.Cu")
		(net "M_A_BS0")
	)
	(segment
		(start 146.2278 -59.944)
		(end 145.158714 -58.874914)
		(width 0.1905)
		(layer "In9.Cu")
		(net "M_A_BS0")
	)
	(segment
		(start 111.50854 -57.74055)
		(end 111.23549 -58.0136)
		(width 0.1905)
		(layer "In9.Cu")
		(net "M_A_BS0")
	)
	(segment
		(start 107.0864 -57.6326)
		(end 107.4674 -58.0136)
		(width 0.1016)
		(layer "In9.Cu")
		(net "M_A_BS0")
	)
	(segment
		(start 111.23549 -58.0136)
		(end 110.74654 -58.0136)
		(width 0.1905)
		(layer "In9.Cu")
		(net "M_A_BS0")
	)
	(segment
		(start 105.664 -51.713638)
		(end 105.664 -51.9684)
		(width 0.1016)
		(layer "In9.Cu")
		(net "M_A_BS0")
	)
	(segment
		(start 151.7142 -67.4116)
		(end 151.526748 -67.224148)
		(width 0.1905)
		(layer "In9.Cu")
		(net "M_A_BS0")
	)
	(segment
		(start 105.5878 -53.34)
		(end 105.918 -53.34)
		(width 0.1016)
		(layer "In9.Cu")
		(net "M_A_BS0")
	)
	(segment
		(start 71.944484 -40.6654)
		(end 73.025 -40.6654)
		(width 0.1143)
		(layer "F.Cu")
		(net "RTC_X1PAD")
	)
	(segment
		(start 78.584806 -39.69639)
		(end 77.197712 -39.69639)
		(width 0.1143)
		(layer "F.Cu")
		(net "RTC_X1PAD")
	)
	(segment
		(start 73.025 -40.6654)
		(end 73.406 -40.6654)
		(width 0.1143)
		(layer "F.Cu")
		(net "RTC_X1PAD")
	)
	(segment
		(start 79.901288 -39.876984)
		(end 78.7654 -39.876984)
		(width 0.1143)
		(layer "F.Cu")
		(net "RTC_X1PAD")
	)
	(segment
		(start 79.960978 -39.817294)
		(end 79.901288 -39.876984)
		(width 0.1143)
		(layer "F.Cu")
		(net "RTC_X1PAD")
	)
	(segment
		(start 76.635102 -40.259)
		(end 77.028294 -39.865808)
		(width 0.1143)
		(layer "F.Cu")
		(net "RTC_X1PAD")
	)
	(segment
		(start 80.096868 -39.817294)
		(end 79.960978 -39.817294)
		(width 0.1143)
		(layer "F.Cu")
		(net "RTC_X1PAD")
	)
	(segment
		(start 74.4982 -40.6908)
		(end 74.8284 -40.6908)
		(width 0.1143)
		(layer "F.Cu")
		(net "RTC_X1PAD")
	)
	(segment
		(start 71.374 -41.235884)
		(end 71.944484 -40.6654)
		(width 0.1143)
		(layer "F.Cu")
		(net "RTC_X1PAD")
	)
	(segment
		(start 77.197712 -39.69639)
		(end 77.028294 -39.865808)
		(width 0.1143)
		(layer "F.Cu")
		(net "RTC_X1PAD")
	)
	(segment
		(start 73.4314 -40.6908)
		(end 74.4982 -40.6908)
		(width 0.1143)
		(layer "F.Cu")
		(net "RTC_X1PAD")
	)
	(segment
		(start 78.7654 -39.876984)
		(end 78.584806 -39.69639)
		(width 0.1143)
		(layer "F.Cu")
		(net "RTC_X1PAD")
	)
	(segment
		(start 75.2602 -40.259)
		(end 76.635102 -40.259)
		(width 0.1143)
		(layer "F.Cu")
		(net "RTC_X1PAD")
	)
	(segment
		(start 74.8284 -40.6908)
		(end 75.2602 -40.259)
		(width 0.1143)
		(layer "F.Cu")
		(net "RTC_X1PAD")
	)
	(segment
		(start 73.406 -40.6654)
		(end 73.4314 -40.6908)
		(width 0.1143)
		(layer "F.Cu")
		(net "RTC_X1PAD")
	)
	(via
		(at 77.028294 -39.865808)
		(size 0.7112)
		(drill 0.3556)
		(layers "F.Cu" "B.Cu")
		(net "RTC_X1PAD")
	)
	(segment
		(start 25.25268 -64.2112)
		(end 25.25268 -64.11468)
		(width 0.4572)
		(layer "F.Cu")
		(net "VR_PVNN_GH")
	)
	(segment
		(start 22.863048 -61.766196)
		(end 22.863048 -61.292994)
		(width 0.2032)
		(layer "F.Cu")
		(net "VR_PVNN_GH")
	)
	(segment
		(start 25.25268 -64.11468)
		(end 24.2824 -63.1444)
		(width 0.4572)
		(layer "F.Cu")
		(net "VR_PVNN_GH")
	)
	(segment
		(start 23.8252 -62.5856)
		(end 23.682452 -62.5856)
		(width 0.2032)
		(layer "F.Cu")
		(net "VR_PVNN_GH")
	)
	(segment
		(start 24.2824 -63.1444)
		(end 24.2824 -63.0428)
		(width 0.4572)
		(layer "F.Cu")
		(net "VR_PVNN_GH")
	)
	(segment
		(start 24.2824 -63.0428)
		(end 23.8252 -62.5856)
		(width 0.4572)
		(layer "F.Cu")
		(net "VR_PVNN_GH")
	)
	(segment
		(start 23.682452 -62.5856)
		(end 22.863048 -61.766196)
		(width 0.2032)
		(layer "F.Cu")
		(net "VR_PVNN_GH")
	)
	(via
		(at 23.8252 -62.5856)
		(size 0.7112)
		(drill 0.3556)
		(layers "F.Cu" "B.Cu")
		(net "VR_PVNN_GH")
	)
	(segment
		(start 185.950098 -70.806564)
		(end 185.950098 -69.999098)
		(width 0.1778)
		(layer "F.Cu")
		(net "M_A_DQ7")
	)
	(segment
		(start 107.68203 -41.966134)
		(end 107.742228 -41.966134)
		(width 0.1016)
		(layer "F.Cu")
		(net "M_A_DQ7")
	)
	(segment
		(start 185.950098 -69.999098)
		(end 185.5216 -69.5706)
		(width 0.1778)
		(layer "F.Cu")
		(net "M_A_DQ7")
	)
	(segment
		(start 185.5216 -69.5706)
		(end 185.5216 -69.3039)
		(width 0.1778)
		(layer "F.Cu")
		(net "M_A_DQ7")
	)
	(segment
		(start 107.742228 -41.966134)
		(end 108.052108 -41.656254)
		(width 0.1016)
		(layer "F.Cu")
		(net "M_A_DQ7")
	)
	(via
		(at 107.68203 -41.966134)
		(size 0.4318)
		(drill 0.2032)
		(layers "F.Cu" "B.Cu")
		(net "M_A_DQ7")
	)
	(via
		(at 185.5216 -69.3039)
		(size 0.4318)
		(drill 0.2032)
		(layers "F.Cu" "B.Cu")
		(net "M_A_DQ7")
	)
	(segment
		(start 185.050176 -69.820028)
		(end 185.505598 -69.364606)
		(width 0.1778)
		(layer "B.Cu")
		(net "M_A_DQ7")
	)
	(segment
		(start 185.505598 -69.364606)
		(end 185.505598 -69.319902)
		(width 0.1778)
		(layer "B.Cu")
		(net "M_A_DQ7")
	)
	(segment
		(start 185.505598 -69.319902)
		(end 185.5216 -69.3039)
		(width 0.1778)
		(layer "B.Cu")
		(net "M_A_DQ7")
	)
	(segment
		(start 185.050176 -70.79996)
		(end 185.050176 -69.820028)
		(width 0.1778)
		(layer "B.Cu")
		(net "M_A_DQ7")
	)
	(segment
		(start 173.256956 -60.557664)
		(end 173.256956 -60.773056)
		(width 0.1524)
		(layer "In7.Cu")
		(net "M_A_DQ7")
	)
	(segment
		(start 168.716452 -56.042052)
		(end 168.931082 -56.256682)
		(width 0.1524)
		(layer "In7.Cu")
		(net "M_A_DQ7")
	)
	(segment
		(start 168.931082 -56.472582)
		(end 168.748202 -56.656224)
		(width 0.1524)
		(layer "In7.Cu")
		(net "M_A_DQ7")
	)
	(segment
		(start 170.238166 -57.754012)
		(end 170.453304 -57.754012)
		(width 0.1524)
		(layer "In7.Cu")
		(net "M_A_DQ7")
	)
	(segment
		(start 173.277022 -61.400436)
		(end 173.492414 -61.400436)
		(width 0.1524)
		(layer "In7.Cu")
		(net "M_A_DQ7")
	)
	(segment
		(start 108.5723 -41.966134)
		(end 107.68203 -41.966134)
		(width 0.1016)
		(layer "In7.Cu")
		(net "M_A_DQ7")
	)
	(segment
		(start 173.061122 -61.184536)
		(end 173.277022 -61.400436)
		(width 0.1524)
		(layer "In7.Cu")
		(net "M_A_DQ7")
	)
	(segment
		(start 173.688502 -61.204348)
		(end 173.90364 -61.204348)
		(width 0.1524)
		(layer "In7.Cu")
		(net "M_A_DQ7")
	)
	(segment
		(start 170.453304 -57.754012)
		(end 170.669204 -57.969912)
		(width 0.1524)
		(layer "In7.Cu")
		(net "M_A_DQ7")
	)
	(segment
		(start 169.826686 -57.9501)
		(end 170.042078 -57.9501)
		(width 0.1524)
		(layer "In7.Cu")
		(net "M_A_DQ7")
	)
	(segment
		(start 170.042078 -57.9501)
		(end 170.238166 -57.754012)
		(width 0.1524)
		(layer "In7.Cu")
		(net "M_A_DQ7")
	)
	(segment
		(start 170.904662 -58.812684)
		(end 171.10075 -58.616596)
		(width 0.1524)
		(layer "In7.Cu")
		(net "M_A_DQ7")
	)
	(segment
		(start 168.748202 -56.656224)
		(end 168.748202 -56.871616)
		(width 0.1524)
		(layer "In7.Cu")
		(net "M_A_DQ7")
	)
	(segment
		(start 172.394372 -59.910472)
		(end 172.198538 -60.10656)
		(width 0.1524)
		(layer "In7.Cu")
		(net "M_A_DQ7")
	)
	(segment
		(start 168.500552 -56.042052)
		(end 168.716452 -56.042052)
		(width 0.1524)
		(layer "In7.Cu")
		(net "M_A_DQ7")
	)
	(segment
		(start 186.58078 -68.761864)
		(end 186.038744 -69.3039)
		(width 0.1524)
		(layer "In7.Cu")
		(net "M_A_DQ7")
	)
	(segment
		(start 168.931082 -56.256682)
		(end 168.931082 -56.472582)
		(width 0.1524)
		(layer "In7.Cu")
		(net "M_A_DQ7")
	)
	(segment
		(start 172.394372 -59.69508)
		(end 172.394372 -59.910472)
		(width 0.1524)
		(layer "In7.Cu")
		(net "M_A_DQ7")
	)
	(segment
		(start 170.669204 -58.185304)
		(end 170.47337 -58.381392)
		(width 0.1524)
		(layer "In7.Cu")
		(net "M_A_DQ7")
	)
	(segment
		(start 171.531788 -59.047888)
		(end 171.335954 -59.243976)
		(width 0.1524)
		(layer "In7.Cu")
		(net "M_A_DQ7")
	)
	(segment
		(start 172.198538 -60.321952)
		(end 172.414438 -60.537852)
		(width 0.1524)
		(layer "In7.Cu")
		(net "M_A_DQ7")
	)
	(segment
		(start 159.97809 -50.8508)
		(end 164.5412 -55.41391)
		(width 0.1524)
		(layer "In7.Cu")
		(net "M_A_DQ7")
	)
	(segment
		(start 169.179494 -57.087516)
		(end 169.375582 -56.891428)
		(width 0.1524)
		(layer "In7.Cu")
		(net "M_A_DQ7")
	)
	(segment
		(start 171.767246 -59.675268)
		(end 171.963334 -59.47918)
		(width 0.1524)
		(layer "In7.Cu")
		(net "M_A_DQ7")
	)
	(segment
		(start 175.2346 -65.8368)
		(end 184.15 -65.8368)
		(width 0.1524)
		(layer "In7.Cu")
		(net "M_A_DQ7")
	)
	(segment
		(start 172.414438 -60.537852)
		(end 172.62983 -60.537852)
		(width 0.1524)
		(layer "In7.Cu")
		(net "M_A_DQ7")
	)
	(segment
		(start 168.964102 -57.087516)
		(end 169.179494 -57.087516)
		(width 0.1524)
		(layer "In7.Cu")
		(net "M_A_DQ7")
	)
	(segment
		(start 169.375582 -56.891428)
		(end 169.59072 -56.891428)
		(width 0.1524)
		(layer "In7.Cu")
		(net "M_A_DQ7")
	)
	(segment
		(start 167.290496 -55.41391)
		(end 168.101518 -56.224932)
		(width 0.1524)
		(layer "In7.Cu")
		(net "M_A_DQ7")
	)
	(segment
		(start 169.80662 -57.32272)
		(end 169.610786 -57.518808)
		(width 0.1524)
		(layer "In7.Cu")
		(net "M_A_DQ7")
	)
	(segment
		(start 173.90364 -61.204348)
		(end 174.11954 -61.420248)
		(width 0.1524)
		(layer "In7.Cu")
		(net "M_A_DQ7")
	)
	(segment
		(start 171.963334 -59.47918)
		(end 172.178472 -59.47918)
		(width 0.1524)
		(layer "In7.Cu")
		(net "M_A_DQ7")
	)
	(segment
		(start 174.11954 -61.420248)
		(end 174.11954 -61.63564)
		(width 0.1524)
		(layer "In7.Cu")
		(net "M_A_DQ7")
	)
	(segment
		(start 172.62983 -60.537852)
		(end 172.825918 -60.341764)
		(width 0.1524)
		(layer "In7.Cu")
		(net "M_A_DQ7")
	)
	(segment
		(start 109.121956 -42.340784)
		(end 108.9152 -42.1386)
		(width 0.1016)
		(layer "In7.Cu")
		(net "M_A_DQ7")
	)
	(segment
		(start 164.5412 -55.41391)
		(end 167.290496 -55.41391)
		(width 0.1524)
		(layer "In7.Cu")
		(net "M_A_DQ7")
	)
	(segment
		(start 110.13948 -43.434)
		(end 111.887 -43.434)
		(width 0.1524)
		(layer "In7.Cu")
		(net "M_A_DQ7")
	)
	(segment
		(start 111.887 -43.434)
		(end 112.395 -43.942)
		(width 0.1524)
		(layer "In7.Cu")
		(net "M_A_DQ7")
	)
	(segment
		(start 168.101518 -56.224932)
		(end 168.31691 -56.224932)
		(width 0.1524)
		(layer "In7.Cu")
		(net "M_A_DQ7")
	)
	(segment
		(start 171.335954 -59.243976)
		(end 171.335954 -59.459368)
		(width 0.1524)
		(layer "In7.Cu")
		(net "M_A_DQ7")
	)
	(segment
		(start 170.669204 -57.969912)
		(end 170.669204 -58.185304)
		(width 0.1524)
		(layer "In7.Cu")
		(net "M_A_DQ7")
	)
	(segment
		(start 169.610786 -57.518808)
		(end 169.610786 -57.7342)
		(width 0.1524)
		(layer "In7.Cu")
		(net "M_A_DQ7")
	)
	(segment
		(start 171.531788 -58.832496)
		(end 171.531788 -59.047888)
		(width 0.1524)
		(layer "In7.Cu")
		(net "M_A_DQ7")
	)
	(segment
		(start 173.492414 -61.400436)
		(end 173.688502 -61.204348)
		(width 0.1524)
		(layer "In7.Cu")
		(net "M_A_DQ7")
	)
	(segment
		(start 171.10075 -58.616596)
		(end 171.315888 -58.616596)
		(width 0.1524)
		(layer "In7.Cu")
		(net "M_A_DQ7")
	)
	(segment
		(start 170.47337 -58.596784)
		(end 170.68927 -58.812684)
		(width 0.1524)
		(layer "In7.Cu")
		(net "M_A_DQ7")
	)
	(segment
		(start 173.041056 -60.341764)
		(end 173.256956 -60.557664)
		(width 0.1524)
		(layer "In7.Cu")
		(net "M_A_DQ7")
	)
	(segment
		(start 172.198538 -60.10656)
		(end 172.198538 -60.321952)
		(width 0.1524)
		(layer "In7.Cu")
		(net "M_A_DQ7")
	)
	(segment
		(start 168.31691 -56.224932)
		(end 168.500552 -56.042052)
		(width 0.1524)
		(layer "In7.Cu")
		(net "M_A_DQ7")
	)
	(segment
		(start 158.892748 -50.8508)
		(end 159.97809 -50.8508)
		(width 0.1524)
		(layer "In7.Cu")
		(net "M_A_DQ7")
	)
	(segment
		(start 170.47337 -58.381392)
		(end 170.47337 -58.596784)
		(width 0.1524)
		(layer "In7.Cu")
		(net "M_A_DQ7")
	)
	(segment
		(start 174.11954 -61.63564)
		(end 173.923706 -61.831728)
		(width 0.1524)
		(layer "In7.Cu")
		(net "M_A_DQ7")
	)
	(segment
		(start 169.80662 -57.107328)
		(end 169.80662 -57.32272)
		(width 0.1524)
		(layer "In7.Cu")
		(net "M_A_DQ7")
	)
	(segment
		(start 171.551854 -59.675268)
		(end 171.767246 -59.675268)
		(width 0.1524)
		(layer "In7.Cu")
		(net "M_A_DQ7")
	)
	(segment
		(start 172.178472 -59.47918)
		(end 172.394372 -59.69508)
		(width 0.1524)
		(layer "In7.Cu")
		(net "M_A_DQ7")
	)
	(segment
		(start 186.58078 -68.26758)
		(end 186.58078 -68.761864)
		(width 0.1524)
		(layer "In7.Cu")
		(net "M_A_DQ7")
	)
	(segment
		(start 172.825918 -60.341764)
		(end 173.041056 -60.341764)
		(width 0.1524)
		(layer "In7.Cu")
		(net "M_A_DQ7")
	)
	(segment
		(start 171.335954 -59.459368)
		(end 171.551854 -59.675268)
		(width 0.1524)
		(layer "In7.Cu")
		(net "M_A_DQ7")
	)
	(segment
		(start 109.431328 -42.77868)
		(end 109.2073 -42.6339)
		(width 0.1016)
		(layer "In7.Cu")
		(net "M_A_DQ7")
	)
	(segment
		(start 118.364 -43.942)
		(end 118.462298 -44.040298)
		(width 0.1524)
		(layer "In7.Cu")
		(net "M_A_DQ7")
	)
	(segment
		(start 109.2073 -42.6339)
		(end 109.13872 -42.4434)
		(width 0.1016)
		(layer "In7.Cu")
		(net "M_A_DQ7")
	)
	(segment
		(start 169.59072 -56.891428)
		(end 169.80662 -57.107328)
		(width 0.1524)
		(layer "In7.Cu")
		(net "M_A_DQ7")
	)
	(segment
		(start 112.395 -43.942)
		(end 118.364 -43.942)
		(width 0.1524)
		(layer "In7.Cu")
		(net "M_A_DQ7")
	)
	(segment
		(start 173.923706 -62.04712)
		(end 174.50816 -62.631574)
		(width 0.1524)
		(layer "In7.Cu")
		(net "M_A_DQ7")
	)
	(segment
		(start 118.462298 -44.040298)
		(end 152.082246 -44.040298)
		(width 0.1524)
		(layer "In7.Cu")
		(net "M_A_DQ7")
	)
	(segment
		(start 173.256956 -60.773056)
		(end 173.061122 -60.969144)
		(width 0.1524)
		(layer "In7.Cu")
		(net "M_A_DQ7")
	)
	(segment
		(start 168.748202 -56.871616)
		(end 168.964102 -57.087516)
		(width 0.1524)
		(layer "In7.Cu")
		(net "M_A_DQ7")
	)
	(segment
		(start 173.923706 -61.831728)
		(end 173.923706 -62.04712)
		(width 0.1524)
		(layer "In7.Cu")
		(net "M_A_DQ7")
	)
	(segment
		(start 109.52988 -42.8244)
		(end 110.13948 -43.434)
		(width 0.1524)
		(layer "In7.Cu")
		(net "M_A_DQ7")
	)
	(segment
		(start 170.68927 -58.812684)
		(end 170.904662 -58.812684)
		(width 0.1524)
		(layer "In7.Cu")
		(net "M_A_DQ7")
	)
	(segment
		(start 186.038744 -69.3039)
		(end 185.5216 -69.3039)
		(width 0.1524)
		(layer "In7.Cu")
		(net "M_A_DQ7")
	)
	(segment
		(start 169.610786 -57.7342)
		(end 169.826686 -57.9501)
		(width 0.1524)
		(layer "In7.Cu")
		(net "M_A_DQ7")
	)
	(segment
		(start 173.061122 -60.969144)
		(end 173.061122 -61.184536)
		(width 0.1524)
		(layer "In7.Cu")
		(net "M_A_DQ7")
	)
	(segment
		(start 171.315888 -58.616596)
		(end 171.531788 -58.832496)
		(width 0.1524)
		(layer "In7.Cu")
		(net "M_A_DQ7")
	)
	(segment
		(start 109.52988 -42.8244)
		(end 109.431328 -42.77868)
		(width 0.1016)
		(layer "In7.Cu")
		(net "M_A_DQ7")
	)
	(segment
		(start 174.50816 -65.11036)
		(end 175.2346 -65.8368)
		(width 0.1524)
		(layer "In7.Cu")
		(net "M_A_DQ7")
	)
	(segment
		(start 174.50816 -62.631574)
		(end 174.50816 -65.11036)
		(width 0.1524)
		(layer "In7.Cu")
		(net "M_A_DQ7")
	)
	(segment
		(start 152.082246 -44.040298)
		(end 158.892748 -50.8508)
		(width 0.1524)
		(layer "In7.Cu")
		(net "M_A_DQ7")
	)
	(segment
		(start 108.9152 -42.1386)
		(end 108.770928 -42.04843)
		(width 0.1016)
		(layer "In7.Cu")
		(net "M_A_DQ7")
	)
	(segment
		(start 184.15 -65.8368)
		(end 186.58078 -68.26758)
		(width 0.1524)
		(layer "In7.Cu")
		(net "M_A_DQ7")
	)
	(arc
		(start 109.13872 -42.4434)
		(mid 109.132873 -42.391677)
		(end 109.121956 -42.340784)
		(width 0.1016)
		(layer "In7.Cu")
		(net "M_A_DQ7")
	)
	(arc
		(start 108.770928 -42.04843)
		(mid 108.679797 -41.987538)
		(end 108.5723 -41.966134)
		(width 0.1016)
		(layer "In7.Cu")
		(net "M_A_DQ7")
	)
	(segment
		(start 93.851984 -19.415252)
		(end 92.978986 -20.28825)
		(width 0.1143)
		(layer "F.Cu")
		(net "LPC_CPU_LAD3")
	)
	(segment
		(start 82.845148 -22.135846)
		(end 83.517994 -21.463)
		(width 0.1143)
		(layer "F.Cu")
		(net "LPC_CPU_LAD3")
	)
	(segment
		(start 91.108022 -20.28825)
		(end 90.513916 -20.882356)
		(width 0.1143)
		(layer "F.Cu")
		(net "LPC_CPU_LAD3")
	)
	(segment
		(start 114.020346 -17.94383)
		(end 113.285016 -17.2085)
		(width 0.1143)
		(layer "F.Cu")
		(net "LPC_CPU_LAD3")
	)
	(segment
		(start 127.7112 -37.592)
		(end 127.474472 -37.592)
		(width 0.1143)
		(layer "F.Cu")
		(net "LPC_CPU_LAD3")
	)
	(segment
		(start 82.639154 -22.135846)
		(end 82.845148 -22.135846)
		(width 0.1143)
		(layer "F.Cu")
		(net "LPC_CPU_LAD3")
	)
	(segment
		(start 87.421212 -21.64715)
		(end 87.084662 -21.3106)
		(width 0.1143)
		(layer "F.Cu")
		(net "LPC_CPU_LAD3")
	)
	(segment
		(start 83.693762 -38.3032)
		(end 83.7692 -38.3032)
		(width 0.1143)
		(layer "F.Cu")
		(net "LPC_CPU_LAD3")
	)
	(segment
		(start 87.084662 -21.3106)
		(end 86.5632 -21.3106)
		(width 0.1143)
		(layer "F.Cu")
		(net "LPC_CPU_LAD3")
	)
	(segment
		(start 86.4108 -21.463)
		(end 86.5632 -21.3106)
		(width 0.1143)
		(layer "F.Cu")
		(net "LPC_CPU_LAD3")
	)
	(segment
		(start 88.956388 -21.64715)
		(end 87.421212 -21.64715)
		(width 0.1143)
		(layer "F.Cu")
		(net "LPC_CPU_LAD3")
	)
	(segment
		(start 82.845148 -23.225252)
		(end 82.55 -22.930104)
		(width 0.1143)
		(layer "F.Cu")
		(net "LPC_CPU_LAD3")
	)
	(segment
		(start 83.266788 -38.730174)
		(end 83.693762 -38.3032)
		(width 0.1143)
		(layer "F.Cu")
		(net "LPC_CPU_LAD3")
	)
	(segment
		(start 105.8545 -17.2085)
		(end 103.647748 -19.415252)
		(width 0.1143)
		(layer "F.Cu")
		(net "LPC_CPU_LAD3")
	)
	(segment
		(start 114.020346 -24.137874)
		(end 114.020346 -17.94383)
		(width 0.1143)
		(layer "F.Cu")
		(net "LPC_CPU_LAD3")
	)
	(segment
		(start 113.285016 -17.2085)
		(end 105.8545 -17.2085)
		(width 0.1143)
		(layer "F.Cu")
		(net "LPC_CPU_LAD3")
	)
	(segment
		(start 127.474472 -37.592)
		(end 114.020346 -24.137874)
		(width 0.1143)
		(layer "F.Cu")
		(net "LPC_CPU_LAD3")
	)
	(segment
		(start 82.55 -22.930104)
		(end 82.55 -22.225)
		(width 0.1143)
		(layer "F.Cu")
		(net "LPC_CPU_LAD3")
	)
	(segment
		(start 103.647748 -19.415252)
		(end 93.851984 -19.415252)
		(width 0.1143)
		(layer "F.Cu")
		(net "LPC_CPU_LAD3")
	)
	(segment
		(start 89.721182 -20.882356)
		(end 88.956388 -21.64715)
		(width 0.1143)
		(layer "F.Cu")
		(net "LPC_CPU_LAD3")
	)
	(segment
		(start 92.978986 -20.28825)
		(end 91.108022 -20.28825)
		(width 0.1143)
		(layer "F.Cu")
		(net "LPC_CPU_LAD3")
	)
	(segment
		(start 82.55 -22.225)
		(end 82.639154 -22.135846)
		(width 0.1143)
		(layer "F.Cu")
		(net "LPC_CPU_LAD3")
	)
	(segment
		(start 83.517994 -21.463)
		(end 86.4108 -21.463)
		(width 0.1143)
		(layer "F.Cu")
		(net "LPC_CPU_LAD3")
	)
	(segment
		(start 90.513916 -20.882356)
		(end 89.721182 -20.882356)
		(width 0.1143)
		(layer "F.Cu")
		(net "LPC_CPU_LAD3")
	)
	(via
		(at 86.5632 -21.3106)
		(size 0.7112)
		(drill 0.3556)
		(layers "F.Cu" "B.Cu")
		(net "LPC_CPU_LAD3")
	)
	(via
		(at 82.845148 -23.225252)
		(size 0.4318)
		(drill 0.2032)
		(layers "F.Cu" "B.Cu")
		(net "LPC_CPU_LAD3")
	)
	(via
		(at 83.7692 -38.3032)
		(size 0.4318)
		(drill 0.2032)
		(layers "F.Cu" "B.Cu")
		(net "LPC_CPU_LAD3")
	)
	(segment
		(start 81.534 -20.36826)
		(end 81.4324 -20.46986)
		(width 0.0889)
		(layer "In2.Cu")
		(net "LPC_CPU_LAD3")
	)
	(segment
		(start 83.2358 -23.123652)
		(end 83.1342 -23.225252)
		(width 0.0889)
		(layer "In2.Cu")
		(net "LPC_CPU_LAD3")
	)
	(segment
		(start 80.60944 -33.31464)
		(end 80.60944 -26.75636)
		(width 0.0889)
		(layer "In2.Cu")
		(net "LPC_CPU_LAD3")
	)
	(segment
		(start 82.1436 -22.23516)
		(end 82.1436 -22.50186)
		(width 0.0889)
		(layer "In2.Cu")
		(net "LPC_CPU_LAD3")
	)
	(segment
		(start 80.9244 -19.9644)
		(end 81.026 -19.8628)
		(width 0.0889)
		(layer "In2.Cu")
		(net "LPC_CPU_LAD3")
	)
	(segment
		(start 80.9244 -21.9837)
		(end 80.9244 -21.717)
		(width 0.0889)
		(layer "In2.Cu")
		(net "LPC_CPU_LAD3")
	)
	(segment
		(start 82.325464 -34.167064)
		(end 81.993232 -33.834832)
		(width 0.0889)
		(layer "In2.Cu")
		(net "LPC_CPU_LAD3")
	)
	(segment
		(start 80.60944 -26.75636)
		(end 81.0006 -26.3652)
		(width 0.0889)
		(layer "In2.Cu")
		(net "LPC_CPU_LAD3")
	)
	(segment
		(start 83.1469 -20.36826)
		(end 81.534 -20.36826)
		(width 0.0889)
		(layer "In2.Cu")
		(net "LPC_CPU_LAD3")
	)
	(segment
		(start 83.1342 -19.8628)
		(end 83.2358 -19.9644)
		(width 0.0889)
		(layer "In2.Cu")
		(net "LPC_CPU_LAD3")
	)
	(segment
		(start 84.384134 -37.688266)
		(end 84.384134 -36.99002)
		(width 0.0889)
		(layer "In2.Cu")
		(net "LPC_CPU_LAD3")
	)
	(segment
		(start 81.6102 -24.794464)
		(end 81.6102 -23.1648)
		(width 0.0889)
		(layer "In2.Cu")
		(net "LPC_CPU_LAD3")
	)
	(segment
		(start 83.1469 -20.81276)
		(end 83.2358 -20.90166)
		(width 0.0889)
		(layer "In2.Cu")
		(net "LPC_CPU_LAD3")
	)
	(segment
		(start 79.502 -22.1869)
		(end 79.6163 -22.0726)
		(width 0.0889)
		(layer "In2.Cu")
		(net "LPC_CPU_LAD3")
	)
	(segment
		(start 80.9244 -21.717)
		(end 80.8355 -21.6281)
		(width 0.0889)
		(layer "In2.Cu")
		(net "LPC_CPU_LAD3")
	)
	(segment
		(start 79.6163 -22.0726)
		(end 80.8355 -22.0726)
		(width 0.0889)
		(layer "In2.Cu")
		(net "LPC_CPU_LAD3")
	)
	(segment
		(start 81.4324 -20.71116)
		(end 81.534 -20.81276)
		(width 0.0889)
		(layer "In2.Cu")
		(net "LPC_CPU_LAD3")
	)
	(segment
		(start 84.384134 -36.99002)
		(end 83.85048 -36.456366)
		(width 0.0889)
		(layer "In2.Cu")
		(net "LPC_CPU_LAD3")
	)
	(segment
		(start 81.5086 -21.70176)
		(end 83.1469 -21.70176)
		(width 0.0889)
		(layer "In2.Cu")
		(net "LPC_CPU_LAD3")
	)
	(segment
		(start 83.85048 -36.456366)
		(end 82.031586 -36.456366)
		(width 0.0889)
		(layer "In2.Cu")
		(net "LPC_CPU_LAD3")
	)
	(segment
		(start 81.81975 -35.20567)
		(end 82.325464 -34.699956)
		(width 0.0889)
		(layer "In2.Cu")
		(net "LPC_CPU_LAD3")
	)
	(segment
		(start 83.7692 -38.3032)
		(end 84.384134 -37.688266)
		(width 0.0889)
		(layer "In2.Cu")
		(net "LPC_CPU_LAD3")
	)
	(segment
		(start 81.4324 -20.46986)
		(end 81.4324 -20.71116)
		(width 0.0889)
		(layer "In2.Cu")
		(net "LPC_CPU_LAD3")
	)
	(segment
		(start 80.8355 -21.1836)
		(end 80.9244 -21.0947)
		(width 0.0889)
		(layer "In2.Cu")
		(net "LPC_CPU_LAD3")
	)
	(segment
		(start 80.8355 -22.0726)
		(end 80.9244 -21.9837)
		(width 0.0889)
		(layer "In2.Cu")
		(net "LPC_CPU_LAD3")
	)
	(segment
		(start 79.8576 -21.5392)
		(end 79.8576 -21.2725)
		(width 0.0889)
		(layer "In2.Cu")
		(net "LPC_CPU_LAD3")
	)
	(segment
		(start 83.1469 -21.70176)
		(end 83.2358 -21.79066)
		(width 0.0889)
		(layer "In2.Cu")
		(net "LPC_CPU_LAD3")
	)
	(segment
		(start 79.6163 -22.5171)
		(end 79.502 -22.4028)
		(width 0.0889)
		(layer "In2.Cu")
		(net "LPC_CPU_LAD3")
	)
	(segment
		(start 83.2358 -19.9644)
		(end 83.2358 -20.27936)
		(width 0.0889)
		(layer "In2.Cu")
		(net "LPC_CPU_LAD3")
	)
	(segment
		(start 79.9465 -21.1836)
		(end 80.8355 -21.1836)
		(width 0.0889)
		(layer "In2.Cu")
		(net "LPC_CPU_LAD3")
	)
	(segment
		(start 83.1342 -23.225252)
		(end 82.845148 -23.225252)
		(width 0.0889)
		(layer "In2.Cu")
		(net "LPC_CPU_LAD3")
	)
	(segment
		(start 80.8355 -21.6281)
		(end 79.9465 -21.6281)
		(width 0.0889)
		(layer "In2.Cu")
		(net "LPC_CPU_LAD3")
	)
	(segment
		(start 81.407 -21.35886)
		(end 81.407 -21.60016)
		(width 0.0889)
		(layer "In2.Cu")
		(net "LPC_CPU_LAD3")
	)
	(segment
		(start 80.9625 -22.5171)
		(end 79.6163 -22.5171)
		(width 0.0889)
		(layer "In2.Cu")
		(net "LPC_CPU_LAD3")
	)
	(segment
		(start 81.6102 -23.1648)
		(end 80.9625 -22.5171)
		(width 0.0889)
		(layer "In2.Cu")
		(net "LPC_CPU_LAD3")
	)
	(segment
		(start 83.1469 -22.14626)
		(end 82.2325 -22.14626)
		(width 0.0889)
		(layer "In2.Cu")
		(net "LPC_CPU_LAD3")
	)
	(segment
		(start 79.502 -22.4028)
		(end 79.502 -22.1869)
		(width 0.0889)
		(layer "In2.Cu")
		(net "LPC_CPU_LAD3")
	)
	(segment
		(start 83.1469 -22.59076)
		(end 83.2358 -22.67966)
		(width 0.0889)
		(layer "In2.Cu")
		(net "LPC_CPU_LAD3")
	)
	(segment
		(start 83.2358 -22.67966)
		(end 83.2358 -23.123652)
		(width 0.0889)
		(layer "In2.Cu")
		(net "LPC_CPU_LAD3")
	)
	(segment
		(start 81.407 -21.60016)
		(end 81.5086 -21.70176)
		(width 0.0889)
		(layer "In2.Cu")
		(net "LPC_CPU_LAD3")
	)
	(segment
		(start 82.031586 -36.456366)
		(end 81.81975 -36.24453)
		(width 0.0889)
		(layer "In2.Cu")
		(net "LPC_CPU_LAD3")
	)
	(segment
		(start 82.2325 -22.14626)
		(end 82.1436 -22.23516)
		(width 0.0889)
		(layer "In2.Cu")
		(net "LPC_CPU_LAD3")
	)
	(segment
		(start 82.2325 -22.59076)
		(end 83.1469 -22.59076)
		(width 0.0889)
		(layer "In2.Cu")
		(net "LPC_CPU_LAD3")
	)
	(segment
		(start 83.2358 -21.16836)
		(end 83.1469 -21.25726)
		(width 0.0889)
		(layer "In2.Cu")
		(net "LPC_CPU_LAD3")
	)
	(segment
		(start 83.2358 -20.27936)
		(end 83.1469 -20.36826)
		(width 0.0889)
		(layer "In2.Cu")
		(net "LPC_CPU_LAD3")
	)
	(segment
		(start 81.993232 -33.834832)
		(end 81.129632 -33.834832)
		(width 0.0889)
		(layer "In2.Cu")
		(net "LPC_CPU_LAD3")
	)
	(segment
		(start 82.1436 -22.50186)
		(end 82.2325 -22.59076)
		(width 0.0889)
		(layer "In2.Cu")
		(net "LPC_CPU_LAD3")
	)
	(segment
		(start 81.534 -20.81276)
		(end 83.1469 -20.81276)
		(width 0.0889)
		(layer "In2.Cu")
		(net "LPC_CPU_LAD3")
	)
	(segment
		(start 81.0006 -25.404064)
		(end 81.6102 -24.794464)
		(width 0.0889)
		(layer "In2.Cu")
		(net "LPC_CPU_LAD3")
	)
	(segment
		(start 81.0006 -26.3652)
		(end 81.0006 -25.404064)
		(width 0.0889)
		(layer "In2.Cu")
		(net "LPC_CPU_LAD3")
	)
	(segment
		(start 81.5086 -21.25726)
		(end 81.407 -21.35886)
		(width 0.0889)
		(layer "In2.Cu")
		(net "LPC_CPU_LAD3")
	)
	(segment
		(start 81.026 -19.8628)
		(end 83.1342 -19.8628)
		(width 0.0889)
		(layer "In2.Cu")
		(net "LPC_CPU_LAD3")
	)
	(segment
		(start 83.2358 -22.05736)
		(end 83.1469 -22.14626)
		(width 0.0889)
		(layer "In2.Cu")
		(net "LPC_CPU_LAD3")
	)
	(segment
		(start 83.2358 -21.79066)
		(end 83.2358 -22.05736)
		(width 0.0889)
		(layer "In2.Cu")
		(net "LPC_CPU_LAD3")
	)
	(segment
		(start 83.2358 -20.90166)
		(end 83.2358 -21.16836)
		(width 0.0889)
		(layer "In2.Cu")
		(net "LPC_CPU_LAD3")
	)
	(segment
		(start 79.9465 -21.6281)
		(end 79.8576 -21.5392)
		(width 0.0889)
		(layer "In2.Cu")
		(net "LPC_CPU_LAD3")
	)
	(segment
		(start 81.129632 -33.834832)
		(end 80.60944 -33.31464)
		(width 0.0889)
		(layer "In2.Cu")
		(net "LPC_CPU_LAD3")
	)
	(segment
		(start 79.8576 -21.2725)
		(end 79.9465 -21.1836)
		(width 0.0889)
		(layer "In2.Cu")
		(net "LPC_CPU_LAD3")
	)
	(segment
		(start 83.1469 -21.25726)
		(end 81.5086 -21.25726)
		(width 0.0889)
		(layer "In2.Cu")
		(net "LPC_CPU_LAD3")
	)
	(segment
		(start 82.325464 -34.699956)
		(end 82.325464 -34.167064)
		(width 0.0889)
		(layer "In2.Cu")
		(net "LPC_CPU_LAD3")
	)
	(segment
		(start 81.81975 -36.24453)
		(end 81.81975 -35.20567)
		(width 0.0889)
		(layer "In2.Cu")
		(net "LPC_CPU_LAD3")
	)
	(segment
		(start 80.9244 -21.0947)
		(end 80.9244 -19.9644)
		(width 0.0889)
		(layer "In2.Cu")
		(net "LPC_CPU_LAD3")
	)
	(segment
		(start 28.4988 -58.6486)
		(end 28.6258 -58.7756)
		(width 0.2032)
		(layer "F.Cu")
		(net "VR_PVCCP_PVNN_VDD")
	)
	(segment
		(start 28.7274 -58.8772)
		(end 28.7274 -59.563)
		(width 0.2032)
		(layer "F.Cu")
		(net "VR_PVCCP_PVNN_VDD")
	)
	(segment
		(start 22.863048 -54.864)
		(end 23.066248 -54.6608)
		(width 0.2032)
		(layer "F.Cu")
		(net "VR_PVCCP_PVNN_VDD")
	)
	(segment
		(start 23.066248 -54.6608)
		(end 23.066248 -54.61)
		(width 0.2032)
		(layer "F.Cu")
		(net "VR_PVCCP_PVNN_VDD")
	)
	(segment
		(start 28.4988 -58.0136)
		(end 28.4988 -58.6486)
		(width 0.2032)
		(layer "F.Cu")
		(net "VR_PVCCP_PVNN_VDD")
	)
	(segment
		(start 22.863048 -55.547006)
		(end 22.863048 -54.864)
		(width 0.2032)
		(layer "F.Cu")
		(net "VR_PVCCP_PVNN_VDD")
	)
	(segment
		(start 28.6258 -58.7756)
		(end 28.7274 -58.8772)
		(width 0.2032)
		(layer "F.Cu")
		(net "VR_PVCCP_PVNN_VDD")
	)
	(via
		(at 23.066248 -54.61)
		(size 0.508)
		(drill 0.254)
		(layers "F.Cu" "B.Cu")
		(net "VR_PVCCP_PVNN_VDD")
	)
	(via
		(at 25.778714 -58.52668)
		(size 0.7112)
		(drill 0.3556)
		(layers "F.Cu" "B.Cu")
		(net "VR_PVCCP_PVNN_VDD")
	)
	(via
		(at 28.6258 -58.7756)
		(size 0.508)
		(drill 0.254)
		(layers "F.Cu" "B.Cu")
		(net "VR_PVCCP_PVNN_VDD")
	)
	(segment
		(start 23.493476 -54.281324)
		(end 23.1648 -54.61)
		(width 0.2032)
		(layer "B.Cu")
		(net "VR_PVCCP_PVNN_VDD")
	)
	(segment
		(start 25.778714 -58.52668)
		(end 24.741124 -57.48909)
		(width 0.2032)
		(layer "B.Cu")
		(net "VR_PVCCP_PVNN_VDD")
	)
	(segment
		(start 27.9654 -59.436)
		(end 26.688034 -59.436)
		(width 0.2032)
		(layer "B.Cu")
		(net "VR_PVCCP_PVNN_VDD")
	)
	(segment
		(start 28.6258 -58.7756)
		(end 27.9654 -59.436)
		(width 0.2032)
		(layer "B.Cu")
		(net "VR_PVCCP_PVNN_VDD")
	)
	(segment
		(start 22.3012 -55.3466)
		(end 22.5552 -55.6006)
		(width 0.2032)
		(layer "B.Cu")
		(net "VR_PVCCP_PVNN_VDD")
	)
	(segment
		(start 24.741124 -57.48909)
		(end 24.741124 -56.513476)
		(width 0.2032)
		(layer "B.Cu")
		(net "VR_PVCCP_PVNN_VDD")
	)
	(segment
		(start 24.436832 -54.281324)
		(end 23.493476 -54.281324)
		(width 0.2032)
		(layer "B.Cu")
		(net "VR_PVCCP_PVNN_VDD")
	)
	(segment
		(start 25.0444 -54.888892)
		(end 24.436832 -54.281324)
		(width 0.2032)
		(layer "B.Cu")
		(net "VR_PVCCP_PVNN_VDD")
	)
	(segment
		(start 24.741124 -56.513476)
		(end 25.0444 -56.2102)
		(width 0.2032)
		(layer "B.Cu")
		(net "VR_PVCCP_PVNN_VDD")
	)
	(segment
		(start 25.0444 -56.2102)
		(end 25.0444 -54.888892)
		(width 0.2032)
		(layer "B.Cu")
		(net "VR_PVCCP_PVNN_VDD")
	)
	(segment
		(start 23.015448 -54.6608)
		(end 22.3012 -54.6608)
		(width 0.2032)
		(layer "B.Cu")
		(net "VR_PVCCP_PVNN_VDD")
	)
	(segment
		(start 23.066248 -54.61)
		(end 23.015448 -54.6608)
		(width 0.2032)
		(layer "B.Cu")
		(net "VR_PVCCP_PVNN_VDD")
	)
	(segment
		(start 23.1648 -54.61)
		(end 23.066248 -54.61)
		(width 0.2032)
		(layer "B.Cu")
		(net "VR_PVCCP_PVNN_VDD")
	)
	(segment
		(start 26.688034 -59.436)
		(end 25.778714 -58.52668)
		(width 0.2032)
		(layer "B.Cu")
		(net "VR_PVCCP_PVNN_VDD")
	)
	(segment
		(start 22.3012 -54.6608)
		(end 22.3012 -55.3466)
		(width 0.2032)
		(layer "B.Cu")
		(net "VR_PVCCP_PVNN_VDD")
	)
	(segment
		(start 161.017712 -66.175128)
		(end 161.02965 -66.175128)
		(width 0.2413)
		(layer "F.Cu")
		(net "M_A_BS2")
	)
	(segment
		(start 108.091732 -47.25543)
		(end 108.077 -47.25543)
		(width 0.1016)
		(layer "F.Cu")
		(net "M_A_BS2")
	)
	(segment
		(start 108.433108 -46.914054)
		(end 108.091732 -47.25543)
		(width 0.1016)
		(layer "F.Cu")
		(net "M_A_BS2")
	)
	(segment
		(start 161.02965 -66.175128)
		(end 161.088578 -66.1162)
		(width 0.2413)
		(layer "F.Cu")
		(net "M_A_BS2")
	)
	(segment
		(start 160.749996 -70.806564)
		(end 160.749996 -69.304408)
		(width 0.2413)
		(layer "F.Cu")
		(net "M_A_BS2")
	)
	(segment
		(start 160.63087 -69.185282)
		(end 160.63087 -66.56197)
		(width 0.2413)
		(layer "F.Cu")
		(net "M_A_BS2")
	)
	(segment
		(start 160.63087 -66.56197)
		(end 161.017712 -66.175128)
		(width 0.2413)
		(layer "F.Cu")
		(net "M_A_BS2")
	)
	(segment
		(start 160.749996 -69.304408)
		(end 160.63087 -69.185282)
		(width 0.2413)
		(layer "F.Cu")
		(net "M_A_BS2")
	)
	(via
		(at 161.088578 -66.1162)
		(size 0.4318)
		(drill 0.2032)
		(layers "F.Cu" "B.Cu")
		(net "M_A_BS2")
	)
	(via
		(at 108.077 -47.25543)
		(size 0.4318)
		(drill 0.2032)
		(layers "F.Cu" "B.Cu")
		(net "M_A_BS2")
	)
	(segment
		(start 160.749996 -62.599824)
		(end 160.749996 -64.74333)
		(width 0.2413)
		(layer "B.Cu")
		(net "M_A_BS2")
	)
	(segment
		(start 160.749996 -64.74333)
		(end 161.088578 -65.081912)
		(width 0.2413)
		(layer "B.Cu")
		(net "M_A_BS2")
	)
	(segment
		(start 161.088578 -65.081912)
		(end 161.088578 -66.1162)
		(width 0.2413)
		(layer "B.Cu")
		(net "M_A_BS2")
	)
	(segment
		(start 160.4264 -63.0174)
		(end 160.4264 -64.9986)
		(width 0.1905)
		(layer "In9.Cu")
		(net "M_A_BS2")
	)
	(segment
		(start 119.86895 -47.78375)
		(end 147.44065 -47.78375)
		(width 0.1905)
		(layer "In9.Cu")
		(net "M_A_BS2")
	)
	(segment
		(start 113.60531 -47.515018)
		(end 113.533428 -47.5869)
		(width 0.1016)
		(layer "In9.Cu")
		(net "M_A_BS2")
	)
	(segment
		(start 117.094 -47.5488)
		(end 119.634 -47.5488)
		(width 0.1905)
		(layer "In9.Cu")
		(net "M_A_BS2")
	)
	(segment
		(start 108.40847 -47.5869)
		(end 108.077 -47.25543)
		(width 0.1016)
		(layer "In9.Cu")
		(net "M_A_BS2")
	)
	(segment
		(start 160.4264 -64.9986)
		(end 161.088578 -65.660778)
		(width 0.1905)
		(layer "In9.Cu")
		(net "M_A_BS2")
	)
	(segment
		(start 119.634 -47.5488)
		(end 119.86895 -47.78375)
		(width 0.1905)
		(layer "In9.Cu")
		(net "M_A_BS2")
	)
	(segment
		(start 160.90265 -62.54115)
		(end 160.4264 -63.0174)
		(width 0.1905)
		(layer "In9.Cu")
		(net "M_A_BS2")
	)
	(segment
		(start 117.060218 -47.515018)
		(end 113.60531 -47.515018)
		(width 0.1016)
		(layer "In9.Cu")
		(net "M_A_BS2")
	)
	(segment
		(start 161.088578 -65.660778)
		(end 161.088578 -66.1162)
		(width 0.1905)
		(layer "In9.Cu")
		(net "M_A_BS2")
	)
	(segment
		(start 147.9677 -48.3108)
		(end 149.15007 -48.3108)
		(width 0.1905)
		(layer "In9.Cu")
		(net "M_A_BS2")
	)
	(segment
		(start 160.90265 -57.758838)
		(end 160.90265 -62.54115)
		(width 0.1905)
		(layer "In9.Cu")
		(net "M_A_BS2")
	)
	(segment
		(start 113.533428 -47.5869)
		(end 108.40847 -47.5869)
		(width 0.1016)
		(layer "In9.Cu")
		(net "M_A_BS2")
	)
	(segment
		(start 117.094 -47.5488)
		(end 117.060218 -47.515018)
		(width 0.1016)
		(layer "In9.Cu")
		(net "M_A_BS2")
	)
	(segment
		(start 151.454358 -48.310546)
		(end 160.90265 -57.758838)
		(width 0.1905)
		(layer "In9.Cu")
		(net "M_A_BS2")
	)
	(segment
		(start 149.15007 -48.3108)
		(end 149.150324 -48.310546)
		(width 0.1905)
		(layer "In9.Cu")
		(net "M_A_BS2")
	)
	(segment
		(start 149.150324 -48.310546)
		(end 151.454358 -48.310546)
		(width 0.1905)
		(layer "In9.Cu")
		(net "M_A_BS2")
	)
	(segment
		(start 147.44065 -47.78375)
		(end 147.9677 -48.3108)
		(width 0.1905)
		(layer "In9.Cu")
		(net "M_A_BS2")
	)
	(segment
		(start 162.774122 -64.514476)
		(end 162.774122 -63.590678)
		(width 0.3048)
		(layer "F.Cu")
		(net "DDR3_M_A_VREF_CA")
	)
	(segment
		(start 163.4998 -61.1124)
		(end 163.4998 -60.3504)
		(width 0.3048)
		(layer "F.Cu")
		(net "DDR3_M_A_VREF_CA")
	)
	(segment
		(start 163.1696 -65.6082)
		(end 162.7759 -65.2145)
		(width 0.3048)
		(layer "F.Cu")
		(net "DDR3_M_A_VREF_CA")
	)
	(segment
		(start 163.5252 -59.0804)
		(end 163.5252 -60.325)
		(width 0.3048)
		(layer "F.Cu")
		(net "DDR3_M_A_VREF_CA")
	)
	(segment
		(start 162.850068 -63.514732)
		(end 162.850068 -62.59322)
		(width 0.3048)
		(layer "F.Cu")
		(net "DDR3_M_A_VREF_CA")
	)
	(segment
		(start 163.7157 -67.86118)
		(end 163.1696 -67.31508)
		(width 0.3048)
		(layer "F.Cu")
		(net "DDR3_M_A_VREF_CA")
	)
	(segment
		(start 163.4998 -60.3504)
		(end 163.5252 -60.325)
		(width 0.3048)
		(layer "F.Cu")
		(net "DDR3_M_A_VREF_CA")
	)
	(segment
		(start 162.850068 -62.59322)
		(end 162.850068 -61.762132)
		(width 0.3048)
		(layer "F.Cu")
		(net "DDR3_M_A_VREF_CA")
	)
	(segment
		(start 162.774122 -63.590678)
		(end 162.850068 -63.514732)
		(width 0.3048)
		(layer "F.Cu")
		(net "DDR3_M_A_VREF_CA")
	)
	(segment
		(start 162.7759 -65.2145)
		(end 162.7759 -64.516254)
		(width 0.3048)
		(layer "F.Cu")
		(net "DDR3_M_A_VREF_CA")
	)
	(segment
		(start 163.1696 -67.31508)
		(end 163.1696 -65.6082)
		(width 0.3048)
		(layer "F.Cu")
		(net "DDR3_M_A_VREF_CA")
	)
	(segment
		(start 162.850068 -61.762132)
		(end 163.4998 -61.1124)
		(width 0.3048)
		(layer "F.Cu")
		(net "DDR3_M_A_VREF_CA")
	)
	(segment
		(start 162.7759 -64.516254)
		(end 162.774122 -64.514476)
		(width 0.3048)
		(layer "F.Cu")
		(net "DDR3_M_A_VREF_CA")
	)
	(via
		(at 163.7157 -67.86118)
		(size 0.4318)
		(drill 0.2032)
		(layers "F.Cu" "B.Cu")
		(net "DDR3_M_A_VREF_CA")
	)
	(via
		(at 163.5252 -59.0804)
		(size 0.7112)
		(drill 0.3556)
		(layers "F.Cu" "B.Cu")
		(net "DDR3_M_A_VREF_CA")
	)
	(segment
		(start 162.797998 -69.575172)
		(end 162.797998 -69.114162)
		(width 0.3048)
		(layer "B.Cu")
		(net "DDR3_M_A_VREF_CA")
	)
	(segment
		(start 162.850068 -72.375268)
		(end 162.850068 -70.79996)
		(width 0.3048)
		(layer "B.Cu")
		(net "DDR3_M_A_VREF_CA")
	)
	(segment
		(start 162.850068 -70.79996)
		(end 162.850068 -69.627242)
		(width 0.3048)
		(layer "B.Cu")
		(net "DDR3_M_A_VREF_CA")
	)
	(segment
		(start 162.850068 -69.627242)
		(end 162.797998 -69.575172)
		(width 0.3048)
		(layer "B.Cu")
		(net "DDR3_M_A_VREF_CA")
	)
	(segment
		(start 162.8902 -69.02196)
		(end 162.8902 -68.63334)
		(width 0.3048)
		(layer "B.Cu")
		(net "DDR3_M_A_VREF_CA")
	)
	(segment
		(start 162.8902 -68.63334)
		(end 163.60394 -67.9196)
		(width 0.3048)
		(layer "B.Cu")
		(net "DDR3_M_A_VREF_CA")
	)
	(segment
		(start 162.8648 -72.39)
		(end 162.1028 -72.39)
		(width 0.3048)
		(layer "B.Cu")
		(net "DDR3_M_A_VREF_CA")
	)
	(segment
		(start 162.8648 -72.39)
		(end 162.850068 -72.375268)
		(width 0.3048)
		(layer "B.Cu")
		(net "DDR3_M_A_VREF_CA")
	)
	(segment
		(start 163.65728 -67.9196)
		(end 163.7157 -67.86118)
		(width 0.3048)
		(layer "B.Cu")
		(net "DDR3_M_A_VREF_CA")
	)
	(segment
		(start 162.797998 -69.114162)
		(end 162.8902 -69.02196)
		(width 0.3048)
		(layer "B.Cu")
		(net "DDR3_M_A_VREF_CA")
	)
	(segment
		(start 163.60394 -67.9196)
		(end 163.65728 -67.9196)
		(width 0.3048)
		(layer "B.Cu")
		(net "DDR3_M_A_VREF_CA")
	)
	(segment
		(start 27.720544 -53.6448)
		(end 27.295348 -53.219604)
		(width 0.2032)
		(layer "F.Cu")
		(net "VR_PVCCP_PVNN_VIN")
	)
	(segment
		(start 29.19222 -53.0352)
		(end 28.58262 -53.6448)
		(width 0.2032)
		(layer "F.Cu")
		(net "VR_PVCCP_PVNN_VIN")
	)
	(segment
		(start 28.58262 -53.6448)
		(end 27.720544 -53.6448)
		(width 0.2032)
		(layer "F.Cu")
		(net "VR_PVCCP_PVNN_VIN")
	)
	(segment
		(start 30.654498 -54.505098)
		(end 30.654498 -53.5305)
		(width 0.2032)
		(layer "F.Cu")
		(net "VR_PVCCP_PVNN_VIN")
	)
	(segment
		(start 30.654498 -53.5305)
		(end 30.6451 -53.521102)
		(width 0.2032)
		(layer "F.Cu")
		(net "VR_PVCCP_PVNN_VIN")
	)
	(segment
		(start 31.75 -54.6862)
		(end 31.6484 -54.5846)
		(width 0.2032)
		(layer "F.Cu")
		(net "VR_PVCCP_PVNN_VIN")
	)
	(segment
		(start 25.5524 -53.6448)
		(end 24.765 -54.4322)
		(width 0.2032)
		(layer "F.Cu")
		(net "VR_PVCCP_PVNN_VIN")
	)
	(segment
		(start 30.6451 -53.521102)
		(end 30.6451 -53.467)
		(width 0.2032)
		(layer "F.Cu")
		(net "VR_PVCCP_PVNN_VIN")
	)
	(segment
		(start 30.2133 -53.0352)
		(end 29.19222 -53.0352)
		(width 0.2032)
		(layer "F.Cu")
		(net "VR_PVCCP_PVNN_VIN")
	)
	(segment
		(start 30.734 -54.5846)
		(end 30.654498 -54.505098)
		(width 0.2032)
		(layer "F.Cu")
		(net "VR_PVCCP_PVNN_VIN")
	)
	(segment
		(start 24.765 -54.4322)
		(end 23.9268 -54.4322)
		(width 0.2032)
		(layer "F.Cu")
		(net "VR_PVCCP_PVNN_VIN")
	)
	(segment
		(start 23.9268 -54.4322)
		(end 23.263098 -55.095902)
		(width 0.2032)
		(layer "F.Cu")
		(net "VR_PVCCP_PVNN_VIN")
	)
	(segment
		(start 31.6484 -54.5846)
		(end 30.734 -54.5846)
		(width 0.2032)
		(layer "F.Cu")
		(net "VR_PVCCP_PVNN_VIN")
	)
	(segment
		(start 30.6451 -53.467)
		(end 30.2133 -53.0352)
		(width 0.2032)
		(layer "F.Cu")
		(net "VR_PVCCP_PVNN_VIN")
	)
	(segment
		(start 23.263098 -55.095902)
		(end 23.263098 -55.547006)
		(width 0.2032)
		(layer "F.Cu")
		(net "VR_PVCCP_PVNN_VIN")
	)
	(segment
		(start 26.870152 -53.6448)
		(end 25.5524 -53.6448)
		(width 0.2032)
		(layer "F.Cu")
		(net "VR_PVCCP_PVNN_VIN")
	)
	(segment
		(start 27.295348 -53.219604)
		(end 26.870152 -53.6448)
		(width 0.2032)
		(layer "F.Cu")
		(net "VR_PVCCP_PVNN_VIN")
	)
	(via
		(at 27.295348 -53.219604)
		(size 0.7112)
		(drill 0.3556)
		(layers "F.Cu" "B.Cu")
		(net "VR_PVCCP_PVNN_VIN")
	)
	(segment
		(start 87.766906 -39.431214)
		(end 87.39886 -39.79926)
		(width 0.1143)
		(layer "F.Cu")
		(net "CPU_UART_TXD_R")
	)
	(segment
		(start 87.838788 -39.431214)
		(end 87.766906 -39.431214)
		(width 0.1143)
		(layer "F.Cu")
		(net "CPU_UART_TXD_R")
	)
	(via
		(at 81.80705 -25.5651)
		(size 0.4318)
		(drill 0.2032)
		(layers "F.Cu" "B.Cu")
		(net "CPU_UART_TXD_R")
	)
	(via
		(at 87.39886 -39.79926)
		(size 0.4318)
		(drill 0.2032)
		(layers "F.Cu" "B.Cu")
		(net "CPU_UART_TXD_R")
	)
	(via
		(at 81.407 -26.162)
		(size 0.7112)
		(drill 0.3556)
		(layers "F.Cu" "B.Cu")
		(net "CPU_UART_TXD_R")
	)
	(segment
		(start 81.661 -25.41905)
		(end 81.80705 -25.5651)
		(width 0.1143)
		(layer "B.Cu")
		(net "CPU_UART_TXD_R")
	)
	(segment
		(start 81.80705 -25.76195)
		(end 81.407 -26.162)
		(width 0.1143)
		(layer "B.Cu")
		(net "CPU_UART_TXD_R")
	)
	(segment
		(start 81.661 -24.9428)
		(end 81.661 -25.41905)
		(width 0.1143)
		(layer "B.Cu")
		(net "CPU_UART_TXD_R")
	)
	(segment
		(start 81.80705 -25.5651)
		(end 81.80705 -25.76195)
		(width 0.1143)
		(layer "B.Cu")
		(net "CPU_UART_TXD_R")
	)
	(segment
		(start 84.965286 -36.45535)
		(end 85.68055 -36.45535)
		(width 0.0889)
		(layer "In2.Cu")
		(net "CPU_UART_TXD_R")
	)
	(segment
		(start 87.39886 -39.523924)
		(end 87.39886 -39.79926)
		(width 0.0889)
		(layer "In2.Cu")
		(net "CPU_UART_TXD_R")
	)
	(segment
		(start 83.40725 -29.35605)
		(end 84.132928 -30.081728)
		(width 0.0889)
		(layer "In2.Cu")
		(net "CPU_UART_TXD_R")
	)
	(segment
		(start 84.074 -34.324798)
		(end 84.074 -35.253422)
		(width 0.0889)
		(layer "In2.Cu")
		(net "CPU_UART_TXD_R")
	)
	(segment
		(start 84.132928 -30.081728)
		(end 84.132928 -30.869128)
		(width 0.0889)
		(layer "In2.Cu")
		(net "CPU_UART_TXD_R")
	)
	(segment
		(start 81.80705 -25.5651)
		(end 83.40725 -27.1653)
		(width 0.0889)
		(layer "In2.Cu")
		(net "CPU_UART_TXD_R")
	)
	(segment
		(start 84.132928 -30.869128)
		(end 84.582 -31.3182)
		(width 0.0889)
		(layer "In2.Cu")
		(net "CPU_UART_TXD_R")
	)
	(segment
		(start 87.07501 -37.84981)
		(end 87.07501 -39.200074)
		(width 0.0889)
		(layer "In2.Cu")
		(net "CPU_UART_TXD_R")
	)
	(segment
		(start 83.40725 -27.1653)
		(end 83.40725 -29.35605)
		(width 0.0889)
		(layer "In2.Cu")
		(net "CPU_UART_TXD_R")
	)
	(segment
		(start 84.5312 -36.021264)
		(end 84.965286 -36.45535)
		(width 0.0889)
		(layer "In2.Cu")
		(net "CPU_UART_TXD_R")
	)
	(segment
		(start 84.582 -32.166306)
		(end 84.455 -32.293306)
		(width 0.0889)
		(layer "In2.Cu")
		(net "CPU_UART_TXD_R")
	)
	(segment
		(start 84.5312 -35.710622)
		(end 84.5312 -36.021264)
		(width 0.0889)
		(layer "In2.Cu")
		(net "CPU_UART_TXD_R")
	)
	(segment
		(start 84.582 -31.3182)
		(end 84.582 -32.166306)
		(width 0.0889)
		(layer "In2.Cu")
		(net "CPU_UART_TXD_R")
	)
	(segment
		(start 84.074 -35.253422)
		(end 84.5312 -35.710622)
		(width 0.0889)
		(layer "In2.Cu")
		(net "CPU_UART_TXD_R")
	)
	(segment
		(start 84.455 -32.293306)
		(end 84.455 -33.943798)
		(width 0.0889)
		(layer "In2.Cu")
		(net "CPU_UART_TXD_R")
	)
	(segment
		(start 84.455 -33.943798)
		(end 84.074 -34.324798)
		(width 0.0889)
		(layer "In2.Cu")
		(net "CPU_UART_TXD_R")
	)
	(segment
		(start 87.07501 -39.200074)
		(end 87.39886 -39.523924)
		(width 0.0889)
		(layer "In2.Cu")
		(net "CPU_UART_TXD_R")
	)
	(segment
		(start 85.68055 -36.45535)
		(end 87.07501 -37.84981)
		(width 0.0889)
		(layer "In2.Cu")
		(net "CPU_UART_TXD_R")
	)
	(segment
		(start 28.067 -55.3212)
		(end 27.7368 -55.6514)
		(width 0.508)
		(layer "F.Cu")
		(net "VR_PVCCP_GH_R")
	)
	(segment
		(start 28.829 -55.3212)
		(end 28.067 -55.3212)
		(width 0.508)
		(layer "F.Cu")
		(net "VR_PVCCP_GH_R")
	)
	(segment
		(start 37.338 -59.944)
		(end 37.211 -60.071)
		(width 0.508)
		(layer "F.Cu")
		(net "VR_PVCCP_GH_R")
	)
	(segment
		(start 38.351206 -59.944)
		(end 37.338 -59.944)
		(width 0.508)
		(layer "F.Cu")
		(net "VR_PVCCP_GH_R")
	)
	(segment
		(start 28.6258 -56.1848)
		(end 28.829 -55.9816)
		(width 0.508)
		(layer "F.Cu")
		(net "VR_PVCCP_GH_R")
	)
	(segment
		(start 28.829 -55.9816)
		(end 28.829 -55.3212)
		(width 0.508)
		(layer "F.Cu")
		(net "VR_PVCCP_GH_R")
	)
	(via
		(at 37.211 -60.071)
		(size 0.508)
		(drill 0.254)
		(layers "F.Cu" "B.Cu")
		(net "VR_PVCCP_GH_R")
	)
	(via
		(at 37.731954 -60.591954)
		(size 0.7112)
		(drill 0.3556)
		(layers "F.Cu" "B.Cu")
		(net "VR_PVCCP_GH_R")
	)
	(via
		(at 28.6258 -56.1848)
		(size 0.508)
		(drill 0.254)
		(layers "F.Cu" "B.Cu")
		(net "VR_PVCCP_GH_R")
	)
	(segment
		(start 37.211 -60.071)
		(end 37.731954 -60.591954)
		(width 0.635)
		(layer "B.Cu")
		(net "VR_PVCCP_GH_R")
	)
	(segment
		(start 31.986982 -56.1848)
		(end 35.873182 -60.071)
		(width 0.635)
		(layer "In2.Cu")
		(net "VR_PVCCP_GH_R")
	)
	(segment
		(start 35.873182 -60.071)
		(end 37.211 -60.071)
		(width 0.635)
		(layer "In2.Cu")
		(net "VR_PVCCP_GH_R")
	)
	(segment
		(start 28.6258 -56.1848)
		(end 31.986982 -56.1848)
		(width 0.635)
		(layer "In2.Cu")
		(net "VR_PVCCP_GH_R")
	)
	(segment
		(start 156.370528 -65.9384)
		(end 156.345128 -65.9638)
		(width 0.2413)
		(layer "F.Cu")
		(net "M_A_MA2")
	)
	(segment
		(start 106.012488 -49.164494)
		(end 106.012488 -49.451514)
		(width 0.1016)
		(layer "F.Cu")
		(net "M_A_MA2")
	)
	(segment
		(start 156.250132 -62.59322)
		(end 156.250132 -63.532004)
		(width 0.2413)
		(layer "F.Cu")
		(net "M_A_MA2")
	)
	(segment
		(start 156.370528 -63.6524)
		(end 156.370528 -65.9384)
		(width 0.2413)
		(layer "F.Cu")
		(net "M_A_MA2")
	)
	(segment
		(start 156.250132 -63.532004)
		(end 156.370528 -63.6524)
		(width 0.2413)
		(layer "F.Cu")
		(net "M_A_MA2")
	)
	(segment
		(start 106.012488 -49.451514)
		(end 105.791 -49.673002)
		(width 0.1016)
		(layer "F.Cu")
		(net "M_A_MA2")
	)
	(via
		(at 156.345128 -65.9638)
		(size 0.4318)
		(drill 0.2032)
		(layers "F.Cu" "B.Cu")
		(net "M_A_MA2")
	)
	(via
		(at 105.791 -49.673002)
		(size 0.4318)
		(drill 0.2032)
		(layers "F.Cu" "B.Cu")
		(net "M_A_MA2")
	)
	(segment
		(start 156.315918 -68.975732)
		(end 156.315918 -68.572126)
		(width 0.2413)
		(layer "B.Cu")
		(net "M_A_MA2")
	)
	(segment
		(start 156.250132 -69.787262)
		(end 156.354272 -69.683122)
		(width 0.2413)
		(layer "B.Cu")
		(net "M_A_MA2")
	)
	(segment
		(start 156.354272 -69.014086)
		(end 156.315918 -68.975732)
		(width 0.2413)
		(layer "B.Cu")
		(net "M_A_MA2")
	)
	(segment
		(start 156.250132 -70.79996)
		(end 156.250132 -69.787262)
		(width 0.2413)
		(layer "B.Cu")
		(net "M_A_MA2")
	)
	(segment
		(start 156.354272 -69.683122)
		(end 156.354272 -69.014086)
		(width 0.2413)
		(layer "B.Cu")
		(net "M_A_MA2")
	)
	(segment
		(start 156.210508 -66.037206)
		(end 156.271722 -66.037206)
		(width 0.2413)
		(layer "B.Cu")
		(net "M_A_MA2")
	)
	(segment
		(start 156.315918 -68.572126)
		(end 155.84297 -68.099178)
		(width 0.2413)
		(layer "B.Cu")
		(net "M_A_MA2")
	)
	(segment
		(start 156.271722 -66.037206)
		(end 156.345128 -65.9638)
		(width 0.2413)
		(layer "B.Cu")
		(net "M_A_MA2")
	)
	(segment
		(start 155.84297 -68.099178)
		(end 155.84297 -66.404744)
		(width 0.2413)
		(layer "B.Cu")
		(net "M_A_MA2")
	)
	(segment
		(start 155.84297 -66.404744)
		(end 156.210508 -66.037206)
		(width 0.2413)
		(layer "B.Cu")
		(net "M_A_MA2")
	)
	(segment
		(start 135.504936 -55.95874)
		(end 145.21434 -55.95874)
		(width 0.1905)
		(layer "In9.Cu")
		(net "M_A_MA2")
	)
	(segment
		(start 153.47442 -65.56502)
		(end 153.8732 -65.9638)
		(width 0.1905)
		(layer "In9.Cu")
		(net "M_A_MA2")
	)
	(segment
		(start 153.8732 -66.33464)
		(end 155.1432 -67.60464)
		(width 0.1905)
		(layer "In9.Cu")
		(net "M_A_MA2")
	)
	(segment
		(start 150.908004 -60.312554)
		(end 150.908258 -60.312554)
		(width 0.1905)
		(layer "In9.Cu")
		(net "M_A_MA2")
	)
	(segment
		(start 155.517088 -67.60464)
		(end 155.86837 -67.253358)
		(width 0.1905)
		(layer "In9.Cu")
		(net "M_A_MA2")
	)
	(segment
		(start 106.0069 -50.114454)
		(end 106.553 -50.660554)
		(width 0.1016)
		(layer "In9.Cu")
		(net "M_A_MA2")
	)
	(segment
		(start 134.411974 -55.87365)
		(end 134.792974 -56.25465)
		(width 0.1905)
		(layer "In9.Cu")
		(net "M_A_MA2")
	)
	(segment
		(start 155.1432 -67.60464)
		(end 155.517088 -67.60464)
		(width 0.1905)
		(layer "In9.Cu")
		(net "M_A_MA2")
	)
	(segment
		(start 153.8732 -65.9638)
		(end 153.8732 -66.33464)
		(width 0.1905)
		(layer "In9.Cu")
		(net "M_A_MA2")
	)
	(segment
		(start 106.553 -50.660554)
		(end 106.553 -52.46751)
		(width 0.1016)
		(layer "In9.Cu")
		(net "M_A_MA2")
	)
	(segment
		(start 110.05185 -55.87365)
		(end 134.411974 -55.87365)
		(width 0.1905)
		(layer "In9.Cu")
		(net "M_A_MA2")
	)
	(segment
		(start 150.908258 -60.312554)
		(end 151.4602 -60.864496)
		(width 0.1905)
		(layer "In9.Cu")
		(net "M_A_MA2")
	)
	(segment
		(start 107.876086 -53.790596)
		(end 107.977686 -53.790596)
		(width 0.1016)
		(layer "In9.Cu")
		(net "M_A_MA2")
	)
	(segment
		(start 152.7429 -65.20434)
		(end 153.10358 -65.56502)
		(width 0.1905)
		(layer "In9.Cu")
		(net "M_A_MA2")
	)
	(segment
		(start 147.628864 -58.373518)
		(end 148.969222 -58.373518)
		(width 0.1905)
		(layer "In9.Cu")
		(net "M_A_MA2")
	)
	(segment
		(start 135.209026 -56.25465)
		(end 135.504936 -55.95874)
		(width 0.1905)
		(layer "In9.Cu")
		(net "M_A_MA2")
	)
	(segment
		(start 156.297122 -66.011806)
		(end 156.345128 -65.9638)
		(width 0.1905)
		(layer "In9.Cu")
		(net "M_A_MA2")
	)
	(segment
		(start 151.4602 -60.864496)
		(end 151.4602 -61.1632)
		(width 0.1905)
		(layer "In9.Cu")
		(net "M_A_MA2")
	)
	(segment
		(start 134.792974 -56.25465)
		(end 135.209026 -56.25465)
		(width 0.1905)
		(layer "In9.Cu")
		(net "M_A_MA2")
	)
	(segment
		(start 107.977686 -53.790596)
		(end 108.4834 -54.29631)
		(width 0.1016)
		(layer "In9.Cu")
		(net "M_A_MA2")
	)
	(segment
		(start 155.86837 -66.415158)
		(end 156.271722 -66.011806)
		(width 0.1905)
		(layer "In9.Cu")
		(net "M_A_MA2")
	)
	(segment
		(start 151.4602 -61.1632)
		(end 152.7429 -62.4459)
		(width 0.1905)
		(layer "In9.Cu")
		(net "M_A_MA2")
	)
	(segment
		(start 108.4834 -54.29631)
		(end 108.4834 -54.3052)
		(width 0.1016)
		(layer "In9.Cu")
		(net "M_A_MA2")
	)
	(segment
		(start 156.271722 -66.011806)
		(end 156.297122 -66.011806)
		(width 0.1905)
		(layer "In9.Cu")
		(net "M_A_MA2")
	)
	(segment
		(start 152.7429 -62.4459)
		(end 152.7429 -65.20434)
		(width 0.1905)
		(layer "In9.Cu")
		(net "M_A_MA2")
	)
	(segment
		(start 150.285958 -59.690254)
		(end 150.285958 -59.690508)
		(width 0.1905)
		(layer "In9.Cu")
		(net "M_A_MA2")
	)
	(segment
		(start 147.264628 -58.009282)
		(end 147.628864 -58.373518)
		(width 0.1905)
		(layer "In9.Cu")
		(net "M_A_MA2")
	)
	(segment
		(start 145.21434 -55.95874)
		(end 147.264628 -58.009028)
		(width 0.1905)
		(layer "In9.Cu")
		(net "M_A_MA2")
	)
	(segment
		(start 106.0069 -49.888902)
		(end 106.0069 -50.114454)
		(width 0.1016)
		(layer "In9.Cu")
		(net "M_A_MA2")
	)
	(segment
		(start 108.4834 -54.3052)
		(end 110.05185 -55.87365)
		(width 0.1905)
		(layer "In9.Cu")
		(net "M_A_MA2")
	)
	(segment
		(start 153.10358 -65.56502)
		(end 153.47442 -65.56502)
		(width 0.1905)
		(layer "In9.Cu")
		(net "M_A_MA2")
	)
	(segment
		(start 147.264628 -58.009028)
		(end 147.264628 -58.009282)
		(width 0.1905)
		(layer "In9.Cu")
		(net "M_A_MA2")
	)
	(segment
		(start 148.969222 -58.373518)
		(end 150.285958 -59.690254)
		(width 0.1905)
		(layer "In9.Cu")
		(net "M_A_MA2")
	)
	(segment
		(start 155.86837 -67.253358)
		(end 155.86837 -66.415158)
		(width 0.1905)
		(layer "In9.Cu")
		(net "M_A_MA2")
	)
	(segment
		(start 105.791 -49.673002)
		(end 106.0069 -49.888902)
		(width 0.1016)
		(layer "In9.Cu")
		(net "M_A_MA2")
	)
	(segment
		(start 150.285958 -59.690508)
		(end 150.908004 -60.312554)
		(width 0.1905)
		(layer "In9.Cu")
		(net "M_A_MA2")
	)
	(segment
		(start 106.553 -52.46751)
		(end 107.876086 -53.790596)
		(width 0.1016)
		(layer "In9.Cu")
		(net "M_A_MA2")
	)
	(segment
		(start 50.8 -46.7868)
		(end 50.8 -46.863)
		(width 0.254)
		(layer "F.Cu")
		(net "P1V0_STBY_PG")
	)
	(segment
		(start 55.57393 -51.557936)
		(end 54.707536 -51.557936)
		(width 0.254)
		(layer "F.Cu")
		(net "P1V0_STBY_PG")
	)
	(segment
		(start 51.386994 -47.449994)
		(end 51.501294 -47.449994)
		(width 0.254)
		(layer "F.Cu")
		(net "P1V0_STBY_PG")
	)
	(segment
		(start 50.8 -46.863)
		(end 51.386994 -47.449994)
		(width 0.254)
		(layer "F.Cu")
		(net "P1V0_STBY_PG")
	)
	(via
		(at 51.501294 -47.449994)
		(size 0.508)
		(drill 0.254)
		(layers "F.Cu" "B.Cu")
		(net "P1V0_STBY_PG")
	)
	(via
		(at 54.707536 -51.557936)
		(size 0.508)
		(drill 0.254)
		(layers "F.Cu" "B.Cu")
		(net "P1V0_STBY_PG")
	)
	(via
		(at 51.308 -46.499272)
		(size 0.7112)
		(drill 0.3556)
		(layers "F.Cu" "B.Cu")
		(net "P1V0_STBY_PG")
	)
	(segment
		(start 51.308 -46.499272)
		(end 51.501294 -46.692566)
		(width 0.254)
		(layer "B.Cu")
		(net "P1V0_STBY_PG")
	)
	(segment
		(start 54.6608 -51.604672)
		(end 54.707536 -51.557936)
		(width 0.254)
		(layer "B.Cu")
		(net "P1V0_STBY_PG")
	)
	(segment
		(start 54.6608 -52.451)
		(end 54.6608 -51.604672)
		(width 0.254)
		(layer "B.Cu")
		(net "P1V0_STBY_PG")
	)
	(segment
		(start 51.501294 -46.692566)
		(end 51.501294 -47.449994)
		(width 0.254)
		(layer "B.Cu")
		(net "P1V0_STBY_PG")
	)
	(segment
		(start 52.197 -49.0474)
		(end 54.707536 -51.557936)
		(width 0.254)
		(layer "In9.Cu")
		(net "P1V0_STBY_PG")
	)
	(segment
		(start 51.501294 -47.449994)
		(end 51.501294 -47.851314)
		(width 0.254)
		(layer "In9.Cu")
		(net "P1V0_STBY_PG")
	)
	(segment
		(start 51.501294 -47.851314)
		(end 52.197 -48.54702)
		(width 0.254)
		(layer "In9.Cu")
		(net "P1V0_STBY_PG")
	)
	(segment
		(start 52.197 -48.54702)
		(end 52.197 -49.0474)
		(width 0.254)
		(layer "In9.Cu")
		(net "P1V0_STBY_PG")
	)
	(segment
		(start 25.654 -63.1698)
		(end 26.6192 -63.1698)
		(width 0.508)
		(layer "F.Cu")
		(net "VR_PVNN_LH_R")
	)
	(segment
		(start 33.401 -69.215)
		(end 33.7312 -68.8848)
		(width 0.508)
		(layer "F.Cu")
		(net "VR_PVNN_LH_R")
	)
	(segment
		(start 33.7312 -68.326)
		(end 33.772094 -68.285106)
		(width 0.4064)
		(layer "F.Cu")
		(net "VR_PVNN_LH_R")
	)
	(segment
		(start 32.766 -68.072)
		(end 32.766 -68.58)
		(width 0.508)
		(layer "F.Cu")
		(net "VR_PVNN_LH_R")
	)
	(segment
		(start 33.772094 -68.285106)
		(end 33.772094 -67.183)
		(width 0.4064)
		(layer "F.Cu")
		(net "VR_PVNN_LH_R")
	)
	(segment
		(start 32.766 -68.58)
		(end 33.401 -69.215)
		(width 0.508)
		(layer "F.Cu")
		(net "VR_PVNN_LH_R")
	)
	(segment
		(start 26.6192 -63.1698)
		(end 26.6446 -63.1952)
		(width 0.508)
		(layer "F.Cu")
		(net "VR_PVNN_LH_R")
	)
	(segment
		(start 33.7312 -68.8848)
		(end 33.7312 -68.326)
		(width 0.508)
		(layer "F.Cu")
		(net "VR_PVNN_LH_R")
	)
	(via
		(at 32.766 -68.072)
		(size 0.7112)
		(drill 0.4064)
		(layers "F.Cu" "B.Cu")
		(net "VR_PVNN_LH_R")
	)
	(via
		(at 33.401 -69.215)
		(size 0.7112)
		(drill 0.3556)
		(layers "F.Cu" "B.Cu")
		(net "VR_PVNN_LH_R")
	)
	(via
		(at 26.6446 -63.1952)
		(size 0.508)
		(drill 0.254)
		(layers "F.Cu" "B.Cu")
		(net "VR_PVNN_LH_R")
	)
	(segment
		(start 27.0256 -63.5762)
		(end 27.0256 -67.183)
		(width 0.508)
		(layer "In2.Cu")
		(net "VR_PVNN_LH_R")
	)
	(segment
		(start 27.0256 -67.183)
		(end 28.8036 -68.961)
		(width 0.508)
		(layer "In2.Cu")
		(net "VR_PVNN_LH_R")
	)
	(segment
		(start 26.6446 -63.1952)
		(end 27.0256 -63.5762)
		(width 0.508)
		(layer "In2.Cu")
		(net "VR_PVNN_LH_R")
	)
	(segment
		(start 31.877 -68.961)
		(end 32.766 -68.072)
		(width 0.508)
		(layer "In2.Cu")
		(net "VR_PVNN_LH_R")
	)
	(segment
		(start 28.8036 -68.961)
		(end 31.877 -68.961)
		(width 0.508)
		(layer "In2.Cu")
		(net "VR_PVNN_LH_R")
	)
	(segment
		(start 111.627158 -46.381924)
		(end 111.488728 -46.520354)
		(width 0.1016)
		(layer "F.Cu")
		(net "M_A_DQS_DP8")
	)
	(segment
		(start 164.95014 -70.053708)
		(end 165.097714 -69.906134)
		(width 0.1778)
		(layer "F.Cu")
		(net "M_A_DQS_DP8")
	)
	(segment
		(start 164.95014 -70.806564)
		(end 164.95014 -70.053708)
		(width 0.1778)
		(layer "F.Cu")
		(net "M_A_DQS_DP8")
	)
	(segment
		(start 112.428528 -47.027084)
		(end 112.428528 -46.701456)
		(width 0.1016)
		(layer "F.Cu")
		(net "M_A_DQS_DP8")
	)
	(segment
		(start 112.428528 -46.701456)
		(end 112.108996 -46.381924)
		(width 0.1016)
		(layer "F.Cu")
		(net "M_A_DQS_DP8")
	)
	(segment
		(start 116.4844 -49.5554)
		(end 114.956844 -49.5554)
		(width 0.1016)
		(layer "F.Cu")
		(net "M_A_DQS_DP8")
	)
	(segment
		(start 165.097714 -66.937128)
		(end 164.832792 -66.672206)
		(width 0.1778)
		(layer "F.Cu")
		(net "M_A_DQS_DP8")
	)
	(segment
		(start 165.097714 -69.906134)
		(end 165.097714 -66.937128)
		(width 0.1778)
		(layer "F.Cu")
		(net "M_A_DQS_DP8")
	)
	(segment
		(start 116.9416 -49.0982)
		(end 116.4844 -49.5554)
		(width 0.1016)
		(layer "F.Cu")
		(net "M_A_DQS_DP8")
	)
	(segment
		(start 114.956844 -49.5554)
		(end 112.428528 -47.027084)
		(width 0.1016)
		(layer "F.Cu")
		(net "M_A_DQS_DP8")
	)
	(segment
		(start 112.108996 -46.381924)
		(end 111.627158 -46.381924)
		(width 0.1016)
		(layer "F.Cu")
		(net "M_A_DQS_DP8")
	)
	(via
		(at 164.832792 -66.672206)
		(size 0.4318)
		(drill 0.2032)
		(layers "F.Cu" "B.Cu")
		(net "M_A_DQS_DP8")
	)
	(via
		(at 116.9416 -49.0982)
		(size 0.4318)
		(drill 0.2032)
		(layers "F.Cu" "B.Cu")
		(net "M_A_DQS_DP8")
	)
	(segment
		(start 165.097714 -63.83655)
		(end 165.097714 -66.407284)
		(width 0.1778)
		(layer "B.Cu")
		(net "M_A_DQS_DP8")
	)
	(segment
		(start 164.95014 -63.688976)
		(end 165.097714 -63.83655)
		(width 0.1778)
		(layer "B.Cu")
		(net "M_A_DQS_DP8")
	)
	(segment
		(start 164.95014 -62.599824)
		(end 164.95014 -63.688976)
		(width 0.1778)
		(layer "B.Cu")
		(net "M_A_DQS_DP8")
	)
	(segment
		(start 165.097714 -66.407284)
		(end 164.832792 -66.672206)
		(width 0.1778)
		(layer "B.Cu")
		(net "M_A_DQS_DP8")
	)
	(segment
		(start 161.442908 -56.492394)
		(end 161.11982 -56.169306)
		(width 0.1524)
		(layer "In2.Cu")
		(net "M_A_DQS_DP8")
	)
	(segment
		(start 162.764978 -57.814464)
		(end 162.588956 -57.814464)
		(width 0.1524)
		(layer "In2.Cu")
		(net "M_A_DQS_DP8")
	)
	(segment
		(start 165.098222 -65.733676)
		(end 166.58844 -64.243458)
		(width 0.1524)
		(layer "In2.Cu")
		(net "M_A_DQS_DP8")
	)
	(segment
		(start 151.103076 -55.72506)
		(end 150.645876 -55.72506)
		(width 0.1524)
		(layer "In2.Cu")
		(net "M_A_DQS_DP8")
	)
	(segment
		(start 117.692424 -48.898048)
		(end 117.141752 -48.898048)
		(width 0.1016)
		(layer "In2.Cu")
		(net "M_A_DQS_DP8")
	)
	(segment
		(start 161.11982 -56.169306)
		(end 160.943798 -56.169306)
		(width 0.1524)
		(layer "In2.Cu")
		(net "M_A_DQS_DP8")
	)
	(segment
		(start 165.642036 -60.867544)
		(end 165.318694 -60.544202)
		(width 0.1524)
		(layer "In2.Cu")
		(net "M_A_DQS_DP8")
	)
	(segment
		(start 148.319236 -55.72506)
		(end 148.194776 -55.6006)
		(width 0.1524)
		(layer "In2.Cu")
		(net "M_A_DQS_DP8")
	)
	(segment
		(start 148.194776 -55.6006)
		(end 147.737576 -55.6006)
		(width 0.1524)
		(layer "In2.Cu")
		(net "M_A_DQS_DP8")
	)
	(segment
		(start 164.1729 -59.222386)
		(end 163.996878 -59.222386)
		(width 0.1524)
		(layer "In2.Cu")
		(net "M_A_DQS_DP8")
	)
	(segment
		(start 117.141752 -48.898048)
		(end 116.9416 -49.0982)
		(width 0.1016)
		(layer "In2.Cu")
		(net "M_A_DQS_DP8")
	)
	(segment
		(start 164.832792 -66.672206)
		(end 165.098222 -66.406776)
		(width 0.1524)
		(layer "In2.Cu")
		(net "M_A_DQS_DP8")
	)
	(segment
		(start 162.265614 -57.491122)
		(end 162.265614 -57.3151)
		(width 0.1524)
		(layer "In2.Cu")
		(net "M_A_DQS_DP8")
	)
	(segment
		(start 160.620456 -55.669942)
		(end 160.297114 -55.3466)
		(width 0.1524)
		(layer "In2.Cu")
		(net "M_A_DQS_DP8")
	)
	(segment
		(start 163.673536 -58.899044)
		(end 163.673536 -58.723022)
		(width 0.1524)
		(layer "In2.Cu")
		(net "M_A_DQS_DP8")
	)
	(segment
		(start 166.58844 -63.483744)
		(end 166.1414 -63.036704)
		(width 0.1524)
		(layer "In2.Cu")
		(net "M_A_DQS_DP8")
	)
	(segment
		(start 150.064216 -55.6006)
		(end 149.939756 -55.72506)
		(width 0.1524)
		(layer "In2.Cu")
		(net "M_A_DQS_DP8")
	)
	(segment
		(start 146.642074 -51.150266)
		(end 145.926048 -51.866546)
		(width 0.1524)
		(layer "In2.Cu")
		(net "M_A_DQS_DP8")
	)
	(segment
		(start 164.496242 -59.72175)
		(end 164.496242 -59.545728)
		(width 0.1524)
		(layer "In2.Cu")
		(net "M_A_DQS_DP8")
	)
	(segment
		(start 152.284176 -55.6006)
		(end 151.227536 -55.6006)
		(width 0.1524)
		(layer "In2.Cu")
		(net "M_A_DQS_DP8")
	)
	(segment
		(start 118.874032 -50.079656)
		(end 117.692424 -48.898048)
		(width 0.1016)
		(layer "In2.Cu")
		(net "M_A_DQS_DP8")
	)
	(segment
		(start 147.32 -53.707538)
		(end 146.357594 -52.745132)
		(width 0.1524)
		(layer "In2.Cu")
		(net "M_A_DQS_DP8")
	)
	(segment
		(start 150.645876 -55.72506)
		(end 150.521416 -55.6006)
		(width 0.1524)
		(layer "In2.Cu")
		(net "M_A_DQS_DP8")
	)
	(segment
		(start 145.479008 -51.866546)
		(end 143.692118 -50.079656)
		(width 0.1524)
		(layer "In2.Cu")
		(net "M_A_DQS_DP8")
	)
	(segment
		(start 147.737576 -55.6006)
		(end 147.32 -55.183024)
		(width 0.1524)
		(layer "In2.Cu")
		(net "M_A_DQS_DP8")
	)
	(segment
		(start 162.265614 -57.3151)
		(end 161.942272 -56.991758)
		(width 0.1524)
		(layer "In2.Cu")
		(net "M_A_DQS_DP8")
	)
	(segment
		(start 165.318694 -60.544202)
		(end 165.318694 -60.36818)
		(width 0.1524)
		(layer "In2.Cu")
		(net "M_A_DQS_DP8")
	)
	(segment
		(start 149.358096 -55.6006)
		(end 148.900896 -55.6006)
		(width 0.1524)
		(layer "In2.Cu")
		(net "M_A_DQS_DP8")
	)
	(segment
		(start 165.098222 -66.406776)
		(end 165.098222 -65.733676)
		(width 0.1524)
		(layer "In2.Cu")
		(net "M_A_DQS_DP8")
	)
	(segment
		(start 165.318694 -60.36818)
		(end 164.995606 -60.045092)
		(width 0.1524)
		(layer "In2.Cu")
		(net "M_A_DQS_DP8")
	)
	(segment
		(start 152.474676 -55.7911)
		(end 152.284176 -55.6006)
		(width 0.1524)
		(layer "In2.Cu")
		(net "M_A_DQS_DP8")
	)
	(segment
		(start 151.227536 -55.6006)
		(end 151.103076 -55.72506)
		(width 0.1524)
		(layer "In2.Cu")
		(net "M_A_DQS_DP8")
	)
	(segment
		(start 164.496242 -59.545728)
		(end 164.1729 -59.222386)
		(width 0.1524)
		(layer "In2.Cu")
		(net "M_A_DQS_DP8")
	)
	(segment
		(start 160.620456 -55.845964)
		(end 160.620456 -55.669942)
		(width 0.1524)
		(layer "In2.Cu")
		(net "M_A_DQS_DP8")
	)
	(segment
		(start 166.1414 -61.190886)
		(end 165.818058 -60.867544)
		(width 0.1524)
		(layer "In2.Cu")
		(net "M_A_DQS_DP8")
	)
	(segment
		(start 143.692118 -50.079656)
		(end 118.874032 -50.079656)
		(width 0.1524)
		(layer "In2.Cu")
		(net "M_A_DQS_DP8")
	)
	(segment
		(start 148.776436 -55.72506)
		(end 148.319236 -55.72506)
		(width 0.1524)
		(layer "In2.Cu")
		(net "M_A_DQS_DP8")
	)
	(segment
		(start 160.943798 -56.169306)
		(end 160.620456 -55.845964)
		(width 0.1524)
		(layer "In2.Cu")
		(net "M_A_DQS_DP8")
	)
	(segment
		(start 149.482556 -55.72506)
		(end 149.358096 -55.6006)
		(width 0.1524)
		(layer "In2.Cu")
		(net "M_A_DQS_DP8")
	)
	(segment
		(start 147.07362 -51.581812)
		(end 147.07362 -51.36642)
		(width 0.1524)
		(layer "In2.Cu")
		(net "M_A_DQS_DP8")
	)
	(segment
		(start 148.900896 -55.6006)
		(end 148.776436 -55.72506)
		(width 0.1524)
		(layer "In2.Cu")
		(net "M_A_DQS_DP8")
	)
	(segment
		(start 161.76625 -56.991758)
		(end 161.442908 -56.668416)
		(width 0.1524)
		(layer "In2.Cu")
		(net "M_A_DQS_DP8")
	)
	(segment
		(start 146.357594 -52.298092)
		(end 147.07362 -51.581812)
		(width 0.1524)
		(layer "In2.Cu")
		(net "M_A_DQS_DP8")
	)
	(segment
		(start 165.818058 -60.867544)
		(end 165.642036 -60.867544)
		(width 0.1524)
		(layer "In2.Cu")
		(net "M_A_DQS_DP8")
	)
	(segment
		(start 162.588956 -57.814464)
		(end 162.265614 -57.491122)
		(width 0.1524)
		(layer "In2.Cu")
		(net "M_A_DQS_DP8")
	)
	(segment
		(start 145.926048 -51.866546)
		(end 145.479008 -51.866546)
		(width 0.1524)
		(layer "In2.Cu")
		(net "M_A_DQS_DP8")
	)
	(segment
		(start 161.942272 -56.991758)
		(end 161.76625 -56.991758)
		(width 0.1524)
		(layer "In2.Cu")
		(net "M_A_DQS_DP8")
	)
	(segment
		(start 154.237436 -55.3466)
		(end 153.792936 -55.7911)
		(width 0.1524)
		(layer "In2.Cu")
		(net "M_A_DQS_DP8")
	)
	(segment
		(start 147.07362 -51.36642)
		(end 146.857466 -51.150266)
		(width 0.1524)
		(layer "In2.Cu")
		(net "M_A_DQS_DP8")
	)
	(segment
		(start 164.995606 -60.045092)
		(end 164.819584 -60.045092)
		(width 0.1524)
		(layer "In2.Cu")
		(net "M_A_DQS_DP8")
	)
	(segment
		(start 166.1414 -63.036704)
		(end 166.1414 -61.190886)
		(width 0.1524)
		(layer "In2.Cu")
		(net "M_A_DQS_DP8")
	)
	(segment
		(start 150.521416 -55.6006)
		(end 150.064216 -55.6006)
		(width 0.1524)
		(layer "In2.Cu")
		(net "M_A_DQS_DP8")
	)
	(segment
		(start 163.673536 -58.723022)
		(end 162.764978 -57.814464)
		(width 0.1524)
		(layer "In2.Cu")
		(net "M_A_DQS_DP8")
	)
	(segment
		(start 160.297114 -55.3466)
		(end 154.237436 -55.3466)
		(width 0.1524)
		(layer "In2.Cu")
		(net "M_A_DQS_DP8")
	)
	(segment
		(start 149.939756 -55.72506)
		(end 149.482556 -55.72506)
		(width 0.1524)
		(layer "In2.Cu")
		(net "M_A_DQS_DP8")
	)
	(segment
		(start 161.442908 -56.668416)
		(end 161.442908 -56.492394)
		(width 0.1524)
		(layer "In2.Cu")
		(net "M_A_DQS_DP8")
	)
	(segment
		(start 163.996878 -59.222386)
		(end 163.673536 -58.899044)
		(width 0.1524)
		(layer "In2.Cu")
		(net "M_A_DQS_DP8")
	)
	(segment
		(start 166.58844 -64.243458)
		(end 166.58844 -63.483744)
		(width 0.1524)
		(layer "In2.Cu")
		(net "M_A_DQS_DP8")
	)
	(segment
		(start 147.32 -55.183024)
		(end 147.32 -53.707538)
		(width 0.1524)
		(layer "In2.Cu")
		(net "M_A_DQS_DP8")
	)
	(segment
		(start 146.357594 -52.745132)
		(end 146.357594 -52.298092)
		(width 0.1524)
		(layer "In2.Cu")
		(net "M_A_DQS_DP8")
	)
	(segment
		(start 146.857466 -51.150266)
		(end 146.642074 -51.150266)
		(width 0.1524)
		(layer "In2.Cu")
		(net "M_A_DQS_DP8")
	)
	(segment
		(start 164.819584 -60.045092)
		(end 164.496242 -59.72175)
		(width 0.1524)
		(layer "In2.Cu")
		(net "M_A_DQS_DP8")
	)
	(segment
		(start 153.792936 -55.7911)
		(end 152.474676 -55.7911)
		(width 0.1524)
		(layer "In2.Cu")
		(net "M_A_DQS_DP8")
	)
	(segment
		(start 102.403148 -16.3703)
		(end 104.9528 -16.3703)
		(width 0.1143)
		(layer "F.Cu")
		(net "LPC_CPU_LAD1")
	)
	(segment
		(start 88.44534 -20.044156)
		(end 88.814148 -19.675348)
		(width 0.1143)
		(layer "F.Cu")
		(net "LPC_CPU_LAD1")
	)
	(segment
		(start 97.79 -17.7927)
		(end 100.980748 -17.7927)
		(width 0.1143)
		(layer "F.Cu")
		(net "LPC_CPU_LAD1")
	)
	(segment
		(start 82.2833 -21.5138)
		(end 82.3849 -21.4122)
		(width 0.1143)
		(layer "F.Cu")
		(net "LPC_CPU_LAD1")
	)
	(segment
		(start 114.858546 -17.596358)
		(end 113.632488 -16.3703)
		(width 0.1143)
		(layer "F.Cu")
		(net "LPC_CPU_LAD1")
	)
	(segment
		(start 81.0133 -21.7424)
		(end 81.1149 -21.844)
		(width 0.1143)
		(layer "F.Cu")
		(net "LPC_CPU_LAD1")
	)
	(segment
		(start 82.3849 -20.5486)
		(end 82.63001 -20.30349)
		(width 0.1143)
		(layer "F.Cu")
		(net "LPC_CPU_LAD1")
	)
	(segment
		(start 81.4705 -21.7424)
		(end 81.4705 -20.5486)
		(width 0.1143)
		(layer "F.Cu")
		(net "LPC_CPU_LAD1")
	)
	(segment
		(start 90.76055 -19.45005)
		(end 92.69095 -19.45005)
		(width 0.1143)
		(layer "F.Cu")
		(net "LPC_CPU_LAD1")
	)
	(segment
		(start 113.632488 -16.3703)
		(end 104.9528 -16.3703)
		(width 0.1143)
		(layer "F.Cu")
		(net "LPC_CPU_LAD1")
	)
	(segment
		(start 89.6874 -20.044156)
		(end 90.166444 -20.044156)
		(width 0.1143)
		(layer "F.Cu")
		(net "LPC_CPU_LAD1")
	)
	(segment
		(start 80.680814 -22.235414)
		(end 80.3783 -21.9329)
		(width 0.1143)
		(layer "F.Cu")
		(net "LPC_CPU_LAD1")
	)
	(segment
		(start 90.166444 -20.044156)
		(end 90.76055 -19.45005)
		(width 0.1143)
		(layer "F.Cu")
		(net "LPC_CPU_LAD1")
	)
	(segment
		(start 92.69095 -19.45005)
		(end 93.599 -18.542)
		(width 0.1143)
		(layer "F.Cu")
		(net "LPC_CPU_LAD1")
	)
	(segment
		(start 81.9277 -20.5486)
		(end 81.9277 -21.4122)
		(width 0.1143)
		(layer "F.Cu")
		(net "LPC_CPU_LAD1")
	)
	(segment
		(start 86.350602 -20.044156)
		(end 88.44534 -20.044156)
		(width 0.1143)
		(layer "F.Cu")
		(net "LPC_CPU_LAD1")
	)
	(segment
		(start 80.899 -20.4343)
		(end 81.0133 -20.5486)
		(width 0.1143)
		(layer "F.Cu")
		(net "LPC_CPU_LAD1")
	)
	(segment
		(start 88.814148 -19.675348)
		(end 89.318592 -19.675348)
		(width 0.1143)
		(layer "F.Cu")
		(net "LPC_CPU_LAD1")
	)
	(segment
		(start 81.8134 -20.4343)
		(end 81.9277 -20.5486)
		(width 0.1143)
		(layer "F.Cu")
		(net "LPC_CPU_LAD1")
	)
	(segment
		(start 81.9277 -21.4122)
		(end 82.0293 -21.5138)
		(width 0.1143)
		(layer "F.Cu")
		(net "LPC_CPU_LAD1")
	)
	(segment
		(start 80.3783 -20.5359)
		(end 80.4799 -20.4343)
		(width 0.1143)
		(layer "F.Cu")
		(net "LPC_CPU_LAD1")
	)
	(segment
		(start 80.3783 -21.9329)
		(end 80.3783 -20.5359)
		(width 0.1143)
		(layer "F.Cu")
		(net "LPC_CPU_LAD1")
	)
	(segment
		(start 82.0293 -21.5138)
		(end 82.2833 -21.5138)
		(width 0.1143)
		(layer "F.Cu")
		(net "LPC_CPU_LAD1")
	)
	(segment
		(start 114.858546 -23.57501)
		(end 114.858546 -17.596358)
		(width 0.1143)
		(layer "F.Cu")
		(net "LPC_CPU_LAD1")
	)
	(segment
		(start 81.4705 -20.5486)
		(end 81.5848 -20.4343)
		(width 0.1143)
		(layer "F.Cu")
		(net "LPC_CPU_LAD1")
	)
	(segment
		(start 81.3689 -21.844)
		(end 81.4705 -21.7424)
		(width 0.1143)
		(layer "F.Cu")
		(net "LPC_CPU_LAD1")
	)
	(segment
		(start 85.585046 -41.766236)
		(end 85.5472 -41.766236)
		(width 0.1143)
		(layer "F.Cu")
		(net "LPC_CPU_LAD1")
	)
	(segment
		(start 86.091268 -20.30349)
		(end 86.350602 -20.044156)
		(width 0.1143)
		(layer "F.Cu")
		(net "LPC_CPU_LAD1")
	)
	(segment
		(start 97.0407 -18.542)
		(end 97.79 -17.7927)
		(width 0.1143)
		(layer "F.Cu")
		(net "LPC_CPU_LAD1")
	)
	(segment
		(start 82.63001 -20.30349)
		(end 86.091268 -20.30349)
		(width 0.1143)
		(layer "F.Cu")
		(net "LPC_CPU_LAD1")
	)
	(segment
		(start 82.3849 -21.4122)
		(end 82.3849 -20.5486)
		(width 0.1143)
		(layer "F.Cu")
		(net "LPC_CPU_LAD1")
	)
	(segment
		(start 80.680814 -23.102824)
		(end 80.680814 -22.235414)
		(width 0.1143)
		(layer "F.Cu")
		(net "LPC_CPU_LAD1")
	)
	(segment
		(start 81.0133 -20.5486)
		(end 81.0133 -21.7424)
		(width 0.1143)
		(layer "F.Cu")
		(net "LPC_CPU_LAD1")
	)
	(segment
		(start 80.4799 -20.4343)
		(end 80.899 -20.4343)
		(width 0.1143)
		(layer "F.Cu")
		(net "LPC_CPU_LAD1")
	)
	(segment
		(start 127.7112 -36.068)
		(end 127.351536 -36.068)
		(width 0.1143)
		(layer "F.Cu")
		(net "LPC_CPU_LAD1")
	)
	(segment
		(start 127.351536 -36.068)
		(end 114.858546 -23.57501)
		(width 0.1143)
		(layer "F.Cu")
		(net "LPC_CPU_LAD1")
	)
	(segment
		(start 81.1149 -21.844)
		(end 81.3689 -21.844)
		(width 0.1143)
		(layer "F.Cu")
		(net "LPC_CPU_LAD1")
	)
	(segment
		(start 93.599 -18.542)
		(end 97.0407 -18.542)
		(width 0.1143)
		(layer "F.Cu")
		(net "LPC_CPU_LAD1")
	)
	(segment
		(start 81.5848 -20.4343)
		(end 81.8134 -20.4343)
		(width 0.1143)
		(layer "F.Cu")
		(net "LPC_CPU_LAD1")
	)
	(segment
		(start 89.318592 -19.675348)
		(end 89.6874 -20.044156)
		(width 0.1143)
		(layer "F.Cu")
		(net "LPC_CPU_LAD1")
	)
	(segment
		(start 85.933788 -41.417494)
		(end 85.585046 -41.766236)
		(width 0.1143)
		(layer "F.Cu")
		(net "LPC_CPU_LAD1")
	)
	(segment
		(start 100.980748 -17.7927)
		(end 102.403148 -16.3703)
		(width 0.1143)
		(layer "F.Cu")
		(net "LPC_CPU_LAD1")
	)
	(via
		(at 85.5472 -41.766236)
		(size 0.4318)
		(drill 0.2032)
		(layers "F.Cu" "B.Cu")
		(net "LPC_CPU_LAD1")
	)
	(via
		(at 80.680814 -23.102824)
		(size 0.4318)
		(drill 0.2032)
		(layers "F.Cu" "B.Cu")
		(net "LPC_CPU_LAD1")
	)
	(via
		(at 104.9528 -16.3703)
		(size 0.7112)
		(drill 0.3556)
		(layers "F.Cu" "B.Cu")
		(net "LPC_CPU_LAD1")
	)
	(segment
		(start 78.8924 -31.7754)
		(end 79.0702 -31.5976)
		(width 0.0889)
		(layer "In9.Cu")
		(net "LPC_CPU_LAD1")
	)
	(segment
		(start 80.01 -40.894)
		(end 80.01 -38.227)
		(width 0.0889)
		(layer "In9.Cu")
		(net "LPC_CPU_LAD1")
	)
	(segment
		(start 80.0608 -29.5402)
		(end 80.0608 -29.083)
		(width 0.0889)
		(layer "In9.Cu")
		(net "LPC_CPU_LAD1")
	)
	(segment
		(start 83.620102 -42.12209)
		(end 83.620102 -41.6179)
		(width 0.0889)
		(layer "In9.Cu")
		(net "LPC_CPU_LAD1")
	)
	(segment
		(start 79.8957 -33.147)
		(end 79.3623 -33.147)
		(width 0.0889)
		(layer "In9.Cu")
		(net "LPC_CPU_LAD1")
	)
	(segment
		(start 79.74965 -26.481532)
		(end 79.66075 -26.392632)
		(width 0.0889)
		(layer "In9.Cu")
		(net "LPC_CPU_LAD1")
	)
	(segment
		(start 85.31733 -41.999154)
		(end 85.105494 -42.21099)
		(width 0.0889)
		(layer "In9.Cu")
		(net "LPC_CPU_LAD1")
	)
	(segment
		(start 81.871058 -41.231058)
		(end 81.871058 -41.105582)
		(width 0.0889)
		(layer "In9.Cu")
		(net "LPC_CPU_LAD1")
	)
	(segment
		(start 78.486 -26.288492)
		(end 78.486 -26.141172)
		(width 0.0889)
		(layer "In9.Cu")
		(net "LPC_CPU_LAD1")
	)
	(segment
		(start 79.66075 -24.012144)
		(end 79.74965 -23.923244)
		(width 0.0889)
		(layer "In9.Cu")
		(net "LPC_CPU_LAD1")
	)
	(segment
		(start 83.709002 -42.21099)
		(end 83.620102 -42.12209)
		(width 0.0889)
		(layer "In9.Cu")
		(net "LPC_CPU_LAD1")
	)
	(segment
		(start 80.0608 -29.083)
		(end 79.6798 -28.702)
		(width 0.0889)
		(layer "In9.Cu")
		(net "LPC_CPU_LAD1")
	)
	(segment
		(start 79.6798 -28.702)
		(end 78.74 -28.702)
		(width 0.0889)
		(layer "In9.Cu")
		(net "LPC_CPU_LAD1")
	)
	(segment
		(start 82.85099 -42.21099)
		(end 81.871058 -41.231058)
		(width 0.0889)
		(layer "In9.Cu")
		(net "LPC_CPU_LAD1")
	)
	(segment
		(start 79.74965 -24.456644)
		(end 79.66075 -24.367744)
		(width 0.0889)
		(layer "In9.Cu")
		(net "LPC_CPU_LAD1")
	)
	(segment
		(start 78.486 -26.141172)
		(end 78.59014 -26.037032)
		(width 0.0889)
		(layer "In9.Cu")
		(net "LPC_CPU_LAD1")
	)
	(segment
		(start 78.486 -28.067)
		(end 78.7654 -27.7876)
		(width 0.0889)
		(layer "In9.Cu")
		(net "LPC_CPU_LAD1")
	)
	(segment
		(start 78.74 -35.56)
		(end 80.01 -34.29)
		(width 0.0889)
		(layer "In9.Cu")
		(net "LPC_CPU_LAD1")
	)
	(segment
		(start 83.620102 -41.6179)
		(end 83.531202 -41.529)
		(width 0.0889)
		(layer "In9.Cu")
		(net "LPC_CPU_LAD1")
	)
	(segment
		(start 78.359 -35.56)
		(end 78.74 -35.56)
		(width 0.0889)
		(layer "In9.Cu")
		(net "LPC_CPU_LAD1")
	)
	(segment
		(start 79.248 -33.0327)
		(end 79.248 -32.512)
		(width 0.0889)
		(layer "In9.Cu")
		(net "LPC_CPU_LAD1")
	)
	(segment
		(start 83.264502 -42.12209)
		(end 83.175602 -42.21099)
		(width 0.0889)
		(layer "In9.Cu")
		(net "LPC_CPU_LAD1")
	)
	(segment
		(start 78.7654 -27.432)
		(end 78.486 -27.1526)
		(width 0.0889)
		(layer "In9.Cu")
		(net "LPC_CPU_LAD1")
	)
	(segment
		(start 79.3242 -24.012144)
		(end 79.66075 -24.012144)
		(width 0.0889)
		(layer "In9.Cu")
		(net "LPC_CPU_LAD1")
	)
	(segment
		(start 79.66075 -24.723344)
		(end 79.74965 -24.634444)
		(width 0.0889)
		(layer "In9.Cu")
		(net "LPC_CPU_LAD1")
	)
	(segment
		(start 78.74 -28.702)
		(end 78.486 -28.448)
		(width 0.0889)
		(layer "In9.Cu")
		(net "LPC_CPU_LAD1")
	)
	(segment
		(start 80.3656 -41.102788)
		(end 80.218788 -41.102788)
		(width 0.0889)
		(layer "In9.Cu")
		(net "LPC_CPU_LAD1")
	)
	(segment
		(start 79.4258 -30.1752)
		(end 80.0608 -29.5402)
		(width 0.0889)
		(layer "In9.Cu")
		(net "LPC_CPU_LAD1")
	)
	(segment
		(start 82.253328 -40.597582)
		(end 82.127344 -40.471598)
		(width 0.0889)
		(layer "In9.Cu")
		(net "LPC_CPU_LAD1")
	)
	(segment
		(start 83.531202 -41.529)
		(end 83.353402 -41.529)
		(width 0.0889)
		(layer "In9.Cu")
		(net "LPC_CPU_LAD1")
	)
	(segment
		(start 81.54924 -40.42156)
		(end 81.54924 -40.27424)
		(width 0.0889)
		(layer "In9.Cu")
		(net "LPC_CPU_LAD1")
	)
	(segment
		(start 79.248 -32.512)
		(end 78.8924 -32.1564)
		(width 0.0889)
		(layer "In9.Cu")
		(net "LPC_CPU_LAD1")
	)
	(segment
		(start 79.66075 -24.367744)
		(end 79.3242 -24.367744)
		(width 0.0889)
		(layer "In9.Cu")
		(net "LPC_CPU_LAD1")
	)
	(segment
		(start 78.59014 -26.037032)
		(end 79.66075 -26.037032)
		(width 0.0889)
		(layer "In9.Cu")
		(net "LPC_CPU_LAD1")
	)
	(segment
		(start 81.494122 -40.854122)
		(end 81.368138 -40.728138)
		(width 0.0889)
		(layer "In9.Cu")
		(net "LPC_CPU_LAD1")
	)
	(segment
		(start 82.127344 -40.471598)
		(end 82.001868 -40.471598)
		(width 0.0889)
		(layer "In9.Cu")
		(net "LPC_CPU_LAD1")
	)
	(segment
		(start 79.1972 -24.977344)
		(end 79.1972 -24.824944)
		(width 0.0889)
		(layer "In9.Cu")
		(net "LPC_CPU_LAD1")
	)
	(segment
		(start 79.66075 -26.392632)
		(end 78.59014 -26.392632)
		(width 0.0889)
		(layer "In9.Cu")
		(net "LPC_CPU_LAD1")
	)
	(segment
		(start 85.31733 -41.996106)
		(end 85.31733 -41.999154)
		(width 0.0889)
		(layer "In9.Cu")
		(net "LPC_CPU_LAD1")
	)
	(segment
		(start 78.105 -36.322)
		(end 78.105 -35.814)
		(width 0.0889)
		(layer "In9.Cu")
		(net "LPC_CPU_LAD1")
	)
	(segment
		(start 83.264502 -41.6179)
		(end 83.264502 -42.12209)
		(width 0.0889)
		(layer "In9.Cu")
		(net "LPC_CPU_LAD1")
	)
	(segment
		(start 81.368138 -40.728138)
		(end 81.368138 -40.602662)
		(width 0.0889)
		(layer "In9.Cu")
		(net "LPC_CPU_LAD1")
	)
	(segment
		(start 78.105 -35.814)
		(end 78.359 -35.56)
		(width 0.0889)
		(layer "In9.Cu")
		(net "LPC_CPU_LAD1")
	)
	(segment
		(start 78.7654 -27.7876)
		(end 78.7654 -27.432)
		(width 0.0889)
		(layer "In9.Cu")
		(net "LPC_CPU_LAD1")
	)
	(segment
		(start 79.74965 -23.32355)
		(end 79.970376 -23.102824)
		(width 0.0889)
		(layer "In9.Cu")
		(net "LPC_CPU_LAD1")
	)
	(segment
		(start 83.175602 -42.21099)
		(end 82.85099 -42.21099)
		(width 0.0889)
		(layer "In9.Cu")
		(net "LPC_CPU_LAD1")
	)
	(segment
		(start 80.218788 -41.102788)
		(end 80.01 -40.894)
		(width 0.0889)
		(layer "In9.Cu")
		(net "LPC_CPU_LAD1")
	)
	(segment
		(start 79.66075 -26.748232)
		(end 79.74965 -26.659332)
		(width 0.0889)
		(layer "In9.Cu")
		(net "LPC_CPU_LAD1")
	)
	(segment
		(start 79.66075 -25.078944)
		(end 79.2988 -25.078944)
		(width 0.0889)
		(layer "In9.Cu")
		(net "LPC_CPU_LAD1")
	)
	(segment
		(start 79.3242 -24.367744)
		(end 79.2226 -24.266144)
		(width 0.0889)
		(layer "In9.Cu")
		(net "LPC_CPU_LAD1")
	)
	(segment
		(start 81.444846 -40.169846)
		(end 81.298034 -40.169846)
		(width 0.0889)
		(layer "In9.Cu")
		(net "LPC_CPU_LAD1")
	)
	(segment
		(start 78.59014 -26.392632)
		(end 78.486 -26.288492)
		(width 0.0889)
		(layer "In9.Cu")
		(net "LPC_CPU_LAD1")
	)
	(segment
		(start 85.5472 -41.766236)
		(end 85.31733 -41.996106)
		(width 0.0889)
		(layer "In9.Cu")
		(net "LPC_CPU_LAD1")
	)
	(segment
		(start 79.1972 -24.824944)
		(end 79.2988 -24.723344)
		(width 0.0889)
		(layer "In9.Cu")
		(net "LPC_CPU_LAD1")
	)
	(segment
		(start 78.486 -27.1526)
		(end 78.486 -26.852372)
		(width 0.0889)
		(layer "In9.Cu")
		(net "LPC_CPU_LAD1")
	)
	(segment
		(start 82.001868 -40.471598)
		(end 81.619598 -40.854122)
		(width 0.0889)
		(layer "In9.Cu")
		(net "LPC_CPU_LAD1")
	)
	(segment
		(start 80.01 -34.29)
		(end 80.01 -33.2613)
		(width 0.0889)
		(layer "In9.Cu")
		(net "LPC_CPU_LAD1")
	)
	(segment
		(start 79.2988 -25.078944)
		(end 79.1972 -24.977344)
		(width 0.0889)
		(layer "In9.Cu")
		(net "LPC_CPU_LAD1")
	)
	(segment
		(start 81.871058 -41.105582)
		(end 82.253328 -40.723058)
		(width 0.0889)
		(layer "In9.Cu")
		(net "LPC_CPU_LAD1")
	)
	(segment
		(start 79.74965 -23.923244)
		(end 79.74965 -23.32355)
		(width 0.0889)
		(layer "In9.Cu")
		(net "LPC_CPU_LAD1")
	)
	(segment
		(start 79.4258 -30.734)
		(end 79.4258 -30.1752)
		(width 0.0889)
		(layer "In9.Cu")
		(net "LPC_CPU_LAD1")
	)
	(segment
		(start 81.368138 -40.602662)
		(end 81.54924 -40.42156)
		(width 0.0889)
		(layer "In9.Cu")
		(net "LPC_CPU_LAD1")
	)
	(segment
		(start 79.0702 -31.5976)
		(end 79.4512 -31.5976)
		(width 0.0889)
		(layer "In9.Cu")
		(net "LPC_CPU_LAD1")
	)
	(segment
		(start 79.3623 -33.147)
		(end 79.248 -33.0327)
		(width 0.0889)
		(layer "In9.Cu")
		(net "LPC_CPU_LAD1")
	)
	(segment
		(start 79.629 -31.4198)
		(end 79.629 -30.9372)
		(width 0.0889)
		(layer "In9.Cu")
		(net "LPC_CPU_LAD1")
	)
	(segment
		(start 81.54924 -40.27424)
		(end 81.444846 -40.169846)
		(width 0.0889)
		(layer "In9.Cu")
		(net "LPC_CPU_LAD1")
	)
	(segment
		(start 78.486 -28.448)
		(end 78.486 -28.067)
		(width 0.0889)
		(layer "In9.Cu")
		(net "LPC_CPU_LAD1")
	)
	(segment
		(start 79.66075 -26.037032)
		(end 79.74965 -25.948132)
		(width 0.0889)
		(layer "In9.Cu")
		(net "LPC_CPU_LAD1")
	)
	(segment
		(start 78.486 -26.852372)
		(end 78.59014 -26.748232)
		(width 0.0889)
		(layer "In9.Cu")
		(net "LPC_CPU_LAD1")
	)
	(segment
		(start 82.253328 -40.723058)
		(end 82.253328 -40.597582)
		(width 0.0889)
		(layer "In9.Cu")
		(net "LPC_CPU_LAD1")
	)
	(segment
		(start 79.4512 -31.5976)
		(end 79.629 -31.4198)
		(width 0.0889)
		(layer "In9.Cu")
		(net "LPC_CPU_LAD1")
	)
	(segment
		(start 79.74965 -25.167844)
		(end 79.66075 -25.078944)
		(width 0.0889)
		(layer "In9.Cu")
		(net "LPC_CPU_LAD1")
	)
	(segment
		(start 80.01 -33.2613)
		(end 79.8957 -33.147)
		(width 0.0889)
		(layer "In9.Cu")
		(net "LPC_CPU_LAD1")
	)
	(segment
		(start 79.2988 -24.723344)
		(end 79.66075 -24.723344)
		(width 0.0889)
		(layer "In9.Cu")
		(net "LPC_CPU_LAD1")
	)
	(segment
		(start 79.2226 -24.266144)
		(end 79.2226 -24.113744)
		(width 0.0889)
		(layer "In9.Cu")
		(net "LPC_CPU_LAD1")
	)
	(segment
		(start 80.01 -38.227)
		(end 78.105 -36.322)
		(width 0.0889)
		(layer "In9.Cu")
		(net "LPC_CPU_LAD1")
	)
	(segment
		(start 79.74965 -24.634444)
		(end 79.74965 -24.456644)
		(width 0.0889)
		(layer "In9.Cu")
		(net "LPC_CPU_LAD1")
	)
	(segment
		(start 79.970376 -23.102824)
		(end 80.680814 -23.102824)
		(width 0.0889)
		(layer "In9.Cu")
		(net "LPC_CPU_LAD1")
	)
	(segment
		(start 79.629 -30.9372)
		(end 79.4258 -30.734)
		(width 0.0889)
		(layer "In9.Cu")
		(net "LPC_CPU_LAD1")
	)
	(segment
		(start 81.298034 -40.169846)
		(end 80.3656 -41.102788)
		(width 0.0889)
		(layer "In9.Cu")
		(net "LPC_CPU_LAD1")
	)
	(segment
		(start 79.2226 -24.113744)
		(end 79.3242 -24.012144)
		(width 0.0889)
		(layer "In9.Cu")
		(net "LPC_CPU_LAD1")
	)
	(segment
		(start 79.74965 -25.948132)
		(end 79.74965 -25.167844)
		(width 0.0889)
		(layer "In9.Cu")
		(net "LPC_CPU_LAD1")
	)
	(segment
		(start 79.74965 -26.659332)
		(end 79.74965 -26.481532)
		(width 0.0889)
		(layer "In9.Cu")
		(net "LPC_CPU_LAD1")
	)
	(segment
		(start 85.105494 -42.21099)
		(end 83.709002 -42.21099)
		(width 0.0889)
		(layer "In9.Cu")
		(net "LPC_CPU_LAD1")
	)
	(segment
		(start 83.353402 -41.529)
		(end 83.264502 -41.6179)
		(width 0.0889)
		(layer "In9.Cu")
		(net "LPC_CPU_LAD1")
	)
	(segment
		(start 78.59014 -26.748232)
		(end 79.66075 -26.748232)
		(width 0.0889)
		(layer "In9.Cu")
		(net "LPC_CPU_LAD1")
	)
	(segment
		(start 78.8924 -32.1564)
		(end 78.8924 -31.7754)
		(width 0.0889)
		(layer "In9.Cu")
		(net "LPC_CPU_LAD1")
	)
	(segment
		(start 81.619598 -40.854122)
		(end 81.494122 -40.854122)
		(width 0.0889)
		(layer "In9.Cu")
		(net "LPC_CPU_LAD1")
	)
	(segment
		(start 102.643178 -56.389778)
		(end 102.643178 -51.987196)
		(width 0.1016)
		(layer "F.Cu")
		(net "M_A_DQ42")
	)
	(segment
		(start 102.067868 -51.411886)
		(end 102.067868 -51.099974)
		(width 0.1016)
		(layer "F.Cu")
		(net "M_A_DQ42")
	)
	(segment
		(start 140.050012 -62.59322)
		(end 140.050012 -63.922148)
		(width 0.1778)
		(layer "F.Cu")
		(net "M_A_DQ42")
	)
	(segment
		(start 140.050012 -63.922148)
		(end 139.954 -64.01816)
		(width 0.1778)
		(layer "F.Cu")
		(net "M_A_DQ42")
	)
	(segment
		(start 102.7176 -56.4642)
		(end 102.643178 -56.389778)
		(width 0.1016)
		(layer "F.Cu")
		(net "M_A_DQ42")
	)
	(segment
		(start 102.643178 -51.987196)
		(end 102.067868 -51.411886)
		(width 0.1016)
		(layer "F.Cu")
		(net "M_A_DQ42")
	)
	(segment
		(start 139.954 -64.01816)
		(end 139.954 -64.022224)
		(width 0.1778)
		(layer "F.Cu")
		(net "M_A_DQ42")
	)
	(via
		(at 102.7176 -56.4642)
		(size 0.4318)
		(drill 0.2032)
		(layers "F.Cu" "B.Cu")
		(net "M_A_DQ42")
	)
	(via
		(at 139.954 -64.022224)
		(size 0.4318)
		(drill 0.2032)
		(layers "F.Cu" "B.Cu")
		(net "M_A_DQ42")
	)
	(segment
		(start 140.349986 -62.599824)
		(end 140.349986 -63.554102)
		(width 0.1778)
		(layer "B.Cu")
		(net "M_A_DQ42")
	)
	(segment
		(start 140.349986 -63.554102)
		(end 139.954 -63.950088)
		(width 0.1778)
		(layer "B.Cu")
		(net "M_A_DQ42")
	)
	(segment
		(start 139.954 -63.950088)
		(end 139.954 -64.022224)
		(width 0.1778)
		(layer "B.Cu")
		(net "M_A_DQ42")
	)
	(segment
		(start 138.868658 -63.096394)
		(end 136.9822 -63.096394)
		(width 0.1524)
		(layer "In2.Cu")
		(net "M_A_DQ42")
	)
	(segment
		(start 124.928376 -62.127384)
		(end 123.76404 -63.29045)
		(width 0.1524)
		(layer "In2.Cu")
		(net "M_A_DQ42")
	)
	(segment
		(start 139.954 -64.022224)
		(end 139.949936 -64.01816)
		(width 0.1524)
		(layer "In2.Cu")
		(net "M_A_DQ42")
	)
	(segment
		(start 133.123178 -65.8114)
		(end 132.970778 -65.659)
		(width 0.1524)
		(layer "In2.Cu")
		(net "M_A_DQ42")
	)
	(segment
		(start 139.790424 -64.01816)
		(end 138.868658 -63.096394)
		(width 0.1524)
		(layer "In2.Cu")
		(net "M_A_DQ42")
	)
	(segment
		(start 128.380998 -66.421)
		(end 126.310898 -64.3509)
		(width 0.1524)
		(layer "In2.Cu")
		(net "M_A_DQ42")
	)
	(segment
		(start 125.385322 -62.532768)
		(end 125.385322 -62.317376)
		(width 0.1524)
		(layer "In2.Cu")
		(net "M_A_DQ42")
	)
	(segment
		(start 123.332748 -63.07455)
		(end 123.332748 -62.859158)
		(width 0.1524)
		(layer "In2.Cu")
		(net "M_A_DQ42")
	)
	(segment
		(start 130.8354 -66.421)
		(end 128.380998 -66.421)
		(width 0.1524)
		(layer "In2.Cu")
		(net "M_A_DQ42")
	)
	(segment
		(start 136.8298 -64.184022)
		(end 136.6774 -64.336422)
		(width 0.1524)
		(layer "In2.Cu")
		(net "M_A_DQ42")
	)
	(segment
		(start 123.548648 -63.29045)
		(end 123.332748 -63.07455)
		(width 0.1524)
		(layer "In2.Cu")
		(net "M_A_DQ42")
	)
	(segment
		(start 132.970778 -65.659)
		(end 132.970778 -65.4304)
		(width 0.1524)
		(layer "In2.Cu")
		(net "M_A_DQ42")
	)
	(segment
		(start 124.609098 -64.3509)
		(end 124.195332 -63.937134)
		(width 0.1524)
		(layer "In2.Cu")
		(net "M_A_DQ42")
	)
	(segment
		(start 139.949936 -64.01816)
		(end 139.790424 -64.01816)
		(width 0.1524)
		(layer "In2.Cu")
		(net "M_A_DQ42")
	)
	(segment
		(start 104.791002 -60.468002)
		(end 103.2002 -58.8772)
		(width 0.1524)
		(layer "In2.Cu")
		(net "M_A_DQ42")
	)
	(segment
		(start 137.16 -65.659)
		(end 137.0076 -65.8114)
		(width 0.1524)
		(layer "In2.Cu")
		(net "M_A_DQ42")
	)
	(segment
		(start 103.2002 -56.9468)
		(end 102.7176 -56.4642)
		(width 0.1524)
		(layer "In2.Cu")
		(net "M_A_DQ42")
	)
	(segment
		(start 120.7262 -60.468002)
		(end 104.791002 -60.468002)
		(width 0.1524)
		(layer "In2.Cu")
		(net "M_A_DQ42")
	)
	(segment
		(start 136.2456 -64.488822)
		(end 136.2456 -64.793622)
		(width 0.1524)
		(layer "In2.Cu")
		(net "M_A_DQ42")
	)
	(segment
		(start 132.818378 -65.278)
		(end 132.513578 -65.278)
		(width 0.1524)
		(layer "In2.Cu")
		(net "M_A_DQ42")
	)
	(segment
		(start 123.633484 -62.558676)
		(end 123.633484 -62.343284)
		(width 0.1524)
		(layer "In2.Cu")
		(net "M_A_DQ42")
	)
	(segment
		(start 123.202192 -62.127384)
		(end 122.901456 -62.427866)
		(width 0.1524)
		(layer "In2.Cu")
		(net "M_A_DQ42")
	)
	(segment
		(start 136.398 -64.946022)
		(end 137.0076 -64.946022)
		(width 0.1524)
		(layer "In2.Cu")
		(net "M_A_DQ42")
	)
	(segment
		(start 132.361178 -65.4304)
		(end 132.361178 -65.659)
		(width 0.1524)
		(layer "In2.Cu")
		(net "M_A_DQ42")
	)
	(segment
		(start 131.445 -65.8114)
		(end 130.8354 -66.421)
		(width 0.1524)
		(layer "In2.Cu")
		(net "M_A_DQ42")
	)
	(segment
		(start 132.208778 -65.8114)
		(end 131.445 -65.8114)
		(width 0.1524)
		(layer "In2.Cu")
		(net "M_A_DQ42")
	)
	(segment
		(start 137.16 -65.098422)
		(end 137.16 -65.659)
		(width 0.1524)
		(layer "In2.Cu")
		(net "M_A_DQ42")
	)
	(segment
		(start 123.76404 -63.29045)
		(end 123.548648 -63.29045)
		(width 0.1524)
		(layer "In2.Cu")
		(net "M_A_DQ42")
	)
	(segment
		(start 123.417584 -62.127384)
		(end 123.202192 -62.127384)
		(width 0.1524)
		(layer "In2.Cu")
		(net "M_A_DQ42")
	)
	(segment
		(start 137.0076 -65.8114)
		(end 133.123178 -65.8114)
		(width 0.1524)
		(layer "In2.Cu")
		(net "M_A_DQ42")
	)
	(segment
		(start 136.9822 -63.096394)
		(end 136.8298 -63.248794)
		(width 0.1524)
		(layer "In2.Cu")
		(net "M_A_DQ42")
	)
	(segment
		(start 125.195584 -62.127384)
		(end 124.928376 -62.127384)
		(width 0.1524)
		(layer "In2.Cu")
		(net "M_A_DQ42")
	)
	(segment
		(start 132.513578 -65.278)
		(end 132.361178 -65.4304)
		(width 0.1524)
		(layer "In2.Cu")
		(net "M_A_DQ42")
	)
	(segment
		(start 132.970778 -65.4304)
		(end 132.818378 -65.278)
		(width 0.1524)
		(layer "In2.Cu")
		(net "M_A_DQ42")
	)
	(segment
		(start 136.398 -64.336422)
		(end 136.2456 -64.488822)
		(width 0.1524)
		(layer "In2.Cu")
		(net "M_A_DQ42")
	)
	(segment
		(start 122.901456 -62.427866)
		(end 122.686064 -62.427866)
		(width 0.1524)
		(layer "In2.Cu")
		(net "M_A_DQ42")
	)
	(segment
		(start 126.310898 -64.3509)
		(end 124.609098 -64.3509)
		(width 0.1524)
		(layer "In2.Cu")
		(net "M_A_DQ42")
	)
	(segment
		(start 137.0076 -64.946022)
		(end 137.16 -65.098422)
		(width 0.1524)
		(layer "In2.Cu")
		(net "M_A_DQ42")
	)
	(segment
		(start 136.6774 -64.336422)
		(end 136.398 -64.336422)
		(width 0.1524)
		(layer "In2.Cu")
		(net "M_A_DQ42")
	)
	(segment
		(start 123.633484 -62.343284)
		(end 123.417584 -62.127384)
		(width 0.1524)
		(layer "In2.Cu")
		(net "M_A_DQ42")
	)
	(segment
		(start 124.195332 -63.937134)
		(end 124.195332 -63.721742)
		(width 0.1524)
		(layer "In2.Cu")
		(net "M_A_DQ42")
	)
	(segment
		(start 136.2456 -64.793622)
		(end 136.398 -64.946022)
		(width 0.1524)
		(layer "In2.Cu")
		(net "M_A_DQ42")
	)
	(segment
		(start 122.686064 -62.427866)
		(end 120.7262 -60.468002)
		(width 0.1524)
		(layer "In2.Cu")
		(net "M_A_DQ42")
	)
	(segment
		(start 124.195332 -63.721742)
		(end 125.385322 -62.532768)
		(width 0.1524)
		(layer "In2.Cu")
		(net "M_A_DQ42")
	)
	(segment
		(start 136.8298 -63.248794)
		(end 136.8298 -64.184022)
		(width 0.1524)
		(layer "In2.Cu")
		(net "M_A_DQ42")
	)
	(segment
		(start 132.361178 -65.659)
		(end 132.208778 -65.8114)
		(width 0.1524)
		(layer "In2.Cu")
		(net "M_A_DQ42")
	)
	(segment
		(start 103.2002 -58.8772)
		(end 103.2002 -56.9468)
		(width 0.1524)
		(layer "In2.Cu")
		(net "M_A_DQ42")
	)
	(segment
		(start 123.332748 -62.859158)
		(end 123.633484 -62.558676)
		(width 0.1524)
		(layer "In2.Cu")
		(net "M_A_DQ42")
	)
	(segment
		(start 125.385322 -62.317376)
		(end 125.195584 -62.127384)
		(width 0.1524)
		(layer "In2.Cu")
		(net "M_A_DQ42")
	)
	(segment
		(start 20.463002 -55.547006)
		(end 20.463002 -54.5338)
		(width 0.2032)
		(layer "F.Cu")
		(net "PVCCP_ISEN2")
	)
	(via
		(at 20.463002 -54.5338)
		(size 0.508)
		(drill 0.254)
		(layers "F.Cu" "B.Cu")
		(net "PVCCP_ISEN2")
	)
	(via
		(at 21.3868 -53.7972)
		(size 0.7112)
		(drill 0.3556)
		(layers "F.Cu" "B.Cu")
		(net "PVCCP_ISEN2")
	)
	(segment
		(start 20.463002 -54.5338)
		(end 21.199602 -53.7972)
		(width 0.2032)
		(layer "B.Cu")
		(net "PVCCP_ISEN2")
	)
	(segment
		(start 21.199602 -53.7972)
		(end 21.3868 -53.7972)
		(width 0.2032)
		(layer "B.Cu")
		(net "PVCCP_ISEN2")
	)
	(segment
		(start 21.3868 -53.7972)
		(end 22.3012 -53.7972)
		(width 0.2032)
		(layer "B.Cu")
		(net "PVCCP_ISEN2")
	)
	(segment
		(start 157.150054 -69.831712)
		(end 157.089348 -69.771006)
		(width 0.2413)
		(layer "F.Cu")
		(net "M_A_MA3")
	)
	(segment
		(start 157.74797 -68.472812)
		(end 157.74797 -66.487548)
		(width 0.2413)
		(layer "F.Cu")
		(net "M_A_MA3")
	)
	(segment
		(start 157.089348 -69.131434)
		(end 157.74797 -68.472812)
		(width 0.2413)
		(layer "F.Cu")
		(net "M_A_MA3")
	)
	(segment
		(start 107.033822 -49.0474)
		(end 107.297728 -48.783494)
		(width 0.1016)
		(layer "F.Cu")
		(net "M_A_MA3")
	)
	(segment
		(start 157.150054 -70.806564)
		(end 157.150054 -69.831712)
		(width 0.2413)
		(layer "F.Cu")
		(net "M_A_MA3")
	)
	(segment
		(start 106.8832 -49.0474)
		(end 107.033822 -49.0474)
		(width 0.1016)
		(layer "F.Cu")
		(net "M_A_MA3")
	)
	(segment
		(start 157.089348 -69.771006)
		(end 157.089348 -69.131434)
		(width 0.2413)
		(layer "F.Cu")
		(net "M_A_MA3")
	)
	(segment
		(start 157.74797 -66.487548)
		(end 157.323028 -66.062606)
		(width 0.2413)
		(layer "F.Cu")
		(net "M_A_MA3")
	)
	(via
		(at 106.8832 -49.0474)
		(size 0.4318)
		(drill 0.2032)
		(layers "F.Cu" "B.Cu")
		(net "M_A_MA3")
	)
	(via
		(at 157.323028 -66.062606)
		(size 0.4318)
		(drill 0.2032)
		(layers "F.Cu" "B.Cu")
		(net "M_A_MA3")
	)
	(segment
		(start 157.150054 -62.599824)
		(end 157.150054 -64.935862)
		(width 0.2413)
		(layer "B.Cu")
		(net "M_A_MA3")
	)
	(segment
		(start 157.323028 -65.108836)
		(end 157.323028 -66.062606)
		(width 0.2413)
		(layer "B.Cu")
		(net "M_A_MA3")
	)
	(segment
		(start 157.150054 -64.935862)
		(end 157.323028 -65.108836)
		(width 0.2413)
		(layer "B.Cu")
		(net "M_A_MA3")
	)
	(segment
		(start 154.014424 -59.704224)
		(end 154.014424 -59.948064)
		(width 0.1905)
		(layer "In9.Cu")
		(net "M_A_MA3")
	)
	(segment
		(start 108.077 -49.8094)
		(end 107.4674 -49.1998)
		(width 0.1016)
		(layer "In9.Cu")
		(net "M_A_MA3")
	)
	(segment
		(start 151.962104 -57.77738)
		(end 152.514046 -57.77738)
		(width 0.1905)
		(layer "In9.Cu")
		(net "M_A_MA3")
	)
	(segment
		(start 107.914694 -52.07)
		(end 107.914694 -51.546506)
		(width 0.1016)
		(layer "In9.Cu")
		(net "M_A_MA3")
	)
	(segment
		(start 133.731 -53.34635)
		(end 138.049 -53.34635)
		(width 0.1905)
		(layer "In9.Cu")
		(net "M_A_MA3")
	)
	(segment
		(start 133.1468 -52.76215)
		(end 133.731 -53.34635)
		(width 0.1905)
		(layer "In9.Cu")
		(net "M_A_MA3")
	)
	(segment
		(start 156.9974 -65.4558)
		(end 157.219904 -65.678304)
		(width 0.1905)
		(layer "In9.Cu")
		(net "M_A_MA3")
	)
	(segment
		(start 151.460962 -56.724296)
		(end 151.460962 -57.276238)
		(width 0.1905)
		(layer "In9.Cu")
		(net "M_A_MA3")
	)
	(segment
		(start 117.69598 -53.213)
		(end 118.14683 -52.76215)
		(width 0.1905)
		(layer "In9.Cu")
		(net "M_A_MA3")
	)
	(segment
		(start 107.914694 -51.546506)
		(end 108.3818 -51.0794)
		(width 0.1016)
		(layer "In9.Cu")
		(net "M_A_MA3")
	)
	(segment
		(start 152.5143 -57.777634)
		(end 152.78862 -57.777634)
		(width 0.1905)
		(layer "In9.Cu")
		(net "M_A_MA3")
	)
	(segment
		(start 149.9362 -55.199534)
		(end 149.9362 -55.751476)
		(width 0.1905)
		(layer "In9.Cu")
		(net "M_A_MA3")
	)
	(segment
		(start 109.8296 -52.9082)
		(end 109.207046 -52.285646)
		(width 0.1016)
		(layer "In9.Cu")
		(net "M_A_MA3")
	)
	(segment
		(start 148.839174 -54.65445)
		(end 149.391116 -54.65445)
		(width 0.1905)
		(layer "In9.Cu")
		(net "M_A_MA3")
	)
	(segment
		(start 157.219904 -65.678304)
		(end 157.219904 -65.959482)
		(width 0.1905)
		(layer "In9.Cu")
		(net "M_A_MA3")
	)
	(segment
		(start 138.632946 -52.76215)
		(end 143.28648 -52.76215)
		(width 0.1905)
		(layer "In9.Cu")
		(net "M_A_MA3")
	)
	(segment
		(start 152.78862 -57.777634)
		(end 153.23185 -58.220864)
		(width 0.1905)
		(layer "In9.Cu")
		(net "M_A_MA3")
	)
	(segment
		(start 118.14683 -52.76215)
		(end 133.1468 -52.76215)
		(width 0.1905)
		(layer "In9.Cu")
		(net "M_A_MA3")
	)
	(segment
		(start 107.0356 -49.1998)
		(end 106.8832 -49.0474)
		(width 0.1016)
		(layer "In9.Cu")
		(net "M_A_MA3")
	)
	(segment
		(start 108.13034 -52.285646)
		(end 107.914694 -52.07)
		(width 0.1016)
		(layer "In9.Cu")
		(net "M_A_MA3")
	)
	(segment
		(start 149.391116 -54.65445)
		(end 149.9362 -55.199534)
		(width 0.1905)
		(layer "In9.Cu")
		(net "M_A_MA3")
	)
	(segment
		(start 149.9362 -55.751476)
		(end 150.406862 -56.222138)
		(width 0.1905)
		(layer "In9.Cu")
		(net "M_A_MA3")
	)
	(segment
		(start 152.514046 -57.77738)
		(end 152.5143 -57.777634)
		(width 0.1905)
		(layer "In9.Cu")
		(net "M_A_MA3")
	)
	(segment
		(start 154.014424 -59.948064)
		(end 156.9974 -62.93104)
		(width 0.1905)
		(layer "In9.Cu")
		(net "M_A_MA3")
	)
	(segment
		(start 107.4674 -49.1998)
		(end 107.0356 -49.1998)
		(width 0.1016)
		(layer "In9.Cu")
		(net "M_A_MA3")
	)
	(segment
		(start 150.958804 -56.222138)
		(end 151.460962 -56.724296)
		(width 0.1905)
		(layer "In9.Cu")
		(net "M_A_MA3")
	)
	(segment
		(start 108.3818 -51.0794)
		(end 108.3818 -50.652172)
		(width 0.1016)
		(layer "In9.Cu")
		(net "M_A_MA3")
	)
	(segment
		(start 151.460962 -57.276238)
		(end 151.962104 -57.77738)
		(width 0.1905)
		(layer "In9.Cu")
		(net "M_A_MA3")
	)
	(segment
		(start 156.9974 -62.93104)
		(end 156.9974 -65.4558)
		(width 0.1905)
		(layer "In9.Cu")
		(net "M_A_MA3")
	)
	(segment
		(start 143.87068 -53.34635)
		(end 146.12239 -53.34635)
		(width 0.1905)
		(layer "In9.Cu")
		(net "M_A_MA3")
	)
	(segment
		(start 108.3818 -50.652172)
		(end 108.077 -50.347372)
		(width 0.1016)
		(layer "In9.Cu")
		(net "M_A_MA3")
	)
	(segment
		(start 109.207046 -52.285646)
		(end 108.13034 -52.285646)
		(width 0.1016)
		(layer "In9.Cu")
		(net "M_A_MA3")
	)
	(segment
		(start 108.077 -50.347372)
		(end 108.077 -49.8094)
		(width 0.1016)
		(layer "In9.Cu")
		(net "M_A_MA3")
	)
	(segment
		(start 153.23185 -58.220864)
		(end 153.23185 -58.92165)
		(width 0.1905)
		(layer "In9.Cu")
		(net "M_A_MA3")
	)
	(segment
		(start 111.76 -53.213)
		(end 117.69598 -53.213)
		(width 0.1905)
		(layer "In9.Cu")
		(net "M_A_MA3")
	)
	(segment
		(start 111.4552 -52.9082)
		(end 109.8296 -52.9082)
		(width 0.1016)
		(layer "In9.Cu")
		(net "M_A_MA3")
	)
	(segment
		(start 157.219904 -65.959482)
		(end 157.323028 -66.062606)
		(width 0.1905)
		(layer "In9.Cu")
		(net "M_A_MA3")
	)
	(segment
		(start 138.049 -53.34635)
		(end 138.632946 -52.76215)
		(width 0.1905)
		(layer "In9.Cu")
		(net "M_A_MA3")
	)
	(segment
		(start 111.4552 -52.9082)
		(end 111.76 -53.213)
		(width 0.1905)
		(layer "In9.Cu")
		(net "M_A_MA3")
	)
	(segment
		(start 143.28648 -52.76215)
		(end 143.87068 -53.34635)
		(width 0.1905)
		(layer "In9.Cu")
		(net "M_A_MA3")
	)
	(segment
		(start 146.607276 -53.831236)
		(end 148.01596 -53.831236)
		(width 0.1905)
		(layer "In9.Cu")
		(net "M_A_MA3")
	)
	(segment
		(start 153.23185 -58.92165)
		(end 154.014424 -59.704224)
		(width 0.1905)
		(layer "In9.Cu")
		(net "M_A_MA3")
	)
	(segment
		(start 146.12239 -53.34635)
		(end 146.607276 -53.831236)
		(width 0.1905)
		(layer "In9.Cu")
		(net "M_A_MA3")
	)
	(segment
		(start 150.406862 -56.222138)
		(end 150.958804 -56.222138)
		(width 0.1905)
		(layer "In9.Cu")
		(net "M_A_MA3")
	)
	(segment
		(start 148.01596 -53.831236)
		(end 148.839174 -54.65445)
		(width 0.1905)
		(layer "In9.Cu")
		(net "M_A_MA3")
	)
	(segment
		(start 84.021168 -35.458146)
		(end 83.672934 -35.109912)
		(width 0.1143)
		(layer "F.Cu")
		(net "SUSPWRDNACK")
	)
	(segment
		(start 84.02828 -35.458146)
		(end 84.021168 -35.458146)
		(width 0.1143)
		(layer "F.Cu")
		(net "SUSPWRDNACK")
	)
	(segment
		(start 84.028788 -35.458654)
		(end 84.02828 -35.458146)
		(width 0.1143)
		(layer "F.Cu")
		(net "SUSPWRDNACK")
	)
	(via
		(at 75.4888 -31.3944)
		(size 0.7112)
		(drill 0.3556)
		(layers "F.Cu" "B.Cu")
		(net "SUSPWRDNACK")
	)
	(via
		(at 83.672934 -35.109912)
		(size 0.4318)
		(drill 0.2032)
		(layers "F.Cu" "B.Cu")
		(net "SUSPWRDNACK")
	)
	(segment
		(start 75.4888 -31.3944)
		(end 76.3905 -32.2961)
		(width 0.1143)
		(layer "B.Cu")
		(net "SUSPWRDNACK")
	)
	(segment
		(start 74.4728 -30.988)
		(end 74.8284 -30.988)
		(width 0.1143)
		(layer "B.Cu")
		(net "SUSPWRDNACK")
	)
	(segment
		(start 82.255868 -34.787586)
		(end 83.040982 -34.787586)
		(width 0.1143)
		(layer "B.Cu")
		(net "SUSPWRDNACK")
	)
	(segment
		(start 76.3905 -32.2961)
		(end 76.3905 -32.878268)
		(width 0.1143)
		(layer "B.Cu")
		(net "SUSPWRDNACK")
	)
	(segment
		(start 81.255616 -34.48431)
		(end 81.695798 -34.924492)
		(width 0.1143)
		(layer "B.Cu")
		(net "SUSPWRDNACK")
	)
	(segment
		(start 74.8284 -30.988)
		(end 75.2348 -31.3944)
		(width 0.1143)
		(layer "B.Cu")
		(net "SUSPWRDNACK")
	)
	(segment
		(start 77.865732 -34.3535)
		(end 79.006954 -34.3535)
		(width 0.1143)
		(layer "B.Cu")
		(net "SUSPWRDNACK")
	)
	(segment
		(start 81.695798 -34.924492)
		(end 82.118962 -34.924492)
		(width 0.1143)
		(layer "B.Cu")
		(net "SUSPWRDNACK")
	)
	(segment
		(start 79.137764 -34.48431)
		(end 81.255616 -34.48431)
		(width 0.1143)
		(layer "B.Cu")
		(net "SUSPWRDNACK")
	)
	(segment
		(start 83.363308 -35.109912)
		(end 83.672934 -35.109912)
		(width 0.1143)
		(layer "B.Cu")
		(net "SUSPWRDNACK")
	)
	(segment
		(start 83.040982 -34.787586)
		(end 83.363308 -35.109912)
		(width 0.1143)
		(layer "B.Cu")
		(net "SUSPWRDNACK")
	)
	(segment
		(start 75.2348 -31.3944)
		(end 75.4888 -31.3944)
		(width 0.1143)
		(layer "B.Cu")
		(net "SUSPWRDNACK")
	)
	(segment
		(start 79.006954 -34.3535)
		(end 79.137764 -34.48431)
		(width 0.1143)
		(layer "B.Cu")
		(net "SUSPWRDNACK")
	)
	(segment
		(start 76.3905 -32.878268)
		(end 77.865732 -34.3535)
		(width 0.1143)
		(layer "B.Cu")
		(net "SUSPWRDNACK")
	)
	(segment
		(start 82.118962 -34.924492)
		(end 82.255868 -34.787586)
		(width 0.1143)
		(layer "B.Cu")
		(net "SUSPWRDNACK")
	)
	(segment
		(start 23.7236 -64.2112)
		(end 23.98268 -64.2112)
		(width 0.4572)
		(layer "F.Cu")
		(net "VR_PVNN_BOOT")
	)
	(segment
		(start 23.2156 -63.7032)
		(end 23.7236 -64.2112)
		(width 0.4572)
		(layer "F.Cu")
		(net "VR_PVNN_BOOT")
	)
	(segment
		(start 22.462998 -61.292994)
		(end 22.462998 -61.833252)
		(width 0.2032)
		(layer "F.Cu")
		(net "VR_PVNN_BOOT")
	)
	(segment
		(start 22.462998 -61.833252)
		(end 23.2156 -62.585854)
		(width 0.2032)
		(layer "F.Cu")
		(net "VR_PVNN_BOOT")
	)
	(segment
		(start 23.2156 -62.585854)
		(end 23.2156 -63.7032)
		(width 0.2032)
		(layer "F.Cu")
		(net "VR_PVNN_BOOT")
	)
	(segment
		(start 101.096572 -47.398178)
		(end 101.338888 -47.640494)
		(width 0.1016)
		(layer "F.Cu")
		(net "M_A_CS_N2")
	)
	(segment
		(start 149.479 -68.6816)
		(end 149.4536 -68.6562)
		(width 0.1778)
		(layer "F.Cu")
		(net "M_A_CS_N2")
	)
	(segment
		(start 149.95017 -70.806564)
		(end 149.95017 -69.667882)
		(width 0.1778)
		(layer "F.Cu")
		(net "M_A_CS_N2")
	)
	(segment
		(start 149.95017 -69.667882)
		(end 149.805644 -69.523356)
		(width 0.1778)
		(layer "F.Cu")
		(net "M_A_CS_N2")
	)
	(segment
		(start 149.805644 -68.991734)
		(end 149.49551 -68.6816)
		(width 0.1778)
		(layer "F.Cu")
		(net "M_A_CS_N2")
	)
	(segment
		(start 149.805644 -69.523356)
		(end 149.805644 -68.991734)
		(width 0.1778)
		(layer "F.Cu")
		(net "M_A_CS_N2")
	)
	(segment
		(start 149.49551 -68.6816)
		(end 149.479 -68.6816)
		(width 0.1778)
		(layer "F.Cu")
		(net "M_A_CS_N2")
	)
	(segment
		(start 100.915978 -47.398178)
		(end 101.096572 -47.398178)
		(width 0.1016)
		(layer "F.Cu")
		(net "M_A_CS_N2")
	)
	(via
		(at 100.915978 -47.398178)
		(size 0.4318)
		(drill 0.2032)
		(layers "F.Cu" "B.Cu")
		(net "M_A_CS_N2")
	)
	(via
		(at 149.4536 -68.6562)
		(size 0.4318)
		(drill 0.2032)
		(layers "F.Cu" "B.Cu")
		(net "M_A_CS_N2")
	)
	(segment
		(start 139.982702 -55.8546)
		(end 138.836654 -55.8546)
		(width 0.1524)
		(layer "In7.Cu")
		(net "M_A_CS_N2")
	)
	(segment
		(start 121.11609 -55.4482)
		(end 119.57304 -56.99125)
		(width 0.1524)
		(layer "In7.Cu")
		(net "M_A_CS_N2")
	)
	(segment
		(start 137.313924 -55.8546)
		(end 135.582152 -55.8546)
		(width 0.1524)
		(layer "In7.Cu")
		(net "M_A_CS_N2")
	)
	(segment
		(start 149.4536 -68.6562)
		(end 149.098 -68.6562)
		(width 0.1524)
		(layer "In7.Cu")
		(net "M_A_CS_N2")
	)
	(segment
		(start 140.764006 -56.851296)
		(end 140.764006 -56.635904)
		(width 0.1524)
		(layer "In7.Cu")
		(net "M_A_CS_N2")
	)
	(segment
		(start 125.8062 -55.88)
		(end 124.968 -55.88)
		(width 0.1524)
		(layer "In7.Cu")
		(net "M_A_CS_N2")
	)
	(segment
		(start 142.9004 -58.8518)
		(end 142.748 -59.0042)
		(width 0.1524)
		(layer "In7.Cu")
		(net "M_A_CS_N2")
	)
	(segment
		(start 142.9004 -58.1914)
		(end 142.9004 -58.8518)
		(width 0.1524)
		(layer "In7.Cu")
		(net "M_A_CS_N2")
	)
	(segment
		(start 134.445248 -55.88)
		(end 127.621538 -55.88)
		(width 0.1524)
		(layer "In7.Cu")
		(net "M_A_CS_N2")
	)
	(segment
		(start 105.1814 -56.0578)
		(end 105.1814 -54.991)
		(width 0.1524)
		(layer "In7.Cu")
		(net "M_A_CS_N2")
	)
	(segment
		(start 124.968 -55.88)
		(end 124.76226 -55.67426)
		(width 0.1524)
		(layer "In7.Cu")
		(net "M_A_CS_N2")
	)
	(segment
		(start 150.504398 -67.5132)
		(end 150.504398 -65.951862)
		(width 0.1524)
		(layer "In7.Cu")
		(net "M_A_CS_N2")
	)
	(segment
		(start 135.582152 -55.8546)
		(end 135.201152 -56.2356)
		(width 0.1524)
		(layer "In7.Cu")
		(net "M_A_CS_N2")
	)
	(segment
		(start 122.751342 -55.88)
		(end 122.319542 -55.4482)
		(width 0.1524)
		(layer "In7.Cu")
		(net "M_A_CS_N2")
	)
	(segment
		(start 140.546074 -57.284874)
		(end 140.546074 -57.069482)
		(width 0.1524)
		(layer "In7.Cu")
		(net "M_A_CS_N2")
	)
	(segment
		(start 144.1958 -58.166)
		(end 144.1958 -58.8518)
		(width 0.1524)
		(layer "In7.Cu")
		(net "M_A_CS_N2")
	)
	(segment
		(start 135.201152 -56.2356)
		(end 134.800848 -56.2356)
		(width 0.1524)
		(layer "In7.Cu")
		(net "M_A_CS_N2")
	)
	(segment
		(start 148.9456 -68.5038)
		(end 148.9456 -67.9958)
		(width 0.1524)
		(layer "In7.Cu")
		(net "M_A_CS_N2")
	)
	(segment
		(start 127.621538 -55.88)
		(end 127.189738 -55.4482)
		(width 0.1524)
		(layer "In7.Cu")
		(net "M_A_CS_N2")
	)
	(segment
		(start 105.41 -57.0484)
		(end 105.1052 -56.7436)
		(width 0.1524)
		(layer "In7.Cu")
		(net "M_A_CS_N2")
	)
	(segment
		(start 150.504398 -65.951862)
		(end 150.658068 -65.798192)
		(width 0.1524)
		(layer "In7.Cu")
		(net "M_A_CS_N2")
	)
	(segment
		(start 141.195552 -57.282588)
		(end 140.977366 -57.500774)
		(width 0.1524)
		(layer "In7.Cu")
		(net "M_A_CS_N2")
	)
	(segment
		(start 142.188438 -59.0042)
		(end 142.036038 -58.8518)
		(width 0.1524)
		(layer "In7.Cu")
		(net "M_A_CS_N2")
	)
	(segment
		(start 144.3482 -58.0136)
		(end 144.1958 -58.166)
		(width 0.1524)
		(layer "In7.Cu")
		(net "M_A_CS_N2")
	)
	(segment
		(start 145.249138 -58.7248)
		(end 145.0848 -58.7248)
		(width 0.1524)
		(layer "In7.Cu")
		(net "M_A_CS_N2")
	)
	(segment
		(start 144.1958 -58.8518)
		(end 144.0434 -59.0042)
		(width 0.1524)
		(layer "In7.Cu")
		(net "M_A_CS_N2")
	)
	(segment
		(start 142.748 -59.0042)
		(end 142.188438 -59.0042)
		(width 0.1524)
		(layer "In7.Cu")
		(net "M_A_CS_N2")
	)
	(segment
		(start 145.249392 -58.725054)
		(end 145.249138 -58.7248)
		(width 0.1524)
		(layer "In7.Cu")
		(net "M_A_CS_N2")
	)
	(segment
		(start 142.036038 -58.8518)
		(end 142.036038 -57.907936)
		(width 0.1524)
		(layer "In7.Cu")
		(net "M_A_CS_N2")
	)
	(segment
		(start 145.733262 -58.7248)
		(end 145.733008 -58.725054)
		(width 0.1524)
		(layer "In7.Cu")
		(net "M_A_CS_N2")
	)
	(segment
		(start 138.304016 -56.387238)
		(end 137.846562 -56.387238)
		(width 0.1524)
		(layer "In7.Cu")
		(net "M_A_CS_N2")
	)
	(segment
		(start 119.57304 -56.99125)
		(end 107.951524 -56.99125)
		(width 0.1524)
		(layer "In7.Cu")
		(net "M_A_CS_N2")
	)
	(segment
		(start 138.836654 -55.8546)
		(end 138.304016 -56.387238)
		(width 0.1524)
		(layer "In7.Cu")
		(net "M_A_CS_N2")
	)
	(segment
		(start 100.922582 -47.398178)
		(end 101.5492 -48.024796)
		(width 0.1016)
		(layer "In7.Cu")
		(net "M_A_CS_N2")
	)
	(segment
		(start 143.7132 -59.0042)
		(end 143.5608 -58.8518)
		(width 0.1524)
		(layer "In7.Cu")
		(net "M_A_CS_N2")
	)
	(segment
		(start 127.189738 -55.4482)
		(end 126.238 -55.4482)
		(width 0.1524)
		(layer "In7.Cu")
		(net "M_A_CS_N2")
	)
	(segment
		(start 142.036038 -57.907936)
		(end 141.41069 -57.282588)
		(width 0.1524)
		(layer "In7.Cu")
		(net "M_A_CS_N2")
	)
	(segment
		(start 149.254718 -67.686682)
		(end 150.330916 -67.686682)
		(width 0.1524)
		(layer "In7.Cu")
		(net "M_A_CS_N2")
	)
	(segment
		(start 101.5492 -48.024796)
		(end 101.5492 -51.3588)
		(width 0.1016)
		(layer "In7.Cu")
		(net "M_A_CS_N2")
	)
	(segment
		(start 105.1052 -56.134)
		(end 105.1814 -56.0578)
		(width 0.1524)
		(layer "In7.Cu")
		(net "M_A_CS_N2")
	)
	(segment
		(start 145.733008 -58.725054)
		(end 145.249392 -58.725054)
		(width 0.1524)
		(layer "In7.Cu")
		(net "M_A_CS_N2")
	)
	(segment
		(start 107.951524 -56.99125)
		(end 107.894374 -57.0484)
		(width 0.1524)
		(layer "In7.Cu")
		(net "M_A_CS_N2")
	)
	(segment
		(start 123.4694 -55.88)
		(end 122.751342 -55.88)
		(width 0.1524)
		(layer "In7.Cu")
		(net "M_A_CS_N2")
	)
	(segment
		(start 140.977366 -57.500774)
		(end 140.761974 -57.500774)
		(width 0.1524)
		(layer "In7.Cu")
		(net "M_A_CS_N2")
	)
	(segment
		(start 148.9456 -67.9958)
		(end 149.254718 -67.686682)
		(width 0.1524)
		(layer "In7.Cu")
		(net "M_A_CS_N2")
	)
	(segment
		(start 143.0528 -58.039)
		(end 142.9004 -58.1914)
		(width 0.1524)
		(layer "In7.Cu")
		(net "M_A_CS_N2")
	)
	(segment
		(start 137.846562 -56.387238)
		(end 137.313924 -55.8546)
		(width 0.1524)
		(layer "In7.Cu")
		(net "M_A_CS_N2")
	)
	(segment
		(start 149.098 -68.6562)
		(end 148.9456 -68.5038)
		(width 0.1524)
		(layer "In7.Cu")
		(net "M_A_CS_N2")
	)
	(segment
		(start 124.76226 -55.67426)
		(end 123.67514 -55.67426)
		(width 0.1524)
		(layer "In7.Cu")
		(net "M_A_CS_N2")
	)
	(segment
		(start 140.546074 -57.069482)
		(end 140.764006 -56.851296)
		(width 0.1524)
		(layer "In7.Cu")
		(net "M_A_CS_N2")
	)
	(segment
		(start 143.4084 -58.039)
		(end 143.0528 -58.039)
		(width 0.1524)
		(layer "In7.Cu")
		(net "M_A_CS_N2")
	)
	(segment
		(start 140.764006 -56.635904)
		(end 139.982702 -55.8546)
		(width 0.1524)
		(layer "In7.Cu")
		(net "M_A_CS_N2")
	)
	(segment
		(start 144.9324 -58.5724)
		(end 144.9324 -58.166)
		(width 0.1524)
		(layer "In7.Cu")
		(net "M_A_CS_N2")
	)
	(segment
		(start 105.1814 -54.991)
		(end 103.73995 -53.54955)
		(width 0.1524)
		(layer "In7.Cu")
		(net "M_A_CS_N2")
	)
	(segment
		(start 123.67514 -55.67426)
		(end 123.4694 -55.88)
		(width 0.1524)
		(layer "In7.Cu")
		(net "M_A_CS_N2")
	)
	(segment
		(start 122.319542 -55.4482)
		(end 121.11609 -55.4482)
		(width 0.1524)
		(layer "In7.Cu")
		(net "M_A_CS_N2")
	)
	(segment
		(start 140.761974 -57.500774)
		(end 140.546074 -57.284874)
		(width 0.1524)
		(layer "In7.Cu")
		(net "M_A_CS_N2")
	)
	(segment
		(start 100.915978 -47.398178)
		(end 100.922582 -47.398178)
		(width 0.1016)
		(layer "In7.Cu")
		(net "M_A_CS_N2")
	)
	(segment
		(start 150.330916 -67.686682)
		(end 150.504398 -67.5132)
		(width 0.1524)
		(layer "In7.Cu")
		(net "M_A_CS_N2")
	)
	(segment
		(start 101.5492 -51.3588)
		(end 103.73995 -53.54955)
		(width 0.1016)
		(layer "In7.Cu")
		(net "M_A_CS_N2")
	)
	(segment
		(start 107.894374 -57.0484)
		(end 105.41 -57.0484)
		(width 0.1524)
		(layer "In7.Cu")
		(net "M_A_CS_N2")
	)
	(segment
		(start 150.658068 -63.158116)
		(end 146.224752 -58.7248)
		(width 0.1524)
		(layer "In7.Cu")
		(net "M_A_CS_N2")
	)
	(segment
		(start 144.78 -58.0136)
		(end 144.3482 -58.0136)
		(width 0.1524)
		(layer "In7.Cu")
		(net "M_A_CS_N2")
	)
	(segment
		(start 144.9324 -58.166)
		(end 144.78 -58.0136)
		(width 0.1524)
		(layer "In7.Cu")
		(net "M_A_CS_N2")
	)
	(segment
		(start 105.1052 -56.7436)
		(end 105.1052 -56.134)
		(width 0.1524)
		(layer "In7.Cu")
		(net "M_A_CS_N2")
	)
	(segment
		(start 146.224752 -58.7248)
		(end 145.733262 -58.7248)
		(width 0.1524)
		(layer "In7.Cu")
		(net "M_A_CS_N2")
	)
	(segment
		(start 144.0434 -59.0042)
		(end 143.7132 -59.0042)
		(width 0.1524)
		(layer "In7.Cu")
		(net "M_A_CS_N2")
	)
	(segment
		(start 134.800848 -56.2356)
		(end 134.445248 -55.88)
		(width 0.1524)
		(layer "In7.Cu")
		(net "M_A_CS_N2")
	)
	(segment
		(start 145.0848 -58.7248)
		(end 144.9324 -58.5724)
		(width 0.1524)
		(layer "In7.Cu")
		(net "M_A_CS_N2")
	)
	(segment
		(start 150.658068 -65.798192)
		(end 150.658068 -63.158116)
		(width 0.1524)
		(layer "In7.Cu")
		(net "M_A_CS_N2")
	)
	(segment
		(start 143.5608 -58.1914)
		(end 143.4084 -58.039)
		(width 0.1524)
		(layer "In7.Cu")
		(net "M_A_CS_N2")
	)
	(segment
		(start 126.238 -55.4482)
		(end 125.8062 -55.88)
		(width 0.1524)
		(layer "In7.Cu")
		(net "M_A_CS_N2")
	)
	(segment
		(start 141.41069 -57.282588)
		(end 141.195552 -57.282588)
		(width 0.1524)
		(layer "In7.Cu")
		(net "M_A_CS_N2")
	)
	(segment
		(start 143.5608 -58.8518)
		(end 143.5608 -58.1914)
		(width 0.1524)
		(layer "In7.Cu")
		(net "M_A_CS_N2")
	)
	(segment
		(start 67.997324 -40.184324)
		(end 68.921884 -40.184324)
		(width 0.1143)
		(layer "F.Cu")
		(net "SPI_CPU_SCLK")
	)
	(segment
		(start 89.317322 -38.93312)
		(end 89.850468 -38.399974)
		(width 0.1143)
		(layer "F.Cu")
		(net "SPI_CPU_SCLK")
	)
	(segment
		(start 53.745384 -38.0873)
		(end 54.450234 -38.79215)
		(width 0.1143)
		(layer "F.Cu")
		(net "SPI_CPU_SCLK")
	)
	(segment
		(start 58.099452 -38.481508)
		(end 64.821308 -38.481508)
		(width 0.1143)
		(layer "F.Cu")
		(net "SPI_CPU_SCLK")
	)
	(segment
		(start 67.9831 -40.1701)
		(end 67.997324 -40.184324)
		(width 0.1143)
		(layer "F.Cu")
		(net "SPI_CPU_SCLK")
	)
	(segment
		(start 66.963036 -40.005)
		(end 67.128136 -40.1701)
		(width 0.1143)
		(layer "F.Cu")
		(net "SPI_CPU_SCLK")
	)
	(segment
		(start 49.3522 -35.3568)
		(end 49.3522 -36.078668)
		(width 0.1143)
		(layer "F.Cu")
		(net "SPI_CPU_SCLK")
	)
	(segment
		(start 54.450234 -38.79215)
		(end 57.78881 -38.79215)
		(width 0.1143)
		(layer "F.Cu")
		(net "SPI_CPU_SCLK")
	)
	(segment
		(start 66.3448 -40.005)
		(end 66.548 -40.005)
		(width 0.1143)
		(layer "F.Cu")
		(net "SPI_CPU_SCLK")
	)
	(segment
		(start 57.78881 -38.79215)
		(end 58.099452 -38.481508)
		(width 0.1143)
		(layer "F.Cu")
		(net "SPI_CPU_SCLK")
	)
	(segment
		(start 49.3522 -36.078668)
		(end 51.360832 -38.0873)
		(width 0.1143)
		(layer "F.Cu")
		(net "SPI_CPU_SCLK")
	)
	(segment
		(start 51.360832 -38.0873)
		(end 53.745384 -38.0873)
		(width 0.1143)
		(layer "F.Cu")
		(net "SPI_CPU_SCLK")
	)
	(segment
		(start 64.821308 -38.481508)
		(end 66.3448 -40.005)
		(width 0.1143)
		(layer "F.Cu")
		(net "SPI_CPU_SCLK")
	)
	(segment
		(start 67.128136 -40.1701)
		(end 67.9831 -40.1701)
		(width 0.1143)
		(layer "F.Cu")
		(net "SPI_CPU_SCLK")
	)
	(segment
		(start 89.0397 -38.93312)
		(end 89.317322 -38.93312)
		(width 0.1143)
		(layer "F.Cu")
		(net "SPI_CPU_SCLK")
	)
	(segment
		(start 66.548 -40.005)
		(end 66.963036 -40.005)
		(width 0.1143)
		(layer "F.Cu")
		(net "SPI_CPU_SCLK")
	)
	(segment
		(start 68.921884 -40.184324)
		(end 69.18452 -40.44696)
		(width 0.1143)
		(layer "F.Cu")
		(net "SPI_CPU_SCLK")
	)
	(via
		(at 66.548 -40.005)
		(size 0.7112)
		(drill 0.3556)
		(layers "F.Cu" "B.Cu")
		(net "SPI_CPU_SCLK")
	)
	(via
		(at 69.18452 -40.44696)
		(size 0.508)
		(drill 0.254)
		(layers "F.Cu" "B.Cu")
		(net "SPI_CPU_SCLK")
	)
	(via
		(at 89.0397 -38.93312)
		(size 0.4318)
		(drill 0.2032)
		(layers "F.Cu" "B.Cu")
		(net "SPI_CPU_SCLK")
	)
	(segment
		(start 88.060784 -40.6654)
		(end 86.23681 -40.6654)
		(width 0.0889)
		(layer "In2.Cu")
		(net "SPI_CPU_SCLK")
	)
	(segment
		(start 70.364858 -37.97935)
		(end 70.104 -38.240208)
		(width 0.0889)
		(layer "In2.Cu")
		(net "SPI_CPU_SCLK")
	)
	(segment
		(start 85.933788 -41.891712)
		(end 85.159596 -42.665904)
		(width 0.0889)
		(layer "In2.Cu")
		(net "SPI_CPU_SCLK")
	)
	(segment
		(start 82.709004 -42.712132)
		(end 79.796132 -42.712132)
		(width 0.0889)
		(layer "In2.Cu")
		(net "SPI_CPU_SCLK")
	)
	(segment
		(start 86.23681 -40.6654)
		(end 85.93455 -40.96766)
		(width 0.0889)
		(layer "In2.Cu")
		(net "SPI_CPU_SCLK")
	)
	(segment
		(start 85.93455 -41.196514)
		(end 85.933788 -41.197276)
		(width 0.0889)
		(layer "In2.Cu")
		(net "SPI_CPU_SCLK")
	)
	(segment
		(start 70.104 -38.240208)
		(end 70.104 -39.80561)
		(width 0.0889)
		(layer "In2.Cu")
		(net "SPI_CPU_SCLK")
	)
	(segment
		(start 79.796132 -42.712132)
		(end 75.06335 -37.97935)
		(width 0.0889)
		(layer "In2.Cu")
		(net "SPI_CPU_SCLK")
	)
	(segment
		(start 85.159596 -42.665904)
		(end 82.755232 -42.665904)
		(width 0.0889)
		(layer "In2.Cu")
		(net "SPI_CPU_SCLK")
	)
	(segment
		(start 70.104 -39.80561)
		(end 69.46265 -40.44696)
		(width 0.0889)
		(layer "In2.Cu")
		(net "SPI_CPU_SCLK")
	)
	(segment
		(start 69.46265 -40.44696)
		(end 69.18452 -40.44696)
		(width 0.0889)
		(layer "In2.Cu")
		(net "SPI_CPU_SCLK")
	)
	(segment
		(start 82.755232 -42.665904)
		(end 82.709004 -42.712132)
		(width 0.0889)
		(layer "In2.Cu")
		(net "SPI_CPU_SCLK")
	)
	(segment
		(start 75.06335 -37.97935)
		(end 70.364858 -37.97935)
		(width 0.0889)
		(layer "In2.Cu")
		(net "SPI_CPU_SCLK")
	)
	(segment
		(start 88.676226 -40.049958)
		(end 88.060784 -40.6654)
		(width 0.0889)
		(layer "In2.Cu")
		(net "SPI_CPU_SCLK")
	)
	(segment
		(start 85.933788 -41.197276)
		(end 85.933788 -41.891712)
		(width 0.0889)
		(layer "In2.Cu")
		(net "SPI_CPU_SCLK")
	)
	(segment
		(start 89.0397 -38.93312)
		(end 89.01176 -38.93312)
		(width 0.0889)
		(layer "In2.Cu")
		(net "SPI_CPU_SCLK")
	)
	(segment
		(start 85.93455 -40.96766)
		(end 85.93455 -41.196514)
		(width 0.0889)
		(layer "In2.Cu")
		(net "SPI_CPU_SCLK")
	)
	(segment
		(start 89.01176 -38.93312)
		(end 88.676226 -39.268654)
		(width 0.0889)
		(layer "In2.Cu")
		(net "SPI_CPU_SCLK")
	)
	(segment
		(start 88.676226 -39.268654)
		(end 88.676226 -40.049958)
		(width 0.0889)
		(layer "In2.Cu")
		(net "SPI_CPU_SCLK")
	)
	(segment
		(start 109.380782 -11.362182)
		(end 108.93425 -10.91565)
		(width 0.1143)
		(layer "F.Cu")
		(net "IRQ_CPU_SERIAL")
	)
	(segment
		(start 111.911638 -11.362182)
		(end 109.380782 -11.362182)
		(width 0.1143)
		(layer "F.Cu")
		(net "IRQ_CPU_SERIAL")
	)
	(segment
		(start 88.1888 -43.753786)
		(end 88.1888 -44.2722)
		(width 0.1143)
		(layer "F.Cu")
		(net "IRQ_CPU_SERIAL")
	)
	(segment
		(start 87.838788 -43.403774)
		(end 88.1888 -43.753786)
		(width 0.1143)
		(layer "F.Cu")
		(net "IRQ_CPU_SERIAL")
	)
	(segment
		(start 129.44856 -32.29356)
		(end 125.0696 -27.9146)
		(width 0.1143)
		(layer "F.Cu")
		(net "IRQ_CPU_SERIAL")
	)
	(segment
		(start 117.182646 -16.63319)
		(end 111.911638 -11.362182)
		(width 0.1143)
		(layer "F.Cu")
		(net "IRQ_CPU_SERIAL")
	)
	(segment
		(start 117.182646 -22.547072)
		(end 117.182646 -16.63319)
		(width 0.1143)
		(layer "F.Cu")
		(net "IRQ_CPU_SERIAL")
	)
	(segment
		(start 132.1308 -32.29356)
		(end 129.44856 -32.29356)
		(width 0.1143)
		(layer "F.Cu")
		(net "IRQ_CPU_SERIAL")
	)
	(segment
		(start 122.550174 -27.9146)
		(end 117.182646 -22.547072)
		(width 0.1143)
		(layer "F.Cu")
		(net "IRQ_CPU_SERIAL")
	)
	(segment
		(start 107.832144 -9.813544)
		(end 108.93425 -10.91565)
		(width 0.1143)
		(layer "F.Cu")
		(net "IRQ_CPU_SERIAL")
	)
	(segment
		(start 107.832144 -8.8392)
		(end 107.832144 -9.813544)
		(width 0.1143)
		(layer "F.Cu")
		(net "IRQ_CPU_SERIAL")
	)
	(segment
		(start 125.0696 -27.9146)
		(end 122.550174 -27.9146)
		(width 0.1143)
		(layer "F.Cu")
		(net "IRQ_CPU_SERIAL")
	)
	(via
		(at 107.832144 -8.8392)
		(size 0.508)
		(drill 0.254)
		(layers "F.Cu" "B.Cu")
		(net "IRQ_CPU_SERIAL")
	)
	(via
		(at 108.93425 -10.91565)
		(size 0.7112)
		(drill 0.3556)
		(layers "F.Cu" "B.Cu")
		(net "IRQ_CPU_SERIAL")
	)
	(via
		(at 88.1888 -44.2722)
		(size 0.4318)
		(drill 0.2032)
		(layers "F.Cu" "B.Cu")
		(net "IRQ_CPU_SERIAL")
	)
	(segment
		(start 108.97235 -11.63955)
		(end 108.97235 -9.979406)
		(width 0.1143)
		(layer "B.Cu")
		(net "IRQ_CPU_SERIAL")
	)
	(segment
		(start 89.154 -45.7962)
		(end 88.392 -45.7962)
		(width 0.1143)
		(layer "B.Cu")
		(net "IRQ_CPU_SERIAL")
	)
	(segment
		(start 108.97235 -9.979406)
		(end 107.832144 -8.8392)
		(width 0.1143)
		(layer "B.Cu")
		(net "IRQ_CPU_SERIAL")
	)
	(segment
		(start 88.392 -45.7962)
		(end 88.1888 -45.593)
		(width 0.1143)
		(layer "B.Cu")
		(net "IRQ_CPU_SERIAL")
	)
	(segment
		(start 110.236 -12.9032)
		(end 108.97235 -11.63955)
		(width 0.1143)
		(layer "B.Cu")
		(net "IRQ_CPU_SERIAL")
	)
	(segment
		(start 88.1888 -45.593)
		(end 88.1888 -44.2722)
		(width 0.1143)
		(layer "B.Cu")
		(net "IRQ_CPU_SERIAL")
	)
	(segment
		(start 91.971114 -38.33495)
		(end 91.53525 -38.33495)
		(width 0.0889)
		(layer "In2.Cu")
		(net "IRQ_CPU_SERIAL")
	)
	(segment
		(start 88.29167 -16.7132)
		(end 86.795356 -18.209514)
		(width 0.0889)
		(layer "In2.Cu")
		(net "IRQ_CPU_SERIAL")
	)
	(segment
		(start 107.95 -8.957056)
		(end 107.95 -11.640566)
		(width 0.0889)
		(layer "In2.Cu")
		(net "IRQ_CPU_SERIAL")
	)
	(segment
		(start 90.6526 -39.2176)
		(end 90.6526 -39.8272)
		(width 0.0889)
		(layer "In2.Cu")
		(net "IRQ_CPU_SERIAL")
	)
	(segment
		(start 91.74734 -37.61105)
		(end 91.971114 -37.61105)
		(width 0.0889)
		(layer "In2.Cu")
		(net "IRQ_CPU_SERIAL")
	)
	(segment
		(start 90.2208 -40.259)
		(end 90.2208 -43.387264)
		(width 0.0889)
		(layer "In2.Cu")
		(net "IRQ_CPU_SERIAL")
	)
	(segment
		(start 90.2208 -43.387264)
		(end 89.335864 -44.2722)
		(width 0.0889)
		(layer "In2.Cu")
		(net "IRQ_CPU_SERIAL")
	)
	(segment
		(start 90.9574 -16.7132)
		(end 88.29167 -16.7132)
		(width 0.0889)
		(layer "In2.Cu")
		(net "IRQ_CPU_SERIAL")
	)
	(segment
		(start 86.795356 -18.209514)
		(end 86.795356 -21.237956)
		(width 0.0889)
		(layer "In2.Cu")
		(net "IRQ_CPU_SERIAL")
	)
	(segment
		(start 90.39225 -28.212034)
		(end 90.39225 -33.619186)
		(width 0.0889)
		(layer "In2.Cu")
		(net "IRQ_CPU_SERIAL")
	)
	(segment
		(start 91.494356 -37.358066)
		(end 91.74734 -37.61105)
		(width 0.0889)
		(layer "In2.Cu")
		(net "IRQ_CPU_SERIAL")
	)
	(segment
		(start 91.494356 -34.721292)
		(end 91.494356 -37.358066)
		(width 0.0889)
		(layer "In2.Cu")
		(net "IRQ_CPU_SERIAL")
	)
	(segment
		(start 91.53525 -38.33495)
		(end 90.6526 -39.2176)
		(width 0.0889)
		(layer "In2.Cu")
		(net "IRQ_CPU_SERIAL")
	)
	(segment
		(start 90.6526 -39.8272)
		(end 90.2208 -40.259)
		(width 0.0889)
		(layer "In2.Cu")
		(net "IRQ_CPU_SERIAL")
	)
	(segment
		(start 91.971114 -37.61105)
		(end 92.18295 -37.822886)
		(width 0.0889)
		(layer "In2.Cu")
		(net "IRQ_CPU_SERIAL")
	)
	(segment
		(start 107.832144 -8.8392)
		(end 107.95 -8.957056)
		(width 0.0889)
		(layer "In2.Cu")
		(net "IRQ_CPU_SERIAL")
	)
	(segment
		(start 92.18295 -37.822886)
		(end 92.18295 -38.123114)
		(width 0.0889)
		(layer "In2.Cu")
		(net "IRQ_CPU_SERIAL")
	)
	(segment
		(start 107.95 -11.640566)
		(end 105.432606 -14.15796)
		(width 0.0889)
		(layer "In2.Cu")
		(net "IRQ_CPU_SERIAL")
	)
	(segment
		(start 90.39225 -33.619186)
		(end 91.494356 -34.721292)
		(width 0.0889)
		(layer "In2.Cu")
		(net "IRQ_CPU_SERIAL")
	)
	(segment
		(start 105.10647 -14.15796)
		(end 105.106216 -14.157706)
		(width 0.0889)
		(layer "In2.Cu")
		(net "IRQ_CPU_SERIAL")
	)
	(segment
		(start 92.18295 -38.123114)
		(end 91.971114 -38.33495)
		(width 0.0889)
		(layer "In2.Cu")
		(net "IRQ_CPU_SERIAL")
	)
	(segment
		(start 105.106216 -14.157706)
		(end 93.512894 -14.157706)
		(width 0.0889)
		(layer "In2.Cu")
		(net "IRQ_CPU_SERIAL")
	)
	(segment
		(start 86.795356 -21.237956)
		(end 88.6714 -23.114)
		(width 0.0889)
		(layer "In2.Cu")
		(net "IRQ_CPU_SERIAL")
	)
	(segment
		(start 89.335864 -44.2722)
		(end 88.1888 -44.2722)
		(width 0.0889)
		(layer "In2.Cu")
		(net "IRQ_CPU_SERIAL")
	)
	(segment
		(start 88.6714 -23.114)
		(end 88.6714 -26.491184)
		(width 0.0889)
		(layer "In2.Cu")
		(net "IRQ_CPU_SERIAL")
	)
	(segment
		(start 105.432606 -14.15796)
		(end 105.10647 -14.15796)
		(width 0.0889)
		(layer "In2.Cu")
		(net "IRQ_CPU_SERIAL")
	)
	(segment
		(start 88.6714 -26.491184)
		(end 90.39225 -28.212034)
		(width 0.0889)
		(layer "In2.Cu")
		(net "IRQ_CPU_SERIAL")
	)
	(segment
		(start 93.512894 -14.157706)
		(end 90.9574 -16.7132)
		(width 0.0889)
		(layer "In2.Cu")
		(net "IRQ_CPU_SERIAL")
	)
	(segment
		(start 22.4536 -48.895)
		(end 22.0726 -48.514)
		(width 0.2032)
		(layer "F.Cu")
		(net "VR_PVCCP_ISUMN_R2")
	)
	(segment
		(start 23.3172 -48.895)
		(end 22.4536 -48.895)
		(width 0.2032)
		(layer "F.Cu")
		(net "VR_PVCCP_ISUMN_R2")
	)
	(via
		(at 29.7688 -54.9656)
		(size 0.7112)
		(drill 0.3556)
		(layers "F.Cu" "B.Cu")
		(net "VR_PVCCP_ISUMN_R2")
	)
	(via
		(at 22.0726 -48.514)
		(size 0.508)
		(drill 0.254)
		(layers "F.Cu" "B.Cu")
		(net "VR_PVCCP_ISUMN_R2")
	)
	(segment
		(start 28.5242 -53.721)
		(end 27.051 -53.721)
		(width 0.2032)
		(layer "B.Cu")
		(net "VR_PVCCP_ISUMN_R2")
	)
	(segment
		(start 47.658274 -55.53075)
		(end 47.118524 -54.991)
		(width 0.2032)
		(layer "B.Cu")
		(net "VR_PVCCP_ISUMN_R2")
	)
	(segment
		(start 29.7688 -54.9656)
		(end 28.5242 -53.721)
		(width 0.2032)
		(layer "B.Cu")
		(net "VR_PVCCP_ISUMN_R2")
	)
	(segment
		(start 35.222434 -54.991)
		(end 34.841434 -55.372)
		(width 0.2032)
		(layer "B.Cu")
		(net "VR_PVCCP_ISUMN_R2")
	)
	(segment
		(start 47.118524 -54.991)
		(end 35.222434 -54.991)
		(width 0.2032)
		(layer "B.Cu")
		(net "VR_PVCCP_ISUMN_R2")
	)
	(segment
		(start 49.264316 -55.53075)
		(end 47.658274 -55.53075)
		(width 0.2032)
		(layer "B.Cu")
		(net "VR_PVCCP_ISUMN_R2")
	)
	(segment
		(start 27.051 -53.721)
		(end 22.0726 -48.7426)
		(width 0.2032)
		(layer "B.Cu")
		(net "VR_PVCCP_ISUMN_R2")
	)
	(segment
		(start 22.0726 -48.7426)
		(end 22.0726 -48.514)
		(width 0.2032)
		(layer "B.Cu")
		(net "VR_PVCCP_ISUMN_R2")
	)
	(segment
		(start 34.841434 -55.372)
		(end 30.1752 -55.372)
		(width 0.2032)
		(layer "B.Cu")
		(net "VR_PVCCP_ISUMN_R2")
	)
	(segment
		(start 51.181 -58.3438)
		(end 51.181 -57.447434)
		(width 0.2032)
		(layer "B.Cu")
		(net "VR_PVCCP_ISUMN_R2")
	)
	(segment
		(start 30.1752 -55.372)
		(end 29.7688 -54.9656)
		(width 0.2032)
		(layer "B.Cu")
		(net "VR_PVCCP_ISUMN_R2")
	)
	(segment
		(start 51.3842 -58.547)
		(end 51.181 -58.3438)
		(width 0.2032)
		(layer "B.Cu")
		(net "VR_PVCCP_ISUMN_R2")
	)
	(segment
		(start 51.181 -57.447434)
		(end 49.264316 -55.53075)
		(width 0.2032)
		(layer "B.Cu")
		(net "VR_PVCCP_ISUMN_R2")
	)
	(segment
		(start 165.402514 -69.940678)
		(end 165.402514 -66.936874)
		(width 0.1778)
		(layer "F.Cu")
		(net "M_A_DQS_DN8")
	)
	(segment
		(start 114.787172 -49.0982)
		(end 112.631728 -46.942756)
		(width 0.1016)
		(layer "F.Cu")
		(net "M_A_DQS_DN8")
	)
	(segment
		(start 111.060738 -46.178724)
		(end 110.749588 -46.489874)
		(width 0.1016)
		(layer "F.Cu")
		(net "M_A_DQS_DN8")
	)
	(segment
		(start 165.550088 -70.806564)
		(end 165.550088 -70.088252)
		(width 0.1778)
		(layer "F.Cu")
		(net "M_A_DQS_DN8")
	)
	(segment
		(start 112.631728 -46.942756)
		(end 112.631728 -46.617128)
		(width 0.1016)
		(layer "F.Cu")
		(net "M_A_DQS_DN8")
	)
	(segment
		(start 112.631728 -46.617128)
		(end 112.193324 -46.178724)
		(width 0.1016)
		(layer "F.Cu")
		(net "M_A_DQS_DN8")
	)
	(segment
		(start 115.1636 -49.0982)
		(end 114.787172 -49.0982)
		(width 0.1016)
		(layer "F.Cu")
		(net "M_A_DQS_DN8")
	)
	(segment
		(start 112.193324 -46.178724)
		(end 111.060738 -46.178724)
		(width 0.1016)
		(layer "F.Cu")
		(net "M_A_DQS_DN8")
	)
	(segment
		(start 165.402514 -66.936874)
		(end 165.667182 -66.672206)
		(width 0.1778)
		(layer "F.Cu")
		(net "M_A_DQS_DN8")
	)
	(segment
		(start 165.550088 -70.088252)
		(end 165.402514 -69.940678)
		(width 0.1778)
		(layer "F.Cu")
		(net "M_A_DQS_DN8")
	)
	(via
		(at 165.667182 -66.672206)
		(size 0.4318)
		(drill 0.2032)
		(layers "F.Cu" "B.Cu")
		(net "M_A_DQS_DN8")
	)
	(via
		(at 115.1636 -49.0982)
		(size 0.4318)
		(drill 0.2032)
		(layers "F.Cu" "B.Cu")
		(net "M_A_DQS_DN8")
	)
	(segment
		(start 165.550088 -63.688976)
		(end 165.402514 -63.83655)
		(width 0.1778)
		(layer "B.Cu")
		(net "M_A_DQS_DN8")
	)
	(segment
		(start 165.550088 -62.599824)
		(end 165.550088 -63.688976)
		(width 0.1778)
		(layer "B.Cu")
		(net "M_A_DQS_DN8")
	)
	(segment
		(start 165.402514 -66.407538)
		(end 165.667182 -66.672206)
		(width 0.1778)
		(layer "B.Cu")
		(net "M_A_DQS_DN8")
	)
	(segment
		(start 165.402514 -63.83655)
		(end 165.402514 -66.407538)
		(width 0.1778)
		(layer "B.Cu")
		(net "M_A_DQS_DN8")
	)
	(segment
		(start 166.86784 -63.36792)
		(end 166.4208 -62.92088)
		(width 0.1524)
		(layer "In2.Cu")
		(net "M_A_DQS_DN8")
	)
	(segment
		(start 147.35302 -51.250596)
		(end 146.97329 -50.870866)
		(width 0.1524)
		(layer "In2.Cu")
		(net "M_A_DQS_DN8")
	)
	(segment
		(start 165.377622 -65.8495)
		(end 166.86784 -64.359282)
		(width 0.1524)
		(layer "In2.Cu")
		(net "M_A_DQS_DN8")
	)
	(segment
		(start 166.4208 -61.075062)
		(end 160.412938 -55.0672)
		(width 0.1524)
		(layer "In2.Cu")
		(net "M_A_DQS_DN8")
	)
	(segment
		(start 152.4 -55.3212)
		(end 147.8534 -55.3212)
		(width 0.1524)
		(layer "In2.Cu")
		(net "M_A_DQS_DN8")
	)
	(segment
		(start 160.412938 -55.0672)
		(end 154.121612 -55.0672)
		(width 0.1524)
		(layer "In2.Cu")
		(net "M_A_DQS_DN8")
	)
	(segment
		(start 146.52625 -50.870866)
		(end 145.810224 -51.587146)
		(width 0.1524)
		(layer "In2.Cu")
		(net "M_A_DQS_DN8")
	)
	(segment
		(start 166.86784 -64.359282)
		(end 166.86784 -63.36792)
		(width 0.1524)
		(layer "In2.Cu")
		(net "M_A_DQS_DN8")
	)
	(segment
		(start 118.88216 -49.800256)
		(end 117.776752 -48.694848)
		(width 0.1016)
		(layer "In2.Cu")
		(net "M_A_DQS_DN8")
	)
	(segment
		(start 147.5994 -53.591714)
		(end 146.636994 -52.629308)
		(width 0.1524)
		(layer "In2.Cu")
		(net "M_A_DQS_DN8")
	)
	(segment
		(start 153.677112 -55.5117)
		(end 152.5905 -55.5117)
		(width 0.1524)
		(layer "In2.Cu")
		(net "M_A_DQS_DN8")
	)
	(segment
		(start 165.377622 -66.382646)
		(end 165.377622 -65.8495)
		(width 0.1524)
		(layer "In2.Cu")
		(net "M_A_DQS_DN8")
	)
	(segment
		(start 147.8534 -55.3212)
		(end 147.5994 -55.0672)
		(width 0.1524)
		(layer "In2.Cu")
		(net "M_A_DQS_DN8")
	)
	(segment
		(start 154.121612 -55.0672)
		(end 153.677112 -55.5117)
		(width 0.1524)
		(layer "In2.Cu")
		(net "M_A_DQS_DN8")
	)
	(segment
		(start 146.97329 -50.870866)
		(end 146.52625 -50.870866)
		(width 0.1524)
		(layer "In2.Cu")
		(net "M_A_DQS_DN8")
	)
	(segment
		(start 115.566952 -48.694848)
		(end 115.1636 -49.0982)
		(width 0.1016)
		(layer "In2.Cu")
		(net "M_A_DQS_DN8")
	)
	(segment
		(start 146.636994 -52.413916)
		(end 147.35302 -51.697636)
		(width 0.1524)
		(layer "In2.Cu")
		(net "M_A_DQS_DN8")
	)
	(segment
		(start 145.594832 -51.587146)
		(end 143.807942 -49.800256)
		(width 0.1524)
		(layer "In2.Cu")
		(net "M_A_DQS_DN8")
	)
	(segment
		(start 147.5994 -55.0672)
		(end 147.5994 -53.591714)
		(width 0.1524)
		(layer "In2.Cu")
		(net "M_A_DQS_DN8")
	)
	(segment
		(start 165.667182 -66.672206)
		(end 165.377622 -66.382646)
		(width 0.1524)
		(layer "In2.Cu")
		(net "M_A_DQS_DN8")
	)
	(segment
		(start 143.807942 -49.800256)
		(end 119.0244 -49.800256)
		(width 0.1524)
		(layer "In2.Cu")
		(net "M_A_DQS_DN8")
	)
	(segment
		(start 117.776752 -48.694848)
		(end 115.566952 -48.694848)
		(width 0.1016)
		(layer "In2.Cu")
		(net "M_A_DQS_DN8")
	)
	(segment
		(start 145.810224 -51.587146)
		(end 145.594832 -51.587146)
		(width 0.1524)
		(layer "In2.Cu")
		(net "M_A_DQS_DN8")
	)
	(segment
		(start 147.35302 -51.697636)
		(end 147.35302 -51.250596)
		(width 0.1524)
		(layer "In2.Cu")
		(net "M_A_DQS_DN8")
	)
	(segment
		(start 119.0244 -49.800256)
		(end 118.88216 -49.800256)
		(width 0.1016)
		(layer "In2.Cu")
		(net "M_A_DQS_DN8")
	)
	(segment
		(start 146.636994 -52.629308)
		(end 146.636994 -52.413916)
		(width 0.1524)
		(layer "In2.Cu")
		(net "M_A_DQS_DN8")
	)
	(segment
		(start 166.4208 -62.92088)
		(end 166.4208 -61.075062)
		(width 0.1524)
		(layer "In2.Cu")
		(net "M_A_DQS_DN8")
	)
	(segment
		(start 152.5905 -55.5117)
		(end 152.4 -55.3212)
		(width 0.1524)
		(layer "In2.Cu")
		(net "M_A_DQS_DN8")
	)
	(segment
		(start 95.448628 -43.743372)
		(end 95.448628 -44.000674)
		(width 0.127)
		(layer "F.Cu")
		(net "TP_CPU_RSVD0")
	)
	(segment
		(start 95.885 -41.97096)
		(end 95.8342 -42.02176)
		(width 0.127)
		(layer "F.Cu")
		(net "TP_CPU_RSVD0")
	)
	(segment
		(start 95.8342 -42.02176)
		(end 95.8342 -43.3578)
		(width 0.127)
		(layer "F.Cu")
		(net "TP_CPU_RSVD0")
	)
	(segment
		(start 95.8342 -43.3578)
		(end 95.448628 -43.743372)
		(width 0.127)
		(layer "F.Cu")
		(net "TP_CPU_RSVD0")
	)
	(via
		(at 95.885 -41.97096)
		(size 0.4318)
		(drill 0.2032)
		(layers "F.Cu" "B.Cu")
		(net "TP_CPU_RSVD0")
	)
	(segment
		(start 95.3262 -42.30243)
		(end 95.55353 -42.30243)
		(width 0.127)
		(layer "B.Cu")
		(net "TP_CPU_RSVD0")
	)
	(segment
		(start 95.55353 -42.30243)
		(end 95.885 -41.97096)
		(width 0.127)
		(layer "B.Cu")
		(net "TP_CPU_RSVD0")
	)
	(segment
		(start 18.8976 -64.1604)
		(end 18.914618 -64.143382)
		(width 0.2032)
		(layer "F.Cu")
		(net "VR_PVNN_COMP")
	)
	(segment
		(start 17.6276 -62.484)
		(end 18.023332 -62.484)
		(width 0.2032)
		(layer "F.Cu")
		(net "VR_PVNN_COMP")
	)
	(segment
		(start 17.6276 -62.3062)
		(end 17.6276 -62.484)
		(width 0.2032)
		(layer "F.Cu")
		(net "VR_PVNN_COMP")
	)
	(segment
		(start 18.023332 -62.484)
		(end 18.914618 -63.375286)
		(width 0.2032)
		(layer "F.Cu")
		(net "VR_PVNN_COMP")
	)
	(segment
		(start 19.263106 -61.292994)
		(end 18.640806 -61.292994)
		(width 0.2032)
		(layer "F.Cu")
		(net "VR_PVNN_COMP")
	)
	(segment
		(start 18.914618 -64.143382)
		(end 18.914618 -63.375286)
		(width 0.2032)
		(layer "F.Cu")
		(net "VR_PVNN_COMP")
	)
	(segment
		(start 18.640806 -61.292994)
		(end 17.6276 -62.3062)
		(width 0.2032)
		(layer "F.Cu")
		(net "VR_PVNN_COMP")
	)
	(via
		(at 17.3736 -61.3664)
		(size 0.7112)
		(drill 0.3556)
		(layers "F.Cu" "B.Cu")
		(net "VR_PVNN_COMP")
	)
	(via
		(at 17.6276 -62.484)
		(size 0.508)
		(drill 0.254)
		(layers "F.Cu" "B.Cu")
		(net "VR_PVNN_COMP")
	)
	(segment
		(start 18.2372 -61.3918)
		(end 17.399 -61.3918)
		(width 0.2032)
		(layer "B.Cu")
		(net "VR_PVNN_COMP")
	)
	(segment
		(start 17.399 -61.3918)
		(end 17.3736 -61.3664)
		(width 0.2032)
		(layer "B.Cu")
		(net "VR_PVNN_COMP")
	)
	(segment
		(start 18.2372 -61.6204)
		(end 17.6276 -62.23)
		(width 0.2032)
		(layer "B.Cu")
		(net "VR_PVNN_COMP")
	)
	(segment
		(start 18.2372 -61.3918)
		(end 18.2372 -61.6204)
		(width 0.2032)
		(layer "B.Cu")
		(net "VR_PVNN_COMP")
	)
	(segment
		(start 17.272 -60.5282)
		(end 17.272 -61.2648)
		(width 0.2032)
		(layer "B.Cu")
		(net "VR_PVNN_COMP")
	)
	(segment
		(start 17.6276 -62.23)
		(end 17.6276 -62.484)
		(width 0.2032)
		(layer "B.Cu")
		(net "VR_PVNN_COMP")
	)
	(segment
		(start 17.272 -61.2648)
		(end 17.3736 -61.3664)
		(width 0.2032)
		(layer "B.Cu")
		(net "VR_PVNN_COMP")
	)
	(segment
		(start 94.791784 -52.891944)
		(end 94.791784 -52.371498)
		(width 0.1016)
		(layer "F.Cu")
		(net "M_A_DQ58")
	)
	(segment
		(start 94.25686 -55.19166)
		(end 94.25686 -53.426868)
		(width 0.1016)
		(layer "F.Cu")
		(net "M_A_DQ58")
	)
	(segment
		(start 93.87332 -55.5752)
		(end 94.25686 -55.19166)
		(width 0.1016)
		(layer "F.Cu")
		(net "M_A_DQ58")
	)
	(segment
		(start 94.791784 -52.371498)
		(end 94.986348 -52.176934)
		(width 0.1016)
		(layer "F.Cu")
		(net "M_A_DQ58")
	)
	(segment
		(start 130.450082 -62.59322)
		(end 130.450082 -64.90589)
		(width 0.1778)
		(layer "F.Cu")
		(net "M_A_DQ58")
	)
	(segment
		(start 130.450082 -64.90589)
		(end 130.590798 -65.046606)
		(width 0.1778)
		(layer "F.Cu")
		(net "M_A_DQ58")
	)
	(segment
		(start 94.986348 -52.176934)
		(end 94.986348 -52.006754)
		(width 0.1016)
		(layer "F.Cu")
		(net "M_A_DQ58")
	)
	(segment
		(start 94.25686 -53.426868)
		(end 94.791784 -52.891944)
		(width 0.1016)
		(layer "F.Cu")
		(net "M_A_DQ58")
	)
	(via
		(at 130.590798 -65.046606)
		(size 0.4318)
		(drill 0.2032)
		(layers "F.Cu" "B.Cu")
		(net "M_A_DQ58")
	)
	(via
		(at 93.87332 -55.5752)
		(size 0.4318)
		(drill 0.2032)
		(layers "F.Cu" "B.Cu")
		(net "M_A_DQ58")
	)
	(segment
		(start 130.750056 -64.887348)
		(end 130.590798 -65.046606)
		(width 0.1778)
		(layer "B.Cu")
		(net "M_A_DQ58")
	)
	(segment
		(start 130.750056 -62.599824)
		(end 130.750056 -64.887348)
		(width 0.1778)
		(layer "B.Cu")
		(net "M_A_DQ58")
	)
	(segment
		(start 121.004076 -68.3514)
		(end 121.004076 -68.5546)
		(width 0.1524)
		(layer "In7.Cu")
		(net "M_A_DQ58")
	)
	(segment
		(start 100.196142 -68.199)
		(end 120.851676 -68.199)
		(width 0.1524)
		(layer "In7.Cu")
		(net "M_A_DQ58")
	)
	(segment
		(start 122.070876 -68.199)
		(end 122.223276 -68.3514)
		(width 0.1524)
		(layer "In7.Cu")
		(net "M_A_DQ58")
	)
	(segment
		(start 93.3196 -57.252108)
		(end 93.3196 -62.433454)
		(width 0.1524)
		(layer "In7.Cu")
		(net "M_A_DQ58")
	)
	(segment
		(start 97.087944 -65.433194)
		(end 96.811338 -65.7098)
		(width 0.1524)
		(layer "In7.Cu")
		(net "M_A_DQ58")
	)
	(segment
		(start 97.087944 -65.217802)
		(end 97.087944 -65.433194)
		(width 0.1524)
		(layer "In7.Cu")
		(net "M_A_DQ58")
	)
	(segment
		(start 122.985276 -68.199)
		(end 123.569476 -68.199)
		(width 0.1524)
		(layer "In7.Cu")
		(net "M_A_DQ58")
	)
	(segment
		(start 122.223276 -68.5546)
		(end 122.375676 -68.707)
		(width 0.1524)
		(layer "In7.Cu")
		(net "M_A_DQ58")
	)
	(segment
		(start 96.811338 -65.7098)
		(end 96.811338 -65.925192)
		(width 0.1524)
		(layer "In7.Cu")
		(net "M_A_DQ58")
	)
	(segment
		(start 93.87332 -55.5752)
		(end 93.87332 -56.698388)
		(width 0.1524)
		(layer "In7.Cu")
		(net "M_A_DQ58")
	)
	(segment
		(start 99.113848 -67.7926)
		(end 99.789742 -67.7926)
		(width 0.1524)
		(layer "In7.Cu")
		(net "M_A_DQ58")
	)
	(segment
		(start 96.811338 -65.925192)
		(end 97.027238 -66.141092)
		(width 0.1524)
		(layer "In7.Cu")
		(net "M_A_DQ58")
	)
	(segment
		(start 121.613676 -68.3514)
		(end 121.766076 -68.199)
		(width 0.1524)
		(layer "In7.Cu")
		(net "M_A_DQ58")
	)
	(segment
		(start 122.680476 -68.707)
		(end 122.832876 -68.5546)
		(width 0.1524)
		(layer "In7.Cu")
		(net "M_A_DQ58")
	)
	(segment
		(start 126.9746 -67.401948)
		(end 129.782824 -64.593724)
		(width 0.1524)
		(layer "In7.Cu")
		(net "M_A_DQ58")
	)
	(segment
		(start 121.004076 -68.5546)
		(end 121.156476 -68.707)
		(width 0.1524)
		(layer "In7.Cu")
		(net "M_A_DQ58")
	)
	(segment
		(start 93.87332 -56.698388)
		(end 93.3196 -57.252108)
		(width 0.1524)
		(layer "In7.Cu")
		(net "M_A_DQ58")
	)
	(segment
		(start 99.789742 -67.7926)
		(end 100.196142 -68.199)
		(width 0.1524)
		(layer "In7.Cu")
		(net "M_A_DQ58")
	)
	(segment
		(start 122.223276 -68.3514)
		(end 122.223276 -68.5546)
		(width 0.1524)
		(layer "In7.Cu")
		(net "M_A_DQ58")
	)
	(segment
		(start 123.569476 -68.199)
		(end 124.178568 -68.808092)
		(width 0.1524)
		(layer "In7.Cu")
		(net "M_A_DQ58")
	)
	(segment
		(start 97.519236 -65.864486)
		(end 97.734628 -65.864486)
		(width 0.1524)
		(layer "In7.Cu")
		(net "M_A_DQ58")
	)
	(segment
		(start 122.832876 -68.5546)
		(end 122.832876 -68.3514)
		(width 0.1524)
		(layer "In7.Cu")
		(net "M_A_DQ58")
	)
	(segment
		(start 96.380046 -65.278508)
		(end 96.656652 -65.001902)
		(width 0.1524)
		(layer "In7.Cu")
		(net "M_A_DQ58")
	)
	(segment
		(start 97.24263 -66.141092)
		(end 97.519236 -65.864486)
		(width 0.1524)
		(layer "In7.Cu")
		(net "M_A_DQ58")
	)
	(segment
		(start 121.766076 -68.199)
		(end 122.070876 -68.199)
		(width 0.1524)
		(layer "In7.Cu")
		(net "M_A_DQ58")
	)
	(segment
		(start 122.375676 -68.707)
		(end 122.680476 -68.707)
		(width 0.1524)
		(layer "In7.Cu")
		(net "M_A_DQ58")
	)
	(segment
		(start 126.416308 -68.808092)
		(end 126.9746 -68.2498)
		(width 0.1524)
		(layer "In7.Cu")
		(net "M_A_DQ58")
	)
	(segment
		(start 129.782824 -64.593724)
		(end 130.137916 -64.593724)
		(width 0.1524)
		(layer "In7.Cu")
		(net "M_A_DQ58")
	)
	(segment
		(start 121.461276 -68.707)
		(end 121.613676 -68.5546)
		(width 0.1524)
		(layer "In7.Cu")
		(net "M_A_DQ58")
	)
	(segment
		(start 97.734628 -65.864486)
		(end 98.8314 -66.961258)
		(width 0.1524)
		(layer "In7.Cu")
		(net "M_A_DQ58")
	)
	(segment
		(start 93.3196 -62.433454)
		(end 96.164654 -65.278508)
		(width 0.1524)
		(layer "In7.Cu")
		(net "M_A_DQ58")
	)
	(segment
		(start 96.164654 -65.278508)
		(end 96.380046 -65.278508)
		(width 0.1524)
		(layer "In7.Cu")
		(net "M_A_DQ58")
	)
	(segment
		(start 98.8314 -66.961258)
		(end 98.8314 -67.510152)
		(width 0.1524)
		(layer "In7.Cu")
		(net "M_A_DQ58")
	)
	(segment
		(start 96.656652 -65.001902)
		(end 96.872044 -65.001902)
		(width 0.1524)
		(layer "In7.Cu")
		(net "M_A_DQ58")
	)
	(segment
		(start 122.832876 -68.3514)
		(end 122.985276 -68.199)
		(width 0.1524)
		(layer "In7.Cu")
		(net "M_A_DQ58")
	)
	(segment
		(start 97.027238 -66.141092)
		(end 97.24263 -66.141092)
		(width 0.1524)
		(layer "In7.Cu")
		(net "M_A_DQ58")
	)
	(segment
		(start 124.178568 -68.808092)
		(end 126.416308 -68.808092)
		(width 0.1524)
		(layer "In7.Cu")
		(net "M_A_DQ58")
	)
	(segment
		(start 120.851676 -68.199)
		(end 121.004076 -68.3514)
		(width 0.1524)
		(layer "In7.Cu")
		(net "M_A_DQ58")
	)
	(segment
		(start 130.137916 -64.593724)
		(end 130.590798 -65.046606)
		(width 0.1524)
		(layer "In7.Cu")
		(net "M_A_DQ58")
	)
	(segment
		(start 98.8314 -67.510152)
		(end 99.113848 -67.7926)
		(width 0.1524)
		(layer "In7.Cu")
		(net "M_A_DQ58")
	)
	(segment
		(start 96.872044 -65.001902)
		(end 97.087944 -65.217802)
		(width 0.1524)
		(layer "In7.Cu")
		(net "M_A_DQ58")
	)
	(segment
		(start 121.156476 -68.707)
		(end 121.461276 -68.707)
		(width 0.1524)
		(layer "In7.Cu")
		(net "M_A_DQ58")
	)
	(segment
		(start 126.9746 -68.2498)
		(end 126.9746 -67.401948)
		(width 0.1524)
		(layer "In7.Cu")
		(net "M_A_DQ58")
	)
	(segment
		(start 121.613676 -68.5546)
		(end 121.613676 -68.3514)
		(width 0.1524)
		(layer "In7.Cu")
		(net "M_A_DQ58")
	)
	(segment
		(start 87.076788 -38.730174)
		(end 86.71306 -39.093902)
		(width 0.1143)
		(layer "F.Cu")
		(net "LPC_CPU_R_CLKOUT0")
	)
	(segment
		(start 86.71306 -39.093902)
		(end 86.71306 -39.113714)
		(width 0.1143)
		(layer "F.Cu")
		(net "LPC_CPU_R_CLKOUT0")
	)
	(via
		(at 76.3524 -37.9476)
		(size 0.7112)
		(drill 0.3556)
		(layers "F.Cu" "B.Cu")
		(net "LPC_CPU_R_CLKOUT0")
	)
	(via
		(at 86.71306 -39.113714)
		(size 0.4318)
		(drill 0.2032)
		(layers "F.Cu" "B.Cu")
		(net "LPC_CPU_R_CLKOUT0")
	)
	(segment
		(start 86.37524 -39.451534)
		(end 85.061552 -39.451534)
		(width 0.1143)
		(layer "B.Cu")
		(net "LPC_CPU_R_CLKOUT0")
	)
	(segment
		(start 84.74964 -39.139622)
		(end 84.74964 -38.91153)
		(width 0.1143)
		(layer "B.Cu")
		(net "LPC_CPU_R_CLKOUT0")
	)
	(segment
		(start 83.283044 -38.692074)
		(end 83.108546 -38.517576)
		(width 0.1143)
		(layer "B.Cu")
		(net "LPC_CPU_R_CLKOUT0")
	)
	(segment
		(start 84.530184 -38.692074)
		(end 83.283044 -38.692074)
		(width 0.1143)
		(layer "B.Cu")
		(net "LPC_CPU_R_CLKOUT0")
	)
	(segment
		(start 75.565 -37.1348)
		(end 76.3524 -37.9222)
		(width 0.1143)
		(layer "B.Cu")
		(net "LPC_CPU_R_CLKOUT0")
	)
	(segment
		(start 83.108546 -38.517576)
		(end 82.35569 -38.517576)
		(width 0.1143)
		(layer "B.Cu")
		(net "LPC_CPU_R_CLKOUT0")
	)
	(segment
		(start 77.560678 -39.661084)
		(end 76.3524 -38.452806)
		(width 0.1143)
		(layer "B.Cu")
		(net "LPC_CPU_R_CLKOUT0")
	)
	(segment
		(start 85.061552 -39.451534)
		(end 84.74964 -39.139622)
		(width 0.1143)
		(layer "B.Cu")
		(net "LPC_CPU_R_CLKOUT0")
	)
	(segment
		(start 79.728568 -39.277544)
		(end 79.345028 -39.661084)
		(width 0.1143)
		(layer "B.Cu")
		(net "LPC_CPU_R_CLKOUT0")
	)
	(segment
		(start 84.74964 -38.91153)
		(end 84.530184 -38.692074)
		(width 0.1143)
		(layer "B.Cu")
		(net "LPC_CPU_R_CLKOUT0")
	)
	(segment
		(start 86.71306 -39.113714)
		(end 86.37524 -39.451534)
		(width 0.1143)
		(layer "B.Cu")
		(net "LPC_CPU_R_CLKOUT0")
	)
	(segment
		(start 76.3524 -38.452806)
		(end 76.3524 -37.9476)
		(width 0.1143)
		(layer "B.Cu")
		(net "LPC_CPU_R_CLKOUT0")
	)
	(segment
		(start 76.3524 -37.9222)
		(end 76.3524 -37.9476)
		(width 0.1143)
		(layer "B.Cu")
		(net "LPC_CPU_R_CLKOUT0")
	)
	(segment
		(start 82.338164 -38.50005)
		(end 81.717896 -38.50005)
		(width 0.1143)
		(layer "B.Cu")
		(net "LPC_CPU_R_CLKOUT0")
	)
	(segment
		(start 80.940402 -39.277544)
		(end 79.728568 -39.277544)
		(width 0.1143)
		(layer "B.Cu")
		(net "LPC_CPU_R_CLKOUT0")
	)
	(segment
		(start 81.717896 -38.50005)
		(end 80.940402 -39.277544)
		(width 0.1143)
		(layer "B.Cu")
		(net "LPC_CPU_R_CLKOUT0")
	)
	(segment
		(start 82.35569 -38.517576)
		(end 82.338164 -38.50005)
		(width 0.1143)
		(layer "B.Cu")
		(net "LPC_CPU_R_CLKOUT0")
	)
	(segment
		(start 79.345028 -39.661084)
		(end 77.560678 -39.661084)
		(width 0.1143)
		(layer "B.Cu")
		(net "LPC_CPU_R_CLKOUT0")
	)
	(segment
		(start 23.662894 -55.331106)
		(end 24.0792 -54.9148)
		(width 0.2032)
		(layer "F.Cu")
		(net "VR_PVCCP_PROG1")
	)
	(segment
		(start 24.0792 -54.9148)
		(end 24.1808 -54.9148)
		(width 0.2032)
		(layer "F.Cu")
		(net "VR_PVCCP_PROG1")
	)
	(segment
		(start 23.662894 -55.547006)
		(end 23.662894 -55.331106)
		(width 0.2032)
		(layer "F.Cu")
		(net "VR_PVCCP_PROG1")
	)
	(via
		(at 24.1808 -54.9148)
		(size 0.508)
		(drill 0.254)
		(layers "F.Cu" "B.Cu")
		(net "VR_PVCCP_PROG1")
	)
	(via
		(at 24.4348 -55.6514)
		(size 0.7112)
		(drill 0.3556)
		(layers "F.Cu" "B.Cu")
		(net "VR_PVCCP_PROG1")
	)
	(segment
		(start 24.433276 -55.6514)
		(end 24.4348 -55.6514)
		(width 0.2032)
		(layer "B.Cu")
		(net "VR_PVCCP_PROG1")
	)
	(segment
		(start 24.433276 -55.167276)
		(end 24.433276 -55.599076)
		(width 0.2032)
		(layer "B.Cu")
		(net "VR_PVCCP_PROG1")
	)
	(segment
		(start 23.5712 -56.2102)
		(end 23.874476 -56.2102)
		(width 0.2032)
		(layer "B.Cu")
		(net "VR_PVCCP_PROG1")
	)
	(segment
		(start 24.433276 -55.599076)
		(end 24.4348 -55.6006)
		(width 0.2032)
		(layer "B.Cu")
		(net "VR_PVCCP_PROG1")
	)
	(segment
		(start 24.1808 -54.9148)
		(end 24.433276 -55.167276)
		(width 0.2032)
		(layer "B.Cu")
		(net "VR_PVCCP_PROG1")
	)
	(segment
		(start 23.874476 -56.2102)
		(end 24.433276 -55.6514)
		(width 0.2032)
		(layer "B.Cu")
		(net "VR_PVCCP_PROG1")
	)
	(segment
		(start 24.4348 -55.6006)
		(end 24.4348 -55.6514)
		(width 0.2032)
		(layer "B.Cu")
		(net "VR_PVCCP_PROG1")
	)
	(segment
		(start 156.846778 -65.865248)
		(end 156.846778 -66.47434)
		(width 0.2413)
		(layer "F.Cu")
		(net "M_A_MA4")
	)
	(segment
		(start 156.846778 -66.47434)
		(end 156.79547 -66.525648)
		(width 0.2413)
		(layer "F.Cu")
		(net "M_A_MA4")
	)
	(segment
		(start 156.79547 -66.807334)
		(end 156.346398 -67.256406)
		(width 0.2413)
		(layer "F.Cu")
		(net "M_A_MA4")
	)
	(segment
		(start 106.012488 -47.710852)
		(end 106.450638 -48.149002)
		(width 0.2413)
		(layer "F.Cu")
		(net "M_A_MA4")
	)
	(segment
		(start 156.85008 -65.861946)
		(end 156.846778 -65.865248)
		(width 0.2413)
		(layer "F.Cu")
		(net "M_A_MA4")
	)
	(segment
		(start 156.79547 -66.525648)
		(end 156.79547 -66.807334)
		(width 0.2413)
		(layer "F.Cu")
		(net "M_A_MA4")
	)
	(segment
		(start 156.85008 -62.59322)
		(end 156.85008 -65.861946)
		(width 0.2413)
		(layer "F.Cu")
		(net "M_A_MA4")
	)
	(segment
		(start 106.012488 -47.640494)
		(end 106.012488 -47.710852)
		(width 0.2413)
		(layer "F.Cu")
		(net "M_A_MA4")
	)
	(via
		(at 156.346398 -67.256406)
		(size 0.4318)
		(drill 0.2032)
		(layers "F.Cu" "B.Cu")
		(net "M_A_MA4")
	)
	(via
		(at 106.450638 -48.149002)
		(size 0.4318)
		(drill 0.2032)
		(layers "F.Cu" "B.Cu")
		(net "M_A_MA4")
	)
	(segment
		(start 156.85008 -70.79996)
		(end 156.85008 -68.621148)
		(width 0.2413)
		(layer "B.Cu")
		(net "M_A_MA4")
	)
	(segment
		(start 156.85008 -68.621148)
		(end 156.346398 -68.117466)
		(width 0.2413)
		(layer "B.Cu")
		(net "M_A_MA4")
	)
	(segment
		(start 156.346398 -68.117466)
		(end 156.346398 -67.256406)
		(width 0.2413)
		(layer "B.Cu")
		(net "M_A_MA4")
	)
	(segment
		(start 135.466836 -56.87695)
		(end 135.762746 -56.58104)
		(width 0.1905)
		(layer "In9.Cu")
		(net "M_A_MA4")
	)
	(segment
		(start 137.3378 -56.58104)
		(end 137.81024 -56.58104)
		(width 0.1905)
		(layer "In9.Cu")
		(net "M_A_MA4")
	)
	(segment
		(start 107.924854 -54.711854)
		(end 107.924854 -54.8894)
		(width 0.1905)
		(layer "In9.Cu")
		(net "M_A_MA4")
	)
	(segment
		(start 106.067606 -48.53178)
		(end 106.067606 -48.922432)
		(width 0.1016)
		(layer "In9.Cu")
		(net "M_A_MA4")
	)
	(segment
		(start 147.108418 -58.995818)
		(end 148.711412 -58.995818)
		(width 0.1905)
		(layer "In9.Cu")
		(net "M_A_MA4")
	)
	(segment
		(start 148.711412 -58.995818)
		(end 152.4508 -62.735206)
		(width 0.1905)
		(layer "In9.Cu")
		(net "M_A_MA4")
	)
	(segment
		(start 139.698984 -57.06745)
		(end 142.768574 -57.06745)
		(width 0.1905)
		(layer "In9.Cu")
		(net "M_A_MA4")
	)
	(segment
		(start 106.3498 -50.744882)
		(end 106.3498 -52.551838)
		(width 0.1016)
		(layer "In9.Cu")
		(net "M_A_MA4")
	)
	(segment
		(start 136.33704 -56.58104)
		(end 136.63295 -56.87695)
		(width 0.1905)
		(layer "In9.Cu")
		(net "M_A_MA4")
	)
	(segment
		(start 139.212574 -56.58104)
		(end 139.698984 -57.06745)
		(width 0.1905)
		(layer "In9.Cu")
		(net "M_A_MA4")
	)
	(segment
		(start 134.535164 -56.87695)
		(end 135.466836 -56.87695)
		(width 0.1905)
		(layer "In9.Cu")
		(net "M_A_MA4")
	)
	(segment
		(start 143.269462 -57.568338)
		(end 145.680938 -57.568338)
		(width 0.1905)
		(layer "In9.Cu")
		(net "M_A_MA4")
	)
	(segment
		(start 138.49604 -56.896)
		(end 138.811 -56.58104)
		(width 0.1905)
		(layer "In9.Cu")
		(net "M_A_MA4")
	)
	(segment
		(start 155.706064 -67.89674)
		(end 156.346398 -67.256406)
		(width 0.1905)
		(layer "In9.Cu")
		(net "M_A_MA4")
	)
	(segment
		(start 138.811 -56.58104)
		(end 139.212574 -56.58104)
		(width 0.1905)
		(layer "In9.Cu")
		(net "M_A_MA4")
	)
	(segment
		(start 105.919778 -50.31486)
		(end 106.3498 -50.744882)
		(width 0.1016)
		(layer "In9.Cu")
		(net "M_A_MA4")
	)
	(segment
		(start 145.680938 -57.568338)
		(end 147.108418 -58.995818)
		(width 0.1905)
		(layer "In9.Cu")
		(net "M_A_MA4")
	)
	(segment
		(start 105.37444 -49.49444)
		(end 105.37444 -49.8602)
		(width 0.1016)
		(layer "In9.Cu")
		(net "M_A_MA4")
	)
	(segment
		(start 109.531404 -56.49595)
		(end 134.154164 -56.49595)
		(width 0.1905)
		(layer "In9.Cu")
		(net "M_A_MA4")
	)
	(segment
		(start 152.4508 -62.735206)
		(end 152.4508 -65.6336)
		(width 0.1905)
		(layer "In9.Cu")
		(net "M_A_MA4")
	)
	(segment
		(start 107.924854 -54.8894)
		(end 109.531404 -56.49595)
		(width 0.1905)
		(layer "In9.Cu")
		(net "M_A_MA4")
	)
	(segment
		(start 154.71394 -67.89674)
		(end 155.706064 -67.89674)
		(width 0.1905)
		(layer "In9.Cu")
		(net "M_A_MA4")
	)
	(segment
		(start 137.04189 -56.87695)
		(end 137.3378 -56.58104)
		(width 0.1905)
		(layer "In9.Cu")
		(net "M_A_MA4")
	)
	(segment
		(start 105.37444 -49.8602)
		(end 105.8291 -50.31486)
		(width 0.1016)
		(layer "In9.Cu")
		(net "M_A_MA4")
	)
	(segment
		(start 142.768574 -57.06745)
		(end 143.269462 -57.568338)
		(width 0.1905)
		(layer "In9.Cu")
		(net "M_A_MA4")
	)
	(segment
		(start 106.450638 -48.149002)
		(end 106.067606 -48.53178)
		(width 0.1016)
		(layer "In9.Cu")
		(net "M_A_MA4")
	)
	(segment
		(start 106.3498 -52.551838)
		(end 107.924854 -54.126892)
		(width 0.1016)
		(layer "In9.Cu")
		(net "M_A_MA4")
	)
	(segment
		(start 105.8291 -50.31486)
		(end 105.919778 -50.31486)
		(width 0.1016)
		(layer "In9.Cu")
		(net "M_A_MA4")
	)
	(segment
		(start 134.154164 -56.49595)
		(end 134.535164 -56.87695)
		(width 0.1905)
		(layer "In9.Cu")
		(net "M_A_MA4")
	)
	(segment
		(start 152.4508 -65.6336)
		(end 154.71394 -67.89674)
		(width 0.1905)
		(layer "In9.Cu")
		(net "M_A_MA4")
	)
	(segment
		(start 106.067606 -48.922432)
		(end 105.85196 -49.138078)
		(width 0.1016)
		(layer "In9.Cu")
		(net "M_A_MA4")
	)
	(segment
		(start 135.762746 -56.58104)
		(end 136.33704 -56.58104)
		(width 0.1905)
		(layer "In9.Cu")
		(net "M_A_MA4")
	)
	(segment
		(start 137.81024 -56.58104)
		(end 138.1252 -56.896)
		(width 0.1905)
		(layer "In9.Cu")
		(net "M_A_MA4")
	)
	(segment
		(start 105.85196 -49.138078)
		(end 105.730802 -49.138078)
		(width 0.1016)
		(layer "In9.Cu")
		(net "M_A_MA4")
	)
	(segment
		(start 138.1252 -56.896)
		(end 138.49604 -56.896)
		(width 0.1905)
		(layer "In9.Cu")
		(net "M_A_MA4")
	)
	(segment
		(start 105.730802 -49.138078)
		(end 105.37444 -49.49444)
		(width 0.1016)
		(layer "In9.Cu")
		(net "M_A_MA4")
	)
	(segment
		(start 136.63295 -56.87695)
		(end 137.04189 -56.87695)
		(width 0.1905)
		(layer "In9.Cu")
		(net "M_A_MA4")
	)
	(segment
		(start 107.924854 -54.126892)
		(end 107.924854 -54.711854)
		(width 0.1016)
		(layer "In9.Cu")
		(net "M_A_MA4")
	)
	(segment
		(start 82.527902 -24.257)
		(end 84.045044 -24.257)
		(width 0.1143)
		(layer "F.Cu")
		(net "LPC_CPU_CLKOUT0")
	)
	(segment
		(start 84.6328 -23.669244)
		(end 84.6328 -23.3172)
		(width 0.1143)
		(layer "F.Cu")
		(net "LPC_CPU_CLKOUT0")
	)
	(segment
		(start 128.64465 -46.84395)
		(end 128.39065 -47.09795)
		(width 0.1143)
		(layer "F.Cu")
		(net "LPC_CPU_CLKOUT0")
	)
	(segment
		(start 112.5728 -18.4658)
		(end 112.763046 -18.656046)
		(width 0.1143)
		(layer "F.Cu")
		(net "LPC_CPU_CLKOUT0")
	)
	(segment
		(start 104.295448 -20.672552)
		(end 106.5022 -18.4658)
		(width 0.1143)
		(layer "F.Cu")
		(net "LPC_CPU_CLKOUT0")
	)
	(segment
		(start 128.39065 -47.09795)
		(end 127.01524 -47.09795)
		(width 0.1143)
		(layer "F.Cu")
		(net "LPC_CPU_CLKOUT0")
	)
	(segment
		(start 132.1308 -40.29456)
		(end 129.93624 -40.29456)
		(width 0.1143)
		(layer "F.Cu")
		(net "LPC_CPU_CLKOUT0")
	)
	(segment
		(start 77.11694 -28.1432)
		(end 77.11694 -27.02306)
		(width 0.1143)
		(layer "F.Cu")
		(net "LPC_CPU_CLKOUT0")
	)
	(segment
		(start 127.01524 -47.09795)
		(end 126.71425 -46.79696)
		(width 0.1143)
		(layer "F.Cu")
		(net "LPC_CPU_CLKOUT0")
	)
	(segment
		(start 129.93624 -40.29456)
		(end 128.64465 -41.58615)
		(width 0.1143)
		(layer "F.Cu")
		(net "LPC_CPU_CLKOUT0")
	)
	(segment
		(start 90.387424 -22.8854)
		(end 91.727274 -21.54555)
		(width 0.1143)
		(layer "F.Cu")
		(net "LPC_CPU_CLKOUT0")
	)
	(segment
		(start 91.727274 -21.54555)
		(end 93.51645 -21.54555)
		(width 0.1143)
		(layer "F.Cu")
		(net "LPC_CPU_CLKOUT0")
	)
	(segment
		(start 94.389448 -20.672552)
		(end 104.295448 -20.672552)
		(width 0.1143)
		(layer "F.Cu")
		(net "LPC_CPU_CLKOUT0")
	)
	(segment
		(start 93.51645 -21.54555)
		(end 94.389448 -20.672552)
		(width 0.1143)
		(layer "F.Cu")
		(net "LPC_CPU_CLKOUT0")
	)
	(segment
		(start 80.845406 -25.26665)
		(end 81.518252 -25.26665)
		(width 0.1143)
		(layer "F.Cu")
		(net "LPC_CPU_CLKOUT0")
	)
	(segment
		(start 112.763046 -24.659082)
		(end 126.71425 -38.610286)
		(width 0.1143)
		(layer "F.Cu")
		(net "LPC_CPU_CLKOUT0")
	)
	(segment
		(start 126.71425 -46.79696)
		(end 126.71425 -39.2684)
		(width 0.1143)
		(layer "F.Cu")
		(net "LPC_CPU_CLKOUT0")
	)
	(segment
		(start 80.406494 -24.68245)
		(end 80.62595 -24.901906)
		(width 0.1143)
		(layer "F.Cu")
		(net "LPC_CPU_CLKOUT0")
	)
	(segment
		(start 77.11694 -27.02306)
		(end 79.45755 -24.68245)
		(width 0.1143)
		(layer "F.Cu")
		(net "LPC_CPU_CLKOUT0")
	)
	(segment
		(start 112.763046 -18.656046)
		(end 112.763046 -24.659082)
		(width 0.1143)
		(layer "F.Cu")
		(net "LPC_CPU_CLKOUT0")
	)
	(segment
		(start 84.045044 -24.257)
		(end 84.6328 -23.669244)
		(width 0.1143)
		(layer "F.Cu")
		(net "LPC_CPU_CLKOUT0")
	)
	(segment
		(start 126.71425 -38.610286)
		(end 126.71425 -39.2684)
		(width 0.1143)
		(layer "F.Cu")
		(net "LPC_CPU_CLKOUT0")
	)
	(segment
		(start 80.62595 -24.901906)
		(end 80.62595 -25.047194)
		(width 0.1143)
		(layer "F.Cu")
		(net "LPC_CPU_CLKOUT0")
	)
	(segment
		(start 85.0646 -22.8854)
		(end 90.387424 -22.8854)
		(width 0.1143)
		(layer "F.Cu")
		(net "LPC_CPU_CLKOUT0")
	)
	(segment
		(start 80.62595 -25.047194)
		(end 80.845406 -25.26665)
		(width 0.1143)
		(layer "F.Cu")
		(net "LPC_CPU_CLKOUT0")
	)
	(segment
		(start 81.518252 -25.26665)
		(end 82.527902 -24.257)
		(width 0.1143)
		(layer "F.Cu")
		(net "LPC_CPU_CLKOUT0")
	)
	(segment
		(start 128.64465 -41.58615)
		(end 128.64465 -46.84395)
		(width 0.1143)
		(layer "F.Cu")
		(net "LPC_CPU_CLKOUT0")
	)
	(segment
		(start 106.5022 -18.4658)
		(end 112.5728 -18.4658)
		(width 0.1143)
		(layer "F.Cu")
		(net "LPC_CPU_CLKOUT0")
	)
	(segment
		(start 84.6328 -23.3172)
		(end 85.0646 -22.8854)
		(width 0.1143)
		(layer "F.Cu")
		(net "LPC_CPU_CLKOUT0")
	)
	(segment
		(start 79.45755 -24.68245)
		(end 80.406494 -24.68245)
		(width 0.1143)
		(layer "F.Cu")
		(net "LPC_CPU_CLKOUT0")
	)
	(via
		(at 76.3778 -36.2839)
		(size 0.508)
		(drill 0.254)
		(layers "F.Cu" "B.Cu")
		(net "LPC_CPU_CLKOUT0")
	)
	(via
		(at 77.11694 -28.1432)
		(size 0.4318)
		(drill 0.2032)
		(layers "F.Cu" "B.Cu")
		(net "LPC_CPU_CLKOUT0")
	)
	(via
		(at 126.71425 -39.2684)
		(size 0.7112)
		(drill 0.3556)
		(layers "F.Cu" "B.Cu")
		(net "LPC_CPU_CLKOUT0")
	)
	(segment
		(start 75.687428 -36.2712)
		(end 75.700128 -36.2839)
		(width 0.1143)
		(layer "B.Cu")
		(net "LPC_CPU_CLKOUT0")
	)
	(segment
		(start 75.565 -36.2712)
		(end 75.687428 -36.2712)
		(width 0.1143)
		(layer "B.Cu")
		(net "LPC_CPU_CLKOUT0")
	)
	(segment
		(start 75.700128 -36.2839)
		(end 76.3778 -36.2839)
		(width 0.1143)
		(layer "B.Cu")
		(net "LPC_CPU_CLKOUT0")
	)
	(segment
		(start 76.3778 -28.88234)
		(end 76.3778 -36.2839)
		(width 0.0889)
		(layer "In9.Cu")
		(net "LPC_CPU_CLKOUT0")
	)
	(segment
		(start 77.11694 -28.1432)
		(end 76.3778 -28.88234)
		(width 0.0889)
		(layer "In9.Cu")
		(net "LPC_CPU_CLKOUT0")
	)
	(segment
		(start 21.1328 -68.2752)
		(end 21.3106 -68.453)
		(width 0.2032)
		(layer "F.Cu")
		(net "VR_PVNN_ISUMN_R2")
	)
	(segment
		(start 21.1328 -67.6148)
		(end 21.1328 -68.2752)
		(width 0.2032)
		(layer "F.Cu")
		(net "VR_PVNN_ISUMN_R2")
	)
	(via
		(at 21.3106 -68.453)
		(size 0.508)
		(drill 0.254)
		(layers "F.Cu" "B.Cu")
		(net "VR_PVNN_ISUMN_R2")
	)
	(via
		(at 41.1226 -64.3382)
		(size 0.7112)
		(drill 0.3556)
		(layers "F.Cu" "B.Cu")
		(net "VR_PVNN_ISUMN_R2")
	)
	(segment
		(start 29.108908 -69.9643)
		(end 29.732732 -70.58787)
		(width 0.2032)
		(layer "B.Cu")
		(net "VR_PVNN_ISUMN_R2")
	)
	(segment
		(start 37.445696 -70.58787)
		(end 41.021 -67.012566)
		(width 0.2032)
		(layer "B.Cu")
		(net "VR_PVNN_ISUMN_R2")
	)
	(segment
		(start 29.732732 -70.58787)
		(end 37.445696 -70.58787)
		(width 0.2032)
		(layer "B.Cu")
		(net "VR_PVNN_ISUMN_R2")
	)
	(segment
		(start 21.3106 -69.3166)
		(end 21.9583 -69.9643)
		(width 0.2032)
		(layer "B.Cu")
		(net "VR_PVNN_ISUMN_R2")
	)
	(segment
		(start 21.9583 -69.9643)
		(end 29.108908 -69.9643)
		(width 0.2032)
		(layer "B.Cu")
		(net "VR_PVNN_ISUMN_R2")
	)
	(segment
		(start 41.021 -65.4812)
		(end 41.2242 -65.278)
		(width 0.2032)
		(layer "B.Cu")
		(net "VR_PVNN_ISUMN_R2")
	)
	(segment
		(start 21.3106 -68.453)
		(end 21.3106 -69.3166)
		(width 0.2032)
		(layer "B.Cu")
		(net "VR_PVNN_ISUMN_R2")
	)
	(segment
		(start 41.2242 -64.4398)
		(end 41.2242 -65.278)
		(width 0.2032)
		(layer "B.Cu")
		(net "VR_PVNN_ISUMN_R2")
	)
	(segment
		(start 41.021 -67.012566)
		(end 41.021 -65.4812)
		(width 0.2032)
		(layer "B.Cu")
		(net "VR_PVNN_ISUMN_R2")
	)
	(segment
		(start 41.1226 -64.3382)
		(end 41.2242 -64.4398)
		(width 0.2032)
		(layer "B.Cu")
		(net "VR_PVNN_ISUMN_R2")
	)
	(segment
		(start 109.49686 -42.32148)
		(end 109.50702 -42.33164)
		(width 0.1778)
		(layer "F.Cu")
		(net "M_A_DQ3")
	)
	(segment
		(start 185.5216 -64.3128)
		(end 185.5216 -64.8716)
		(width 0.1778)
		(layer "F.Cu")
		(net "M_A_DQ3")
	)
	(segment
		(start 109.25048 -42.32148)
		(end 109.49686 -42.32148)
		(width 0.1778)
		(layer "F.Cu")
		(net "M_A_DQ3")
	)
	(segment
		(start 185.050176 -62.59322)
		(end 185.050176 -63.841376)
		(width 0.1778)
		(layer "F.Cu")
		(net "M_A_DQ3")
	)
	(segment
		(start 185.050176 -63.841376)
		(end 185.5216 -64.3128)
		(width 0.1778)
		(layer "F.Cu")
		(net "M_A_DQ3")
	)
	(segment
		(start 108.814108 -41.656254)
		(end 108.814108 -41.885362)
		(width 0.1778)
		(layer "F.Cu")
		(net "M_A_DQ3")
	)
	(segment
		(start 108.814108 -41.885362)
		(end 109.25048 -42.32148)
		(width 0.1778)
		(layer "F.Cu")
		(net "M_A_DQ3")
	)
	(via
		(at 109.50702 -42.33164)
		(size 0.4318)
		(drill 0.2032)
		(layers "F.Cu" "B.Cu")
		(net "M_A_DQ3")
	)
	(via
		(at 185.5216 -64.8716)
		(size 0.4318)
		(drill 0.2032)
		(layers "F.Cu" "B.Cu")
		(net "M_A_DQ3")
	)
	(segment
		(start 185.5216 -63.857632)
		(end 185.5216 -64.8716)
		(width 0.1778)
		(layer "B.Cu")
		(net "M_A_DQ3")
	)
	(segment
		(start 185.950098 -63.429134)
		(end 185.5216 -63.857632)
		(width 0.1778)
		(layer "B.Cu")
		(net "M_A_DQ3")
	)
	(segment
		(start 185.950098 -62.599824)
		(end 185.950098 -63.429134)
		(width 0.1778)
		(layer "B.Cu")
		(net "M_A_DQ3")
	)
	(segment
		(start 162.641026 -50.867818)
		(end 162.641026 -50.652426)
		(width 0.1524)
		(layer "In7.Cu")
		(net "M_A_DQ3")
	)
	(segment
		(start 171.068746 -56.235346)
		(end 170.853354 -56.235346)
		(width 0.1524)
		(layer "In7.Cu")
		(net "M_A_DQ3")
	)
	(segment
		(start 162.437318 -51.718718)
		(end 162.221418 -51.502818)
		(width 0.1524)
		(layer "In7.Cu")
		(net "M_A_DQ3")
	)
	(segment
		(start 164.366194 -52.377594)
		(end 164.150294 -52.161694)
		(width 0.1524)
		(layer "In7.Cu")
		(net "M_A_DQ3")
	)
	(segment
		(start 165.02507 -54.30647)
		(end 164.80917 -54.09057)
		(width 0.1524)
		(layer "In7.Cu")
		(net "M_A_DQ3")
	)
	(segment
		(start 172.793914 -57.960514)
		(end 172.578522 -57.960514)
		(width 0.1524)
		(layer "In7.Cu")
		(net "M_A_DQ3")
	)
	(segment
		(start 165.66007 -53.886862)
		(end 165.240462 -54.30647)
		(width 0.1524)
		(layer "In7.Cu")
		(net "M_A_DQ3")
	)
	(segment
		(start 172.831506 -58.785506)
		(end 172.831506 -58.570114)
		(width 0.1524)
		(layer "In7.Cu")
		(net "M_A_DQ3")
	)
	(segment
		(start 164.797486 -53.024278)
		(end 164.377878 -53.443886)
		(width 0.1524)
		(layer "In7.Cu")
		(net "M_A_DQ3")
	)
	(segment
		(start 109.825282 -42.337482)
		(end 109.550962 -42.337482)
		(width 0.1524)
		(layer "In7.Cu")
		(net "M_A_DQ3")
	)
	(segment
		(start 175.597566 -60.979558)
		(end 175.597566 -60.764166)
		(width 0.1524)
		(layer "In7.Cu")
		(net "M_A_DQ3")
	)
	(segment
		(start 163.946586 -53.012594)
		(end 164.366194 -52.592986)
		(width 0.1524)
		(layer "In7.Cu")
		(net "M_A_DQ3")
	)
	(segment
		(start 163.084002 -52.15001)
		(end 163.50361 -51.730402)
		(width 0.1524)
		(layer "In7.Cu")
		(net "M_A_DQ3")
	)
	(segment
		(start 176.24425 -61.41085)
		(end 176.028858 -61.41085)
		(width 0.1524)
		(layer "In7.Cu")
		(net "M_A_DQ3")
	)
	(segment
		(start 163.28771 -51.29911)
		(end 163.072318 -51.29911)
		(width 0.1524)
		(layer "In7.Cu")
		(net "M_A_DQ3")
	)
	(segment
		(start 176.497742 -62.451742)
		(end 176.281842 -62.235842)
		(width 0.1524)
		(layer "In7.Cu")
		(net "M_A_DQ3")
	)
	(segment
		(start 170.243754 -56.197754)
		(end 170.243754 -55.982362)
		(width 0.1524)
		(layer "In7.Cu")
		(net "M_A_DQ3")
	)
	(segment
		(start 162.221418 -51.287426)
		(end 162.641026 -50.867818)
		(width 0.1524)
		(layer "In7.Cu")
		(net "M_A_DQ3")
	)
	(segment
		(start 164.377878 -53.443886)
		(end 164.162486 -53.443886)
		(width 0.1524)
		(layer "In7.Cu")
		(net "M_A_DQ3")
	)
	(segment
		(start 162.641026 -50.652426)
		(end 161.8488 -49.8602)
		(width 0.1524)
		(layer "In7.Cu")
		(net "M_A_DQ3")
	)
	(segment
		(start 164.150294 -52.161694)
		(end 163.934902 -52.161694)
		(width 0.1524)
		(layer "In7.Cu")
		(net "M_A_DQ3")
	)
	(segment
		(start 173.441106 -58.823098)
		(end 173.262798 -59.001406)
		(width 0.1524)
		(layer "In7.Cu")
		(net "M_A_DQ3")
	)
	(segment
		(start 173.872398 -59.25439)
		(end 173.872398 -59.038998)
		(width 0.1524)
		(layer "In7.Cu")
		(net "M_A_DQ3")
	)
	(segment
		(start 175.85055 -61.589158)
		(end 175.635158 -61.589158)
		(width 0.1524)
		(layer "In7.Cu")
		(net "M_A_DQ3")
	)
	(segment
		(start 173.69409 -59.64809)
		(end 173.69409 -59.432698)
		(width 0.1524)
		(layer "In7.Cu")
		(net "M_A_DQ3")
	)
	(segment
		(start 166.81831 -54.82971)
		(end 165.875462 -53.886862)
		(width 0.1524)
		(layer "In7.Cu")
		(net "M_A_DQ3")
	)
	(segment
		(start 176.281842 -62.02045)
		(end 176.46015 -61.842142)
		(width 0.1524)
		(layer "In7.Cu")
		(net "M_A_DQ3")
	)
	(segment
		(start 184.2516 -63.373)
		(end 178.2064 -63.373)
		(width 0.1524)
		(layer "In7.Cu")
		(net "M_A_DQ3")
	)
	(segment
		(start 163.515294 -52.581302)
		(end 163.299902 -52.581302)
		(width 0.1524)
		(layer "In7.Cu")
		(net "M_A_DQ3")
	)
	(segment
		(start 109.54512 -42.33164)
		(end 109.50702 -42.33164)
		(width 0.1524)
		(layer "In7.Cu")
		(net "M_A_DQ3")
	)
	(segment
		(start 185.5216 -64.8716)
		(end 185.5216 -64.643)
		(width 0.1524)
		(layer "In7.Cu")
		(net "M_A_DQ3")
	)
	(segment
		(start 165.875462 -53.886862)
		(end 165.66007 -53.886862)
		(width 0.1524)
		(layer "In7.Cu")
		(net "M_A_DQ3")
	)
	(segment
		(start 165.012878 -53.024278)
		(end 164.797486 -53.024278)
		(width 0.1524)
		(layer "In7.Cu")
		(net "M_A_DQ3")
	)
	(segment
		(start 170.243754 -55.982362)
		(end 170.422062 -55.804054)
		(width 0.1524)
		(layer "In7.Cu")
		(net "M_A_DQ3")
	)
	(segment
		(start 172.14723 -57.529222)
		(end 172.14723 -57.31383)
		(width 0.1524)
		(layer "In7.Cu")
		(net "M_A_DQ3")
	)
	(segment
		(start 170.422062 -55.588662)
		(end 169.66311 -54.82971)
		(width 0.1524)
		(layer "In7.Cu")
		(net "M_A_DQ3")
	)
	(segment
		(start 163.50361 -51.51501)
		(end 163.28771 -51.29911)
		(width 0.1524)
		(layer "In7.Cu")
		(net "M_A_DQ3")
	)
	(segment
		(start 175.597566 -60.764166)
		(end 175.381666 -60.548266)
		(width 0.1524)
		(layer "In7.Cu")
		(net "M_A_DQ3")
	)
	(segment
		(start 171.284646 -56.666638)
		(end 171.284646 -56.451246)
		(width 0.1524)
		(layer "In7.Cu")
		(net "M_A_DQ3")
	)
	(segment
		(start 171.715938 -57.09793)
		(end 171.53763 -57.276238)
		(width 0.1524)
		(layer "In7.Cu")
		(net "M_A_DQ3")
	)
	(segment
		(start 164.80917 -53.875178)
		(end 165.228778 -53.45557)
		(width 0.1524)
		(layer "In7.Cu")
		(net "M_A_DQ3")
	)
	(segment
		(start 174.125382 -59.86399)
		(end 173.90999 -59.86399)
		(width 0.1524)
		(layer "In7.Cu")
		(net "M_A_DQ3")
	)
	(segment
		(start 169.66311 -54.82971)
		(end 166.81831 -54.82971)
		(width 0.1524)
		(layer "In7.Cu")
		(net "M_A_DQ3")
	)
	(segment
		(start 163.946586 -53.227986)
		(end 163.946586 -53.012594)
		(width 0.1524)
		(layer "In7.Cu")
		(net "M_A_DQ3")
	)
	(segment
		(start 163.299902 -52.581302)
		(end 163.084002 -52.365402)
		(width 0.1524)
		(layer "In7.Cu")
		(net "M_A_DQ3")
	)
	(segment
		(start 174.772574 -60.726574)
		(end 174.556674 -60.510674)
		(width 0.1524)
		(layer "In7.Cu")
		(net "M_A_DQ3")
	)
	(segment
		(start 178.2064 -63.373)
		(end 177.106834 -62.273434)
		(width 0.1524)
		(layer "In7.Cu")
		(net "M_A_DQ3")
	)
	(segment
		(start 171.53763 -57.276238)
		(end 171.322238 -57.276238)
		(width 0.1524)
		(layer "In7.Cu")
		(net "M_A_DQ3")
	)
	(segment
		(start 117.243098 -43.456098)
		(end 116.7638 -42.9768)
		(width 0.1524)
		(layer "In7.Cu")
		(net "M_A_DQ3")
	)
	(segment
		(start 174.556674 -60.295282)
		(end 174.734982 -60.116974)
		(width 0.1524)
		(layer "In7.Cu")
		(net "M_A_DQ3")
	)
	(segment
		(start 172.14723 -57.31383)
		(end 171.93133 -57.09793)
		(width 0.1524)
		(layer "In7.Cu")
		(net "M_A_DQ3")
	)
	(segment
		(start 173.262798 -59.001406)
		(end 173.047406 -59.001406)
		(width 0.1524)
		(layer "In7.Cu")
		(net "M_A_DQ3")
	)
	(segment
		(start 174.556674 -60.510674)
		(end 174.556674 -60.295282)
		(width 0.1524)
		(layer "In7.Cu")
		(net "M_A_DQ3")
	)
	(segment
		(start 174.987966 -60.726574)
		(end 174.772574 -60.726574)
		(width 0.1524)
		(layer "In7.Cu")
		(net "M_A_DQ3")
	)
	(segment
		(start 173.872398 -59.038998)
		(end 173.656498 -58.823098)
		(width 0.1524)
		(layer "In7.Cu")
		(net "M_A_DQ3")
	)
	(segment
		(start 170.422062 -55.804054)
		(end 170.422062 -55.588662)
		(width 0.1524)
		(layer "In7.Cu")
		(net "M_A_DQ3")
	)
	(segment
		(start 152.324308 -43.456098)
		(end 117.243098 -43.456098)
		(width 0.1524)
		(layer "In7.Cu")
		(net "M_A_DQ3")
	)
	(segment
		(start 163.934902 -52.161694)
		(end 163.515294 -52.581302)
		(width 0.1524)
		(layer "In7.Cu")
		(net "M_A_DQ3")
	)
	(segment
		(start 176.028858 -61.41085)
		(end 175.85055 -61.589158)
		(width 0.1524)
		(layer "In7.Cu")
		(net "M_A_DQ3")
	)
	(segment
		(start 171.106338 -57.060338)
		(end 171.106338 -56.844946)
		(width 0.1524)
		(layer "In7.Cu")
		(net "M_A_DQ3")
	)
	(segment
		(start 175.381666 -60.548266)
		(end 175.166274 -60.548266)
		(width 0.1524)
		(layer "In7.Cu")
		(net "M_A_DQ3")
	)
	(segment
		(start 171.322238 -57.276238)
		(end 171.106338 -57.060338)
		(width 0.1524)
		(layer "In7.Cu")
		(net "M_A_DQ3")
	)
	(segment
		(start 175.635158 -61.589158)
		(end 175.419258 -61.373258)
		(width 0.1524)
		(layer "In7.Cu")
		(net "M_A_DQ3")
	)
	(segment
		(start 162.65271 -51.718718)
		(end 162.437318 -51.718718)
		(width 0.1524)
		(layer "In7.Cu")
		(net "M_A_DQ3")
	)
	(segment
		(start 174.734982 -59.901582)
		(end 174.519082 -59.685682)
		(width 0.1524)
		(layer "In7.Cu")
		(net "M_A_DQ3")
	)
	(segment
		(start 173.69409 -59.432698)
		(end 173.872398 -59.25439)
		(width 0.1524)
		(layer "In7.Cu")
		(net "M_A_DQ3")
	)
	(segment
		(start 172.831506 -58.570114)
		(end 173.009814 -58.391806)
		(width 0.1524)
		(layer "In7.Cu")
		(net "M_A_DQ3")
	)
	(segment
		(start 163.50361 -51.730402)
		(end 163.50361 -51.51501)
		(width 0.1524)
		(layer "In7.Cu")
		(net "M_A_DQ3")
	)
	(segment
		(start 163.084002 -52.365402)
		(end 163.084002 -52.15001)
		(width 0.1524)
		(layer "In7.Cu")
		(net "M_A_DQ3")
	)
	(segment
		(start 172.400214 -58.138822)
		(end 172.184822 -58.138822)
		(width 0.1524)
		(layer "In7.Cu")
		(net "M_A_DQ3")
	)
	(segment
		(start 174.519082 -59.685682)
		(end 174.30369 -59.685682)
		(width 0.1524)
		(layer "In7.Cu")
		(net "M_A_DQ3")
	)
	(segment
		(start 176.46015 -61.62675)
		(end 176.24425 -61.41085)
		(width 0.1524)
		(layer "In7.Cu")
		(net "M_A_DQ3")
	)
	(segment
		(start 176.281842 -62.235842)
		(end 176.281842 -62.02045)
		(width 0.1524)
		(layer "In7.Cu")
		(net "M_A_DQ3")
	)
	(segment
		(start 173.009814 -58.176414)
		(end 172.793914 -57.960514)
		(width 0.1524)
		(layer "In7.Cu")
		(net "M_A_DQ3")
	)
	(segment
		(start 109.550962 -42.337482)
		(end 109.54512 -42.33164)
		(width 0.1524)
		(layer "In7.Cu")
		(net "M_A_DQ3")
	)
	(segment
		(start 175.419258 -61.157866)
		(end 175.597566 -60.979558)
		(width 0.1524)
		(layer "In7.Cu")
		(net "M_A_DQ3")
	)
	(segment
		(start 161.8488 -49.8602)
		(end 158.72841 -49.8602)
		(width 0.1524)
		(layer "In7.Cu")
		(net "M_A_DQ3")
	)
	(segment
		(start 165.228778 -53.45557)
		(end 165.228778 -53.240178)
		(width 0.1524)
		(layer "In7.Cu")
		(net "M_A_DQ3")
	)
	(segment
		(start 162.221418 -51.502818)
		(end 162.221418 -51.287426)
		(width 0.1524)
		(layer "In7.Cu")
		(net "M_A_DQ3")
	)
	(segment
		(start 110.4646 -42.9768)
		(end 109.825282 -42.337482)
		(width 0.1524)
		(layer "In7.Cu")
		(net "M_A_DQ3")
	)
	(segment
		(start 171.968922 -57.922922)
		(end 171.968922 -57.70753)
		(width 0.1524)
		(layer "In7.Cu")
		(net "M_A_DQ3")
	)
	(segment
		(start 165.240462 -54.30647)
		(end 165.02507 -54.30647)
		(width 0.1524)
		(layer "In7.Cu")
		(net "M_A_DQ3")
	)
	(segment
		(start 158.72841 -49.8602)
		(end 152.324308 -43.456098)
		(width 0.1524)
		(layer "In7.Cu")
		(net "M_A_DQ3")
	)
	(segment
		(start 175.419258 -61.373258)
		(end 175.419258 -61.157866)
		(width 0.1524)
		(layer "In7.Cu")
		(net "M_A_DQ3")
	)
	(segment
		(start 164.80917 -54.09057)
		(end 164.80917 -53.875178)
		(width 0.1524)
		(layer "In7.Cu")
		(net "M_A_DQ3")
	)
	(segment
		(start 171.93133 -57.09793)
		(end 171.715938 -57.09793)
		(width 0.1524)
		(layer "In7.Cu")
		(net "M_A_DQ3")
	)
	(segment
		(start 173.90999 -59.86399)
		(end 173.69409 -59.64809)
		(width 0.1524)
		(layer "In7.Cu")
		(net "M_A_DQ3")
	)
	(segment
		(start 170.459654 -56.413654)
		(end 170.243754 -56.197754)
		(width 0.1524)
		(layer "In7.Cu")
		(net "M_A_DQ3")
	)
	(segment
		(start 173.047406 -59.001406)
		(end 172.831506 -58.785506)
		(width 0.1524)
		(layer "In7.Cu")
		(net "M_A_DQ3")
	)
	(segment
		(start 176.891442 -62.273434)
		(end 176.713134 -62.451742)
		(width 0.1524)
		(layer "In7.Cu")
		(net "M_A_DQ3")
	)
	(segment
		(start 177.106834 -62.273434)
		(end 176.891442 -62.273434)
		(width 0.1524)
		(layer "In7.Cu")
		(net "M_A_DQ3")
	)
	(segment
		(start 172.578522 -57.960514)
		(end 172.400214 -58.138822)
		(width 0.1524)
		(layer "In7.Cu")
		(net "M_A_DQ3")
	)
	(segment
		(start 174.30369 -59.685682)
		(end 174.125382 -59.86399)
		(width 0.1524)
		(layer "In7.Cu")
		(net "M_A_DQ3")
	)
	(segment
		(start 170.675046 -56.413654)
		(end 170.459654 -56.413654)
		(width 0.1524)
		(layer "In7.Cu")
		(net "M_A_DQ3")
	)
	(segment
		(start 176.46015 -61.842142)
		(end 176.46015 -61.62675)
		(width 0.1524)
		(layer "In7.Cu")
		(net "M_A_DQ3")
	)
	(segment
		(start 172.184822 -58.138822)
		(end 171.968922 -57.922922)
		(width 0.1524)
		(layer "In7.Cu")
		(net "M_A_DQ3")
	)
	(segment
		(start 171.284646 -56.451246)
		(end 171.068746 -56.235346)
		(width 0.1524)
		(layer "In7.Cu")
		(net "M_A_DQ3")
	)
	(segment
		(start 165.228778 -53.240178)
		(end 165.012878 -53.024278)
		(width 0.1524)
		(layer "In7.Cu")
		(net "M_A_DQ3")
	)
	(segment
		(start 171.106338 -56.844946)
		(end 171.284646 -56.666638)
		(width 0.1524)
		(layer "In7.Cu")
		(net "M_A_DQ3")
	)
	(segment
		(start 163.072318 -51.29911)
		(end 162.65271 -51.718718)
		(width 0.1524)
		(layer "In7.Cu")
		(net "M_A_DQ3")
	)
	(segment
		(start 116.7638 -42.9768)
		(end 110.4646 -42.9768)
		(width 0.1524)
		(layer "In7.Cu")
		(net "M_A_DQ3")
	)
	(segment
		(start 164.162486 -53.443886)
		(end 163.946586 -53.227986)
		(width 0.1524)
		(layer "In7.Cu")
		(net "M_A_DQ3")
	)
	(segment
		(start 176.713134 -62.451742)
		(end 176.497742 -62.451742)
		(width 0.1524)
		(layer "In7.Cu")
		(net "M_A_DQ3")
	)
	(segment
		(start 171.968922 -57.70753)
		(end 172.14723 -57.529222)
		(width 0.1524)
		(layer "In7.Cu")
		(net "M_A_DQ3")
	)
	(segment
		(start 175.166274 -60.548266)
		(end 174.987966 -60.726574)
		(width 0.1524)
		(layer "In7.Cu")
		(net "M_A_DQ3")
	)
	(segment
		(start 173.656498 -58.823098)
		(end 173.441106 -58.823098)
		(width 0.1524)
		(layer "In7.Cu")
		(net "M_A_DQ3")
	)
	(segment
		(start 170.853354 -56.235346)
		(end 170.675046 -56.413654)
		(width 0.1524)
		(layer "In7.Cu")
		(net "M_A_DQ3")
	)
	(segment
		(start 174.734982 -60.116974)
		(end 174.734982 -59.901582)
		(width 0.1524)
		(layer "In7.Cu")
		(net "M_A_DQ3")
	)
	(segment
		(start 185.5216 -64.643)
		(end 184.2516 -63.373)
		(width 0.1524)
		(layer "In7.Cu")
		(net "M_A_DQ3")
	)
	(segment
		(start 164.366194 -52.592986)
		(end 164.366194 -52.377594)
		(width 0.1524)
		(layer "In7.Cu")
		(net "M_A_DQ3")
	)
	(segment
		(start 173.009814 -58.391806)
		(end 173.009814 -58.176414)
		(width 0.1524)
		(layer "In7.Cu")
		(net "M_A_DQ3")
	)
	(segment
		(start 19.662902 -55.547006)
		(end 19.662902 -54.946042)
		(width 0.2032)
		(layer "F.Cu")
		(net "VR_PVCCP_FB")
	)
	(segment
		(start 17.272 -51.2318)
		(end 17.399 -51.3588)
		(width 0.2032)
		(layer "F.Cu")
		(net "VR_PVCCP_FB")
	)
	(segment
		(start 19.662902 -54.946042)
		(end 19.9136 -54.695344)
		(width 0.2032)
		(layer "F.Cu")
		(net "VR_PVCCP_FB")
	)
	(segment
		(start 17.799812 -51.6128)
		(end 18.3896 -51.6128)
		(width 0.2032)
		(layer "F.Cu")
		(net "VR_PVCCP_FB")
	)
	(segment
		(start 20.3962 -52.6288)
		(end 20.3962 -53.092858)
		(width 0.2032)
		(layer "F.Cu")
		(net "VR_PVCCP_FB")
	)
	(segment
		(start 20.3962 -52.3494)
		(end 20.3962 -52.6288)
		(width 0.2032)
		(layer "F.Cu")
		(net "VR_PVCCP_FB")
	)
	(segment
		(start 19.9136 -53.575458)
		(end 19.970242 -53.518816)
		(width 0.2032)
		(layer "F.Cu")
		(net "VR_PVCCP_FB")
	)
	(segment
		(start 19.6596 -51.6128)
		(end 18.3896 -51.6128)
		(width 0.2032)
		(layer "F.Cu")
		(net "VR_PVCCP_FB")
	)
	(segment
		(start 17.2466 -51.2572)
		(end 17.272 -51.2318)
		(width 0.2032)
		(layer "F.Cu")
		(net "VR_PVCCP_FB")
	)
	(segment
		(start 17.399 -51.3588)
		(end 17.545812 -51.3588)
		(width 0.2032)
		(layer "F.Cu")
		(net "VR_PVCCP_FB")
	)
	(segment
		(start 17.545812 -51.3588)
		(end 17.799812 -51.6128)
		(width 0.2032)
		(layer "F.Cu")
		(net "VR_PVCCP_FB")
	)
	(segment
		(start 20.3962 -53.092858)
		(end 19.970242 -53.518816)
		(width 0.2032)
		(layer "F.Cu")
		(net "VR_PVCCP_FB")
	)
	(segment
		(start 16.51 -51.2572)
		(end 17.2466 -51.2572)
		(width 0.2032)
		(layer "F.Cu")
		(net "VR_PVCCP_FB")
	)
	(segment
		(start 19.6596 -51.6128)
		(end 20.3962 -52.3494)
		(width 0.2032)
		(layer "F.Cu")
		(net "VR_PVCCP_FB")
	)
	(segment
		(start 19.9136 -54.695344)
		(end 19.9136 -53.575458)
		(width 0.2032)
		(layer "F.Cu")
		(net "VR_PVCCP_FB")
	)
	(via
		(at 19.970242 -53.518816)
		(size 0.7112)
		(drill 0.3556)
		(layers "F.Cu" "B.Cu")
		(net "VR_PVCCP_FB")
	)
	(segment
		(start 108.763054 -43.97248)
		(end 108.839 -43.97248)
		(width 0.1016)
		(layer "F.Cu")
		(net "M_A_DQ14")
	)
	(segment
		(start 181.150006 -69.999606)
		(end 180.6956 -69.5452)
		(width 0.1778)
		(layer "F.Cu")
		(net "M_A_DQ14")
	)
	(segment
		(start 181.150006 -70.806564)
		(end 181.150006 -69.999606)
		(width 0.1778)
		(layer "F.Cu")
		(net "M_A_DQ14")
	)
	(segment
		(start 180.6956 -69.5452)
		(end 180.6956 -68.9102)
		(width 0.1778)
		(layer "F.Cu")
		(net "M_A_DQ14")
	)
	(segment
		(start 180.6956 -68.9102)
		(end 180.8988 -68.707)
		(width 0.1778)
		(layer "F.Cu")
		(net "M_A_DQ14")
	)
	(segment
		(start 108.433108 -43.642534)
		(end 108.763054 -43.97248)
		(width 0.1016)
		(layer "F.Cu")
		(net "M_A_DQ14")
	)
	(via
		(at 180.8988 -68.707)
		(size 0.4318)
		(drill 0.2032)
		(layers "F.Cu" "B.Cu")
		(net "M_A_DQ14")
	)
	(via
		(at 108.839 -43.97248)
		(size 0.4318)
		(drill 0.2032)
		(layers "F.Cu" "B.Cu")
		(net "M_A_DQ14")
	)
	(segment
		(start 180.6702 -68.9102)
		(end 180.8734 -68.707)
		(width 0.1778)
		(layer "B.Cu")
		(net "M_A_DQ14")
	)
	(segment
		(start 180.250084 -70.79996)
		(end 180.250084 -69.85508)
		(width 0.1778)
		(layer "B.Cu")
		(net "M_A_DQ14")
	)
	(segment
		(start 180.8734 -68.707)
		(end 180.8988 -68.707)
		(width 0.1778)
		(layer "B.Cu")
		(net "M_A_DQ14")
	)
	(segment
		(start 180.250084 -69.85508)
		(end 180.6702 -69.434964)
		(width 0.1778)
		(layer "B.Cu")
		(net "M_A_DQ14")
	)
	(segment
		(start 180.6702 -69.434964)
		(end 180.6702 -68.9102)
		(width 0.1778)
		(layer "B.Cu")
		(net "M_A_DQ14")
	)
	(segment
		(start 166.762176 -50.112676)
		(end 166.977568 -50.112676)
		(width 0.1524)
		(layer "In4.Cu")
		(net "M_A_DQ14")
	)
	(segment
		(start 157.0736 -48.283876)
		(end 157.494224 -48.7045)
		(width 0.1524)
		(layer "In4.Cu")
		(net "M_A_DQ14")
	)
	(segment
		(start 166.401496 -50.25771)
		(end 166.616888 -50.25771)
		(width 0.1524)
		(layer "In4.Cu")
		(net "M_A_DQ14")
	)
	(segment
		(start 182.1942 -65.557908)
		(end 182.0418 -65.710308)
		(width 0.1524)
		(layer "In4.Cu")
		(net "M_A_DQ14")
	)
	(segment
		(start 181.6354 -63.8556)
		(end 181.619398 -63.8556)
		(width 0.1524)
		(layer "In4.Cu")
		(net "M_A_DQ14")
	)
	(segment
		(start 113.03 -43.0022)
		(end 117.8306 -43.0022)
		(width 0.1524)
		(layer "In4.Cu")
		(net "M_A_DQ14")
	)
	(segment
		(start 179.5018 -58.201814)
		(end 179.5018 -59.7408)
		(width 0.1524)
		(layer "In4.Cu")
		(net "M_A_DQ14")
	)
	(segment
		(start 166.616888 -50.25771)
		(end 166.762176 -50.112676)
		(width 0.1524)
		(layer "In4.Cu")
		(net "M_A_DQ14")
	)
	(segment
		(start 170.75785 -53.25745)
		(end 170.75785 -53.472842)
		(width 0.1524)
		(layer "In4.Cu")
		(net "M_A_DQ14")
	)
	(segment
		(start 181.771798 -65.100708)
		(end 182.0418 -65.100708)
		(width 0.1524)
		(layer "In4.Cu")
		(net "M_A_DQ14")
	)
	(segment
		(start 168.918636 -52.269136)
		(end 168.773348 -52.414424)
		(width 0.1524)
		(layer "In4.Cu")
		(net "M_A_DQ14")
	)
	(segment
		(start 175.865028 -54.565042)
		(end 179.5018 -58.201814)
		(width 0.1524)
		(layer "In4.Cu")
		(net "M_A_DQ14")
	)
	(segment
		(start 121.993914 -43.8404)
		(end 122.501914 -44.3484)
		(width 0.1524)
		(layer "In4.Cu")
		(net "M_A_DQ14")
	)
	(segment
		(start 181.4322 -67.166998)
		(end 181.5846 -67.319398)
		(width 0.1524)
		(layer "In4.Cu")
		(net "M_A_DQ14")
	)
	(segment
		(start 151.419814 -44.3484)
		(end 152.763474 -45.69206)
		(width 0.1524)
		(layer "In4.Cu")
		(net "M_A_DQ14")
	)
	(segment
		(start 167.910764 -51.766978)
		(end 168.126664 -51.982878)
		(width 0.1524)
		(layer "In4.Cu")
		(net "M_A_DQ14")
	)
	(segment
		(start 181.619398 -64.948308)
		(end 181.771798 -65.100708)
		(width 0.1524)
		(layer "In4.Cu")
		(net "M_A_DQ14")
	)
	(segment
		(start 170.54195 -53.04155)
		(end 170.75785 -53.25745)
		(width 0.1524)
		(layer "In4.Cu")
		(net "M_A_DQ14")
	)
	(segment
		(start 181.5846 -67.319398)
		(end 181.5846 -67.624198)
		(width 0.1524)
		(layer "In4.Cu")
		(net "M_A_DQ14")
	)
	(segment
		(start 112.395 -43.438826)
		(end 109.756194 -43.438826)
		(width 0.1016)
		(layer "In4.Cu")
		(net "M_A_DQ14")
	)
	(segment
		(start 169.863516 -53.504338)
		(end 170.326558 -53.04155)
		(width 0.1524)
		(layer "In4.Cu")
		(net "M_A_DQ14")
	)
	(segment
		(start 169.648124 -53.504338)
		(end 169.863516 -53.504338)
		(width 0.1524)
		(layer "In4.Cu")
		(net "M_A_DQ14")
	)
	(segment
		(start 180.715158 -68.523358)
		(end 180.8988 -68.707)
		(width 0.1524)
		(layer "In4.Cu")
		(net "M_A_DQ14")
	)
	(segment
		(start 170.294808 -54.151022)
		(end 170.708828 -54.565042)
		(width 0.1524)
		(layer "In4.Cu")
		(net "M_A_DQ14")
	)
	(segment
		(start 167.04818 -50.689256)
		(end 167.04818 -50.904394)
		(width 0.1524)
		(layer "In4.Cu")
		(net "M_A_DQ14")
	)
	(segment
		(start 168.702736 -51.837844)
		(end 168.918636 -52.053744)
		(width 0.1524)
		(layer "In4.Cu")
		(net "M_A_DQ14")
	)
	(segment
		(start 170.708828 -54.565042)
		(end 175.865028 -54.565042)
		(width 0.1524)
		(layer "In4.Cu")
		(net "M_A_DQ14")
	)
	(segment
		(start 179.5018 -59.7408)
		(end 181.8386 -62.0776)
		(width 0.1524)
		(layer "In4.Cu")
		(net "M_A_DQ14")
	)
	(segment
		(start 181.771798 -65.710308)
		(end 181.619398 -65.862708)
		(width 0.1524)
		(layer "In4.Cu")
		(net "M_A_DQ14")
	)
	(segment
		(start 168.773348 -52.414424)
		(end 168.773348 -52.629562)
		(width 0.1524)
		(layer "In4.Cu")
		(net "M_A_DQ14")
	)
	(segment
		(start 168.126664 -51.982878)
		(end 168.342056 -51.982878)
		(width 0.1524)
		(layer "In4.Cu")
		(net "M_A_DQ14")
	)
	(segment
		(start 167.479472 -51.120294)
		(end 167.62476 -50.97526)
		(width 0.1524)
		(layer "In4.Cu")
		(net "M_A_DQ14")
	)
	(segment
		(start 168.342056 -51.982878)
		(end 168.487344 -51.837844)
		(width 0.1524)
		(layer "In4.Cu")
		(net "M_A_DQ14")
	)
	(segment
		(start 168.056052 -51.406552)
		(end 167.910764 -51.55184)
		(width 0.1524)
		(layer "In4.Cu")
		(net "M_A_DQ14")
	)
	(segment
		(start 164.848286 -48.7045)
		(end 166.401496 -50.25771)
		(width 0.1524)
		(layer "In4.Cu")
		(net "M_A_DQ14")
	)
	(segment
		(start 180.6702 -66.548)
		(end 180.5178 -66.7004)
		(width 0.1524)
		(layer "In4.Cu")
		(net "M_A_DQ14")
	)
	(segment
		(start 168.773348 -52.629562)
		(end 169.648124 -53.504338)
		(width 0.1524)
		(layer "In4.Cu")
		(net "M_A_DQ14")
	)
	(segment
		(start 170.326558 -53.04155)
		(end 170.54195 -53.04155)
		(width 0.1524)
		(layer "In4.Cu")
		(net "M_A_DQ14")
	)
	(segment
		(start 181.8386 -63.6524)
		(end 181.6354 -63.8556)
		(width 0.1524)
		(layer "In4.Cu")
		(net "M_A_DQ14")
	)
	(segment
		(start 180.5178 -66.7004)
		(end 180.5178 -67.0306)
		(width 0.1524)
		(layer "In4.Cu")
		(net "M_A_DQ14")
	)
	(segment
		(start 167.840152 -50.97526)
		(end 168.056052 -51.19116)
		(width 0.1524)
		(layer "In4.Cu")
		(net "M_A_DQ14")
	)
	(segment
		(start 181.5846 -67.624198)
		(end 181.4322 -67.776598)
		(width 0.1524)
		(layer "In4.Cu")
		(net "M_A_DQ14")
	)
	(segment
		(start 182.1942 -65.253108)
		(end 182.1942 -65.557908)
		(width 0.1524)
		(layer "In4.Cu")
		(net "M_A_DQ14")
	)
	(segment
		(start 180.5178 -67.0306)
		(end 180.654198 -67.166998)
		(width 0.1524)
		(layer "In4.Cu")
		(net "M_A_DQ14")
	)
	(segment
		(start 170.75785 -53.472842)
		(end 170.294808 -53.93563)
		(width 0.1524)
		(layer "In4.Cu")
		(net "M_A_DQ14")
	)
	(segment
		(start 181.619398 -66.3956)
		(end 181.466998 -66.548)
		(width 0.1524)
		(layer "In4.Cu")
		(net "M_A_DQ14")
	)
	(segment
		(start 109.22254 -43.97248)
		(end 108.839 -43.97248)
		(width 0.1016)
		(layer "In4.Cu")
		(net "M_A_DQ14")
	)
	(segment
		(start 181.619398 -63.8556)
		(end 181.619398 -64.948308)
		(width 0.1524)
		(layer "In4.Cu")
		(net "M_A_DQ14")
	)
	(segment
		(start 170.294808 -53.93563)
		(end 170.294808 -54.151022)
		(width 0.1524)
		(layer "In4.Cu")
		(net "M_A_DQ14")
	)
	(segment
		(start 152.763474 -45.69206)
		(end 156.84246 -45.69206)
		(width 0.1524)
		(layer "In4.Cu")
		(net "M_A_DQ14")
	)
	(segment
		(start 180.867558 -67.776598)
		(end 180.715158 -67.928998)
		(width 0.1524)
		(layer "In4.Cu")
		(net "M_A_DQ14")
	)
	(segment
		(start 167.26408 -51.120294)
		(end 167.479472 -51.120294)
		(width 0.1524)
		(layer "In4.Cu")
		(net "M_A_DQ14")
	)
	(segment
		(start 109.756194 -43.438826)
		(end 109.22254 -43.97248)
		(width 0.1016)
		(layer "In4.Cu")
		(net "M_A_DQ14")
	)
	(segment
		(start 181.8386 -62.0776)
		(end 181.8386 -63.6524)
		(width 0.1524)
		(layer "In4.Cu")
		(net "M_A_DQ14")
	)
	(segment
		(start 167.193468 -50.543968)
		(end 167.04818 -50.689256)
		(width 0.1524)
		(layer "In4.Cu")
		(net "M_A_DQ14")
	)
	(segment
		(start 181.619398 -65.862708)
		(end 181.619398 -66.3956)
		(width 0.1524)
		(layer "In4.Cu")
		(net "M_A_DQ14")
	)
	(segment
		(start 118.6688 -43.8404)
		(end 121.993914 -43.8404)
		(width 0.1524)
		(layer "In4.Cu")
		(net "M_A_DQ14")
	)
	(segment
		(start 180.715158 -67.928998)
		(end 180.715158 -68.523358)
		(width 0.1524)
		(layer "In4.Cu")
		(net "M_A_DQ14")
	)
	(segment
		(start 167.04818 -50.904394)
		(end 167.26408 -51.120294)
		(width 0.1524)
		(layer "In4.Cu")
		(net "M_A_DQ14")
	)
	(segment
		(start 182.0418 -65.710308)
		(end 181.771798 -65.710308)
		(width 0.1524)
		(layer "In4.Cu")
		(net "M_A_DQ14")
	)
	(segment
		(start 112.593374 -43.438826)
		(end 113.03 -43.0022)
		(width 0.1524)
		(layer "In4.Cu")
		(net "M_A_DQ14")
	)
	(segment
		(start 168.918636 -52.053744)
		(end 168.918636 -52.269136)
		(width 0.1524)
		(layer "In4.Cu")
		(net "M_A_DQ14")
	)
	(segment
		(start 156.84246 -45.69206)
		(end 157.0736 -45.9232)
		(width 0.1524)
		(layer "In4.Cu")
		(net "M_A_DQ14")
	)
	(segment
		(start 167.910764 -51.55184)
		(end 167.910764 -51.766978)
		(width 0.1524)
		(layer "In4.Cu")
		(net "M_A_DQ14")
	)
	(segment
		(start 180.654198 -67.166998)
		(end 181.4322 -67.166998)
		(width 0.1524)
		(layer "In4.Cu")
		(net "M_A_DQ14")
	)
	(segment
		(start 157.0736 -45.9232)
		(end 157.0736 -48.283876)
		(width 0.1524)
		(layer "In4.Cu")
		(net "M_A_DQ14")
	)
	(segment
		(start 122.501914 -44.3484)
		(end 151.419814 -44.3484)
		(width 0.1524)
		(layer "In4.Cu")
		(net "M_A_DQ14")
	)
	(segment
		(start 112.395 -43.438826)
		(end 112.593374 -43.438826)
		(width 0.1524)
		(layer "In4.Cu")
		(net "M_A_DQ14")
	)
	(segment
		(start 168.056052 -51.19116)
		(end 168.056052 -51.406552)
		(width 0.1524)
		(layer "In4.Cu")
		(net "M_A_DQ14")
	)
	(segment
		(start 157.494224 -48.7045)
		(end 164.848286 -48.7045)
		(width 0.1524)
		(layer "In4.Cu")
		(net "M_A_DQ14")
	)
	(segment
		(start 182.0418 -65.100708)
		(end 182.1942 -65.253108)
		(width 0.1524)
		(layer "In4.Cu")
		(net "M_A_DQ14")
	)
	(segment
		(start 168.487344 -51.837844)
		(end 168.702736 -51.837844)
		(width 0.1524)
		(layer "In4.Cu")
		(net "M_A_DQ14")
	)
	(segment
		(start 117.8306 -43.0022)
		(end 118.6688 -43.8404)
		(width 0.1524)
		(layer "In4.Cu")
		(net "M_A_DQ14")
	)
	(segment
		(start 181.466998 -66.548)
		(end 180.6702 -66.548)
		(width 0.1524)
		(layer "In4.Cu")
		(net "M_A_DQ14")
	)
	(segment
		(start 167.193468 -50.328576)
		(end 167.193468 -50.543968)
		(width 0.1524)
		(layer "In4.Cu")
		(net "M_A_DQ14")
	)
	(segment
		(start 166.977568 -50.112676)
		(end 167.193468 -50.328576)
		(width 0.1524)
		(layer "In4.Cu")
		(net "M_A_DQ14")
	)
	(segment
		(start 181.4322 -67.776598)
		(end 180.867558 -67.776598)
		(width 0.1524)
		(layer "In4.Cu")
		(net "M_A_DQ14")
	)
	(segment
		(start 167.62476 -50.97526)
		(end 167.840152 -50.97526)
		(width 0.1524)
		(layer "In4.Cu")
		(net "M_A_DQ14")
	)
	(segment
		(start 53.8988 -55.6768)
		(end 53.975 -55.753)
		(width 0.2032)
		(layer "F.Cu")
		(net "VR_PVCCP_NTC")
	)
	(segment
		(start 25.7302 -47.879)
		(end 24.8412 -47.879)
		(width 0.2032)
		(layer "F.Cu")
		(net "VR_PVCCP_NTC")
	)
	(segment
		(start 24.8412 -47.879)
		(end 24.6634 -48.0568)
		(width 0.2032)
		(layer "F.Cu")
		(net "VR_PVCCP_NTC")
	)
	(segment
		(start 53.8988 -54.864)
		(end 53.8988 -55.6768)
		(width 0.2032)
		(layer "F.Cu")
		(net "VR_PVCCP_NTC")
	)
	(via
		(at 54.356 -56.642)
		(size 0.7112)
		(drill 0.3556)
		(layers "F.Cu" "B.Cu")
		(net "VR_PVCCP_NTC")
	)
	(via
		(at 53.975 -55.753)
		(size 0.508)
		(drill 0.254)
		(layers "F.Cu" "B.Cu")
		(net "VR_PVCCP_NTC")
	)
	(via
		(at 24.6634 -48.0568)
		(size 0.508)
		(drill 0.254)
		(layers "F.Cu" "B.Cu")
		(net "VR_PVCCP_NTC")
	)
	(segment
		(start 53.975 -56.261)
		(end 54.356 -56.642)
		(width 0.2032)
		(layer "B.Cu")
		(net "VR_PVCCP_NTC")
	)
	(segment
		(start 53.975 -55.753)
		(end 53.975 -56.261)
		(width 0.2032)
		(layer "B.Cu")
		(net "VR_PVCCP_NTC")
	)
	(segment
		(start 53.753766 -55.753)
		(end 53.975 -55.753)
		(width 0.2032)
		(layer "In2.Cu")
		(net "VR_PVCCP_NTC")
	)
	(segment
		(start 26.416 -51.8668)
		(end 26.99004 -52.44084)
		(width 0.2032)
		(layer "In2.Cu")
		(net "VR_PVCCP_NTC")
	)
	(segment
		(start 26.99004 -52.44084)
		(end 27.576526 -52.44084)
		(width 0.2032)
		(layer "In2.Cu")
		(net "VR_PVCCP_NTC")
	)
	(segment
		(start 26.416 -49.8094)
		(end 26.416 -51.8668)
		(width 0.2032)
		(layer "In2.Cu")
		(net "VR_PVCCP_NTC")
	)
	(segment
		(start 53.04917 -55.048404)
		(end 53.753766 -55.753)
		(width 0.2032)
		(layer "In2.Cu")
		(net "VR_PVCCP_NTC")
	)
	(segment
		(start 30.637226 -51.943)
		(end 33.74263 -55.048404)
		(width 0.2032)
		(layer "In2.Cu")
		(net "VR_PVCCP_NTC")
	)
	(segment
		(start 24.6634 -48.0568)
		(end 26.416 -49.8094)
		(width 0.2032)
		(layer "In2.Cu")
		(net "VR_PVCCP_NTC")
	)
	(segment
		(start 33.74263 -55.048404)
		(end 53.04917 -55.048404)
		(width 0.2032)
		(layer "In2.Cu")
		(net "VR_PVCCP_NTC")
	)
	(segment
		(start 27.576526 -52.44084)
		(end 28.074366 -51.943)
		(width 0.2032)
		(layer "In2.Cu")
		(net "VR_PVCCP_NTC")
	)
	(segment
		(start 28.074366 -51.943)
		(end 30.637226 -51.943)
		(width 0.2032)
		(layer "In2.Cu")
		(net "VR_PVCCP_NTC")
	)
	(segment
		(start 115.877594 -36.957)
		(end 115.2906 -37.543994)
		(width 0.127)
		(layer "F.Cu")
		(net "AVV_VSSCPUVIDSIO_1P03_SENSE")
	)
	(segment
		(start 112.88141 -38.608)
		(end 113.945416 -37.543994)
		(width 0.127)
		(layer "F.Cu")
		(net "AVV_VSSCPUVIDSIO_1P03_SENSE")
	)
	(segment
		(start 115.2906 -37.8841)
		(end 115.2906 -37.543994)
		(width 0.127)
		(layer "F.Cu")
		(net "AVV_VSSCPUVIDSIO_1P03_SENSE")
	)
	(segment
		(start 116.5352 -37.354002)
		(end 116.138198 -36.957)
		(width 0.127)
		(layer "F.Cu")
		(net "AVV_VSSCPUVIDSIO_1P03_SENSE")
	)
	(segment
		(start 111.628174 -38.608)
		(end 112.88141 -38.608)
		(width 0.127)
		(layer "F.Cu")
		(net "AVV_VSSCPUVIDSIO_1P03_SENSE")
	)
	(segment
		(start 113.945416 -37.543994)
		(end 115.2906 -37.543994)
		(width 0.127)
		(layer "F.Cu")
		(net "AVV_VSSCPUVIDSIO_1P03_SENSE")
	)
	(segment
		(start 116.138198 -36.957)
		(end 115.877594 -36.957)
		(width 0.127)
		(layer "F.Cu")
		(net "AVV_VSSCPUVIDSIO_1P03_SENSE")
	)
	(segment
		(start 111.603028 -38.582854)
		(end 111.628174 -38.608)
		(width 0.127)
		(layer "F.Cu")
		(net "AVV_VSSCPUVIDSIO_1P03_SENSE")
	)
	(via
		(at 115.2906 -37.8841)
		(size 0.7112)
		(drill 0.3556)
		(layers "F.Cu" "B.Cu")
		(net "AVV_VSSCPUVIDSIO_1P03_SENSE")
	)
	(segment
		(start 182.80253 -69.940678)
		(end 182.80253 -66.936874)
		(width 0.1778)
		(layer "F.Cu")
		(net "M_A_DQS_DN1")
	)
	(segment
		(start 109.11586 -42.941494)
		(end 109.195108 -42.941494)
		(width 0.1016)
		(layer "F.Cu")
		(net "M_A_DQS_DN1")
	)
	(segment
		(start 182.80253 -66.936874)
		(end 183.067198 -66.672206)
		(width 0.1778)
		(layer "F.Cu")
		(net "M_A_DQS_DN1")
	)
	(segment
		(start 182.950104 -70.806564)
		(end 182.950104 -70.088252)
		(width 0.1778)
		(layer "F.Cu")
		(net "M_A_DQS_DN1")
	)
	(segment
		(start 182.950104 -70.088252)
		(end 182.80253 -69.940678)
		(width 0.1778)
		(layer "F.Cu")
		(net "M_A_DQS_DN1")
	)
	(segment
		(start 108.772452 -42.598086)
		(end 109.11586 -42.941494)
		(width 0.1016)
		(layer "F.Cu")
		(net "M_A_DQS_DN1")
	)
	(via
		(at 183.067198 -66.672206)
		(size 0.4318)
		(drill 0.2032)
		(layers "F.Cu" "B.Cu")
		(net "M_A_DQS_DN1")
	)
	(via
		(at 108.772452 -42.598086)
		(size 0.4318)
		(drill 0.2032)
		(layers "F.Cu" "B.Cu")
		(net "M_A_DQS_DN1")
	)
	(segment
		(start 182.950104 -63.3603)
		(end 182.80253 -63.507874)
		(width 0.1778)
		(layer "B.Cu")
		(net "M_A_DQS_DN1")
	)
	(segment
		(start 182.80253 -63.507874)
		(end 182.80253 -66.407538)
		(width 0.1778)
		(layer "B.Cu")
		(net "M_A_DQS_DN1")
	)
	(segment
		(start 182.950104 -62.599824)
		(end 182.950104 -63.3603)
		(width 0.1778)
		(layer "B.Cu")
		(net "M_A_DQS_DN1")
	)
	(segment
		(start 182.80253 -66.407538)
		(end 183.067198 -66.672206)
		(width 0.1778)
		(layer "B.Cu")
		(net "M_A_DQS_DN1")
	)
	(segment
		(start 176.222914 -53.701442)
		(end 172.765466 -53.701442)
		(width 0.1524)
		(layer "In4.Cu")
		(net "M_A_DQS_DN1")
	)
	(segment
		(start 108.7755 -42.598086)
		(end 108.772452 -42.598086)
		(width 0.1016)
		(layer "In4.Cu")
		(net "M_A_DQS_DN1")
	)
	(segment
		(start 158.6484 -47.8282)
		(end 158.1404 -47.8282)
		(width 0.1524)
		(layer "In4.Cu")
		(net "M_A_DQS_DN1")
	)
	(segment
		(start 152.9969 -44.704)
		(end 151.7777 -43.4848)
		(width 0.1524)
		(layer "In4.Cu")
		(net "M_A_DQS_DN1")
	)
	(segment
		(start 180.3654 -59.269376)
		(end 180.3654 -57.843928)
		(width 0.1524)
		(layer "In4.Cu")
		(net "M_A_DQS_DN1")
	)
	(segment
		(start 183.067198 -66.672206)
		(end 182.8038 -66.408808)
		(width 0.1524)
		(layer "In4.Cu")
		(net "M_A_DQS_DN1")
	)
	(segment
		(start 159.856424 -44.7802)
		(end 159.116776 -44.7802)
		(width 0.1524)
		(layer "In4.Cu")
		(net "M_A_DQS_DN1")
	)
	(segment
		(start 158.8008 -45.096176)
		(end 158.8008 -47.6758)
		(width 0.1524)
		(layer "In4.Cu")
		(net "M_A_DQS_DN1")
	)
	(segment
		(start 160.1724 -47.6885)
		(end 160.1724 -45.096176)
		(width 0.1524)
		(layer "In4.Cu")
		(net "M_A_DQS_DN1")
	)
	(segment
		(start 157.5562 -44.704)
		(end 152.9969 -44.704)
		(width 0.1524)
		(layer "In4.Cu")
		(net "M_A_DQS_DN1")
	)
	(segment
		(start 182.8038 -66.408808)
		(end 182.8038 -61.707776)
		(width 0.1524)
		(layer "In4.Cu")
		(net "M_A_DQS_DN1")
	)
	(segment
		(start 160.1724 -45.096176)
		(end 159.856424 -44.7802)
		(width 0.1524)
		(layer "In4.Cu")
		(net "M_A_DQS_DN1")
	)
	(segment
		(start 180.3654 -57.843928)
		(end 176.222914 -53.701442)
		(width 0.1524)
		(layer "In4.Cu")
		(net "M_A_DQS_DN1")
	)
	(segment
		(start 182.8038 -61.707776)
		(end 180.3654 -59.269376)
		(width 0.1524)
		(layer "In4.Cu")
		(net "M_A_DQS_DN1")
	)
	(segment
		(start 119.0752 -42.9768)
		(end 118.25351 -42.15511)
		(width 0.1524)
		(layer "In4.Cu")
		(net "M_A_DQS_DN1")
	)
	(segment
		(start 122.8598 -43.4848)
		(end 122.3518 -42.9768)
		(width 0.1524)
		(layer "In4.Cu")
		(net "M_A_DQS_DN1")
	)
	(segment
		(start 109.710982 -42.908982)
		(end 109.086396 -42.908982)
		(width 0.1016)
		(layer "In4.Cu")
		(net "M_A_DQS_DN1")
	)
	(segment
		(start 118.145814 -42.15511)
		(end 117.900704 -41.91)
		(width 0.1016)
		(layer "In4.Cu")
		(net "M_A_DQS_DN1")
	)
	(segment
		(start 151.7777 -43.4848)
		(end 122.8598 -43.4848)
		(width 0.1524)
		(layer "In4.Cu")
		(net "M_A_DQS_DN1")
	)
	(segment
		(start 122.3518 -42.9768)
		(end 119.0752 -42.9768)
		(width 0.1524)
		(layer "In4.Cu")
		(net "M_A_DQS_DN1")
	)
	(segment
		(start 157.988 -47.6758)
		(end 157.988 -45.1358)
		(width 0.1524)
		(layer "In4.Cu")
		(net "M_A_DQS_DN1")
	)
	(segment
		(start 166.904924 -47.8409)
		(end 160.3248 -47.8409)
		(width 0.1524)
		(layer "In4.Cu")
		(net "M_A_DQS_DN1")
	)
	(segment
		(start 160.3248 -47.8409)
		(end 160.1724 -47.6885)
		(width 0.1524)
		(layer "In4.Cu")
		(net "M_A_DQS_DN1")
	)
	(segment
		(start 111.421672 -42.9768)
		(end 109.7788 -42.9768)
		(width 0.1016)
		(layer "In4.Cu")
		(net "M_A_DQS_DN1")
	)
	(segment
		(start 157.988 -45.1358)
		(end 157.5562 -44.704)
		(width 0.1524)
		(layer "In4.Cu")
		(net "M_A_DQS_DN1")
	)
	(segment
		(start 158.1404 -47.8282)
		(end 157.988 -47.6758)
		(width 0.1524)
		(layer "In4.Cu")
		(net "M_A_DQS_DN1")
	)
	(segment
		(start 112.488472 -41.91)
		(end 111.421672 -42.9768)
		(width 0.1016)
		(layer "In4.Cu")
		(net "M_A_DQS_DN1")
	)
	(segment
		(start 117.900704 -41.91)
		(end 112.488472 -41.91)
		(width 0.1016)
		(layer "In4.Cu")
		(net "M_A_DQS_DN1")
	)
	(segment
		(start 109.086396 -42.908982)
		(end 108.7755 -42.598086)
		(width 0.1016)
		(layer "In4.Cu")
		(net "M_A_DQS_DN1")
	)
	(segment
		(start 158.8008 -47.6758)
		(end 158.6484 -47.8282)
		(width 0.1524)
		(layer "In4.Cu")
		(net "M_A_DQS_DN1")
	)
	(segment
		(start 118.25351 -42.15511)
		(end 118.145814 -42.15511)
		(width 0.1016)
		(layer "In4.Cu")
		(net "M_A_DQS_DN1")
	)
	(segment
		(start 172.765466 -53.701442)
		(end 166.904924 -47.8409)
		(width 0.1524)
		(layer "In4.Cu")
		(net "M_A_DQS_DN1")
	)
	(segment
		(start 159.116776 -44.7802)
		(end 158.8008 -45.096176)
		(width 0.1524)
		(layer "In4.Cu")
		(net "M_A_DQS_DN1")
	)
	(segment
		(start 109.7788 -42.9768)
		(end 109.710982 -42.908982)
		(width 0.1016)
		(layer "In4.Cu")
		(net "M_A_DQS_DN1")
	)
	(segment
		(start 87.076788 -43.403774)
		(end 87.094822 -43.403774)
		(width 0.127)
		(layer "F.Cu")
		(net "TP_CPU_RSVD1")
	)
	(segment
		(start 87.4014 -43.097196)
		(end 87.4014 -43.060874)
		(width 0.127)
		(layer "F.Cu")
		(net "TP_CPU_RSVD1")
	)
	(segment
		(start 87.094822 -43.403774)
		(end 87.4014 -43.097196)
		(width 0.127)
		(layer "F.Cu")
		(net "TP_CPU_RSVD1")
	)
	(segment
		(start 87.4014 -43.060874)
		(end 87.41791 -43.044364)
		(width 0.127)
		(layer "F.Cu")
		(net "TP_CPU_RSVD1")
	)
	(via
		(at 87.41791 -43.044364)
		(size 0.4318)
		(drill 0.2032)
		(layers "F.Cu" "B.Cu")
		(net "TP_CPU_RSVD1")
	)
	(segment
		(start 86.746588 -43.561)
		(end 87.263224 -43.044364)
		(width 0.127)
		(layer "B.Cu")
		(net "TP_CPU_RSVD1")
	)
	(segment
		(start 87.263224 -43.044364)
		(end 87.41791 -43.044364)
		(width 0.127)
		(layer "B.Cu")
		(net "TP_CPU_RSVD1")
	)
	(segment
		(start 85.852 -43.561)
		(end 86.746588 -43.561)
		(width 0.127)
		(layer "B.Cu")
		(net "TP_CPU_RSVD1")
	)
	(segment
		(start 21.3868 -54.0766)
		(end 21.3868 -54.994302)
		(width 0.127)
		(layer "F.Cu")
		(net "VR_PVCCP_VSEN")
	)
	(segment
		(start 22.606 -52.6034)
		(end 22.9616 -52.959)
		(width 0.127)
		(layer "F.Cu")
		(net "VR_PVCCP_VSEN")
	)
	(segment
		(start 123.129802 -36.769802)
		(end 124.714 -38.354)
		(width 0.127)
		(layer "F.Cu")
		(net "VR_PVCCP_VSEN")
	)
	(segment
		(start 115.9637 -56.86171)
		(end 112.50041 -60.325)
		(width 0.127)
		(layer "F.Cu")
		(net "VR_PVCCP_VSEN")
	)
	(segment
		(start 103.78821 -60.325)
		(end 102.066852 -62.046358)
		(width 0.127)
		(layer "F.Cu")
		(net "VR_PVCCP_VSEN")
	)
	(segment
		(start 21.263102 -55.118)
		(end 21.263102 -55.547006)
		(width 0.127)
		(layer "F.Cu")
		(net "VR_PVCCP_VSEN")
	)
	(segment
		(start 22.7584 -50.9524)
		(end 22.8092 -51.0032)
		(width 0.127)
		(layer "F.Cu")
		(net "VR_PVCCP_VSEN")
	)
	(segment
		(start 118.491 -36.769802)
		(end 123.129802 -36.769802)
		(width 0.127)
		(layer "F.Cu")
		(net "VR_PVCCP_VSEN")
	)
	(segment
		(start 22.7838 -51.8668)
		(end 22.7838 -52.4256)
		(width 0.127)
		(layer "F.Cu")
		(net "VR_PVCCP_VSEN")
	)
	(segment
		(start 21.3868 -54.994302)
		(end 21.263102 -55.118)
		(width 0.127)
		(layer "F.Cu")
		(net "VR_PVCCP_VSEN")
	)
	(segment
		(start 121.2977 -48.488346)
		(end 115.9637 -53.822346)
		(width 0.127)
		(layer "F.Cu")
		(net "VR_PVCCP_VSEN")
	)
	(segment
		(start 118.1862 -36.465002)
		(end 118.237 -36.515802)
		(width 0.127)
		(layer "F.Cu")
		(net "VR_PVCCP_VSEN")
	)
	(segment
		(start 22.8473 -53.2511)
		(end 22.2123 -53.2511)
		(width 0.127)
		(layer "F.Cu")
		(net "VR_PVCCP_VSEN")
	)
	(segment
		(start 22.733 -51.816)
		(end 22.7838 -51.8668)
		(width 0.127)
		(layer "F.Cu")
		(net "VR_PVCCP_VSEN")
	)
	(segment
		(start 22.7838 -52.4256)
		(end 22.606 -52.6034)
		(width 0.127)
		(layer "F.Cu")
		(net "VR_PVCCP_VSEN")
	)
	(segment
		(start 22.2123 -53.2511)
		(end 21.3868 -54.0766)
		(width 0.127)
		(layer "F.Cu")
		(net "VR_PVCCP_VSEN")
	)
	(segment
		(start 124.714 -38.354)
		(end 124.714 -39.98341)
		(width 0.127)
		(layer "F.Cu")
		(net "VR_PVCCP_VSEN")
	)
	(segment
		(start 102.066852 -62.046358)
		(end 102.066852 -62.546992)
		(width 0.127)
		(layer "F.Cu")
		(net "VR_PVCCP_VSEN")
	)
	(segment
		(start 115.9637 -53.822346)
		(end 115.9637 -56.86171)
		(width 0.127)
		(layer "F.Cu")
		(net "VR_PVCCP_VSEN")
	)
	(segment
		(start 22.9616 -53.1368)
		(end 22.8473 -53.2511)
		(width 0.127)
		(layer "F.Cu")
		(net "VR_PVCCP_VSEN")
	)
	(segment
		(start 118.237 -36.515802)
		(end 118.491 -36.769802)
		(width 0.127)
		(layer "F.Cu")
		(net "VR_PVCCP_VSEN")
	)
	(segment
		(start 112.50041 -60.325)
		(end 103.78821 -60.325)
		(width 0.127)
		(layer "F.Cu")
		(net "VR_PVCCP_VSEN")
	)
	(segment
		(start 117.3988 -36.465002)
		(end 118.1862 -36.465002)
		(width 0.127)
		(layer "F.Cu")
		(net "VR_PVCCP_VSEN")
	)
	(segment
		(start 124.714 -39.98341)
		(end 121.2977 -43.39971)
		(width 0.127)
		(layer "F.Cu")
		(net "VR_PVCCP_VSEN")
	)
	(segment
		(start 121.2977 -43.39971)
		(end 121.2977 -48.488346)
		(width 0.127)
		(layer "F.Cu")
		(net "VR_PVCCP_VSEN")
	)
	(segment
		(start 22.9616 -52.959)
		(end 22.9616 -53.1368)
		(width 0.127)
		(layer "F.Cu")
		(net "VR_PVCCP_VSEN")
	)
	(segment
		(start 22.8092 -51.7398)
		(end 22.733 -51.816)
		(width 0.127)
		(layer "F.Cu")
		(net "VR_PVCCP_VSEN")
	)
	(segment
		(start 22.8092 -51.0032)
		(end 22.8092 -51.7398)
		(width 0.127)
		(layer "F.Cu")
		(net "VR_PVCCP_VSEN")
	)
	(via
		(at 21.844 -52.324)
		(size 0.7112)
		(drill 0.3556)
		(layers "F.Cu" "B.Cu")
		(net "VR_PVCCP_VSEN")
	)
	(via
		(at 22.733 -51.816)
		(size 0.508)
		(drill 0.254)
		(layers "F.Cu" "B.Cu")
		(net "VR_PVCCP_VSEN")
	)
	(via
		(at 102.066852 -62.546992)
		(size 0.508)
		(drill 0.254)
		(layers "F.Cu" "B.Cu")
		(net "VR_PVCCP_VSEN")
	)
	(segment
		(start 22.225 -52.324)
		(end 22.733 -51.816)
		(width 0.127)
		(layer "B.Cu")
		(net "VR_PVCCP_VSEN")
	)
	(segment
		(start 21.844 -52.324)
		(end 22.225 -52.324)
		(width 0.127)
		(layer "B.Cu")
		(net "VR_PVCCP_VSEN")
	)
	(segment
		(start 68.946268 -63.22695)
		(end 68.279518 -62.5602)
		(width 0.127)
		(layer "In9.Cu")
		(net "VR_PVCCP_VSEN")
	)
	(segment
		(start 63.35649 -59.0423)
		(end 60.678822 -59.0423)
		(width 0.127)
		(layer "In9.Cu")
		(net "VR_PVCCP_VSEN")
	)
	(segment
		(start 60.678822 -59.0423)
		(end 56.818022 -55.1815)
		(width 0.127)
		(layer "In9.Cu")
		(net "VR_PVCCP_VSEN")
	)
	(segment
		(start 23.0378 -52.81041)
		(end 23.0378 -52.1208)
		(width 0.127)
		(layer "In9.Cu")
		(net "VR_PVCCP_VSEN")
	)
	(segment
		(start 68.279518 -62.5602)
		(end 66.87439 -62.5602)
		(width 0.127)
		(layer "In9.Cu")
		(net "VR_PVCCP_VSEN")
	)
	(segment
		(start 23.0378 -52.1208)
		(end 22.733 -51.816)
		(width 0.127)
		(layer "In9.Cu")
		(net "VR_PVCCP_VSEN")
	)
	(segment
		(start 56.818022 -55.1815)
		(end 25.40889 -55.1815)
		(width 0.127)
		(layer "In9.Cu")
		(net "VR_PVCCP_VSEN")
	)
	(segment
		(start 102.066852 -62.546992)
		(end 101.635306 -62.546992)
		(width 0.127)
		(layer "In9.Cu")
		(net "VR_PVCCP_VSEN")
	)
	(segment
		(start 101.317044 -62.865)
		(end 92.00388 -62.865)
		(width 0.127)
		(layer "In9.Cu")
		(net "VR_PVCCP_VSEN")
	)
	(segment
		(start 25.40889 -55.1815)
		(end 23.0378 -52.81041)
		(width 0.127)
		(layer "In9.Cu")
		(net "VR_PVCCP_VSEN")
	)
	(segment
		(start 91.64193 -63.22695)
		(end 68.946268 -63.22695)
		(width 0.127)
		(layer "In9.Cu")
		(net "VR_PVCCP_VSEN")
	)
	(segment
		(start 92.00388 -62.865)
		(end 91.64193 -63.22695)
		(width 0.127)
		(layer "In9.Cu")
		(net "VR_PVCCP_VSEN")
	)
	(segment
		(start 101.635306 -62.546992)
		(end 101.317044 -62.865)
		(width 0.127)
		(layer "In9.Cu")
		(net "VR_PVCCP_VSEN")
	)
	(segment
		(start 66.87439 -62.5602)
		(end 63.35649 -59.0423)
		(width 0.127)
		(layer "In9.Cu")
		(net "VR_PVCCP_VSEN")
	)
	(segment
		(start 104.32161 -45.23486)
		(end 104.060244 -44.973494)
		(width 0.1016)
		(layer "F.Cu")
		(net "M_A_DQ19")
	)
	(segment
		(start 104.46004 -45.23486)
		(end 104.32161 -45.23486)
		(width 0.1016)
		(layer "F.Cu")
		(net "M_A_DQ19")
	)
	(segment
		(start 104.060244 -44.973494)
		(end 104.026208 -44.973494)
		(width 0.1016)
		(layer "F.Cu")
		(net "M_A_DQ19")
	)
	(segment
		(start 175.449992 -64.126618)
		(end 174.9552 -64.62141)
		(width 0.1778)
		(layer "F.Cu")
		(net "M_A_DQ19")
	)
	(segment
		(start 175.449992 -62.59322)
		(end 175.449992 -64.126618)
		(width 0.1778)
		(layer "F.Cu")
		(net "M_A_DQ19")
	)
	(segment
		(start 174.9552 -64.62141)
		(end 174.9552 -64.6684)
		(width 0.1778)
		(layer "F.Cu")
		(net "M_A_DQ19")
	)
	(via
		(at 104.46004 -45.23486)
		(size 0.4318)
		(drill 0.2032)
		(layers "F.Cu" "B.Cu")
		(net "M_A_DQ19")
	)
	(via
		(at 174.9552 -64.6684)
		(size 0.4318)
		(drill 0.2032)
		(layers "F.Cu" "B.Cu")
		(net "M_A_DQ19")
	)
	(segment
		(start 175.150018 -63.435738)
		(end 175.36668 -63.6524)
		(width 0.1778)
		(layer "B.Cu")
		(net "M_A_DQ19")
	)
	(segment
		(start 175.150018 -62.599824)
		(end 175.150018 -63.435738)
		(width 0.1778)
		(layer "B.Cu")
		(net "M_A_DQ19")
	)
	(segment
		(start 175.36668 -64.25692)
		(end 174.9552 -64.6684)
		(width 0.1778)
		(layer "B.Cu")
		(net "M_A_DQ19")
	)
	(segment
		(start 175.36668 -63.6524)
		(end 175.36668 -64.25692)
		(width 0.1778)
		(layer "B.Cu")
		(net "M_A_DQ19")
	)
	(segment
		(start 167.206168 -63.174118)
		(end 167.422068 -63.390018)
		(width 0.1524)
		(layer "In4.Cu")
		(net "M_A_DQ19")
	)
	(segment
		(start 165.763448 -61.166248)
		(end 165.979348 -61.382148)
		(width 0.1524)
		(layer "In4.Cu")
		(net "M_A_DQ19")
	)
	(segment
		(start 168.183052 -64.784986)
		(end 168.676066 -65.278)
		(width 0.1524)
		(layer "In4.Cu")
		(net "M_A_DQ19")
	)
	(segment
		(start 165.548056 -61.166248)
		(end 165.763448 -61.166248)
		(width 0.1524)
		(layer "In4.Cu")
		(net "M_A_DQ19")
	)
	(segment
		(start 167.320468 -63.922402)
		(end 167.536368 -64.138302)
		(width 0.1524)
		(layer "In4.Cu")
		(net "M_A_DQ19")
	)
	(segment
		(start 108.583984 -50.876962)
		(end 109.449362 -50.876962)
		(width 0.1524)
		(layer "In4.Cu")
		(net "M_A_DQ19")
	)
	(segment
		(start 142.039848 -52.4256)
		(end 143.716248 -54.102)
		(width 0.1524)
		(layer "In4.Cu")
		(net "M_A_DQ19")
	)
	(segment
		(start 167.536368 -64.138302)
		(end 167.75176 -64.138302)
		(width 0.1524)
		(layer "In4.Cu")
		(net "M_A_DQ19")
	)
	(segment
		(start 118.3132 -53.1114)
		(end 118.5418 -52.8828)
		(width 0.1524)
		(layer "In4.Cu")
		(net "M_A_DQ19")
	)
	(segment
		(start 166.673784 -63.275718)
		(end 166.889176 -63.275718)
		(width 0.1524)
		(layer "In4.Cu")
		(net "M_A_DQ19")
	)
	(segment
		(start 168.284652 -64.467994)
		(end 168.183052 -64.569594)
		(width 0.1524)
		(layer "In4.Cu")
		(net "M_A_DQ19")
	)
	(segment
		(start 168.284652 -64.252602)
		(end 168.284652 -64.467994)
		(width 0.1524)
		(layer "In4.Cu")
		(net "M_A_DQ19")
	)
	(segment
		(start 168.676066 -65.278)
		(end 174.3456 -65.278)
		(width 0.1524)
		(layer "In4.Cu")
		(net "M_A_DQ19")
	)
	(segment
		(start 166.880032 -62.422024)
		(end 166.457884 -62.844426)
		(width 0.1524)
		(layer "In4.Cu")
		(net "M_A_DQ19")
	)
	(segment
		(start 166.880032 -62.206632)
		(end 166.880032 -62.422024)
		(width 0.1524)
		(layer "In4.Cu")
		(net "M_A_DQ19")
	)
	(segment
		(start 167.75176 -64.138302)
		(end 167.85336 -64.036702)
		(width 0.1524)
		(layer "In4.Cu")
		(net "M_A_DQ19")
	)
	(segment
		(start 165.5953 -61.981842)
		(end 165.5953 -62.197234)
		(width 0.1524)
		(layer "In4.Cu")
		(net "M_A_DQ19")
	)
	(segment
		(start 167.85336 -64.036702)
		(end 168.068752 -64.036702)
		(width 0.1524)
		(layer "In4.Cu")
		(net "M_A_DQ19")
	)
	(segment
		(start 166.664132 -61.990732)
		(end 166.880032 -62.206632)
		(width 0.1524)
		(layer "In4.Cu")
		(net "M_A_DQ19")
	)
	(segment
		(start 164.948616 -61.55055)
		(end 165.164008 -61.55055)
		(width 0.1524)
		(layer "In4.Cu")
		(net "M_A_DQ19")
	)
	(segment
		(start 105.2322 -49.8602)
		(end 105.2322 -48.2346)
		(width 0.1016)
		(layer "In4.Cu")
		(net "M_A_DQ19")
	)
	(segment
		(start 109.449362 -50.876962)
		(end 111.6838 -53.1114)
		(width 0.1524)
		(layer "In4.Cu")
		(net "M_A_DQ19")
	)
	(segment
		(start 166.889176 -63.275718)
		(end 166.990776 -63.174118)
		(width 0.1524)
		(layer "In4.Cu")
		(net "M_A_DQ19")
	)
	(segment
		(start 165.8112 -62.413134)
		(end 166.026592 -62.413134)
		(width 0.1524)
		(layer "In4.Cu")
		(net "M_A_DQ19")
	)
	(segment
		(start 165.979348 -61.59754)
		(end 165.5953 -61.981842)
		(width 0.1524)
		(layer "In4.Cu")
		(net "M_A_DQ19")
	)
	(segment
		(start 168.183052 -64.569594)
		(end 168.183052 -64.784986)
		(width 0.1524)
		(layer "In4.Cu")
		(net "M_A_DQ19")
	)
	(segment
		(start 105.2322 -48.2346)
		(end 104.9909 -47.9933)
		(width 0.1016)
		(layer "In4.Cu")
		(net "M_A_DQ19")
	)
	(segment
		(start 104.112568 -47.648368)
		(end 104.112568 -45.582332)
		(width 0.1016)
		(layer "In4.Cu")
		(net "M_A_DQ19")
	)
	(segment
		(start 168.068752 -64.036702)
		(end 168.284652 -64.252602)
		(width 0.1524)
		(layer "In4.Cu")
		(net "M_A_DQ19")
	)
	(segment
		(start 165.979348 -61.382148)
		(end 165.979348 -61.59754)
		(width 0.1524)
		(layer "In4.Cu")
		(net "M_A_DQ19")
	)
	(segment
		(start 143.716248 -54.102)
		(end 144.974818 -54.102)
		(width 0.1524)
		(layer "In4.Cu")
		(net "M_A_DQ19")
	)
	(segment
		(start 123.8758 -52.4256)
		(end 142.039848 -52.4256)
		(width 0.1524)
		(layer "In4.Cu")
		(net "M_A_DQ19")
	)
	(segment
		(start 167.320468 -63.70701)
		(end 167.320468 -63.922402)
		(width 0.1524)
		(layer "In4.Cu")
		(net "M_A_DQ19")
	)
	(segment
		(start 167.422068 -63.390018)
		(end 167.422068 -63.60541)
		(width 0.1524)
		(layer "In4.Cu")
		(net "M_A_DQ19")
	)
	(segment
		(start 111.6838 -53.1114)
		(end 118.3132 -53.1114)
		(width 0.1524)
		(layer "In4.Cu")
		(net "M_A_DQ19")
	)
	(segment
		(start 166.44874 -61.990732)
		(end 166.664132 -61.990732)
		(width 0.1524)
		(layer "In4.Cu")
		(net "M_A_DQ19")
	)
	(segment
		(start 106.838496 -50.3936)
		(end 105.7656 -50.3936)
		(width 0.1016)
		(layer "In4.Cu")
		(net "M_A_DQ19")
	)
	(segment
		(start 104.9909 -47.9933)
		(end 104.4575 -47.9933)
		(width 0.1016)
		(layer "In4.Cu")
		(net "M_A_DQ19")
	)
	(segment
		(start 144.974818 -54.102)
		(end 150.131018 -59.2582)
		(width 0.1524)
		(layer "In4.Cu")
		(net "M_A_DQ19")
	)
	(segment
		(start 150.131018 -59.2582)
		(end 162.656266 -59.2582)
		(width 0.1524)
		(layer "In4.Cu")
		(net "M_A_DQ19")
	)
	(segment
		(start 104.4575 -47.9933)
		(end 104.112568 -47.648368)
		(width 0.1016)
		(layer "In4.Cu")
		(net "M_A_DQ19")
	)
	(segment
		(start 167.422068 -63.60541)
		(end 167.320468 -63.70701)
		(width 0.1524)
		(layer "In4.Cu")
		(net "M_A_DQ19")
	)
	(segment
		(start 166.990776 -63.174118)
		(end 167.206168 -63.174118)
		(width 0.1524)
		(layer "In4.Cu")
		(net "M_A_DQ19")
	)
	(segment
		(start 106.845608 -50.386488)
		(end 106.838496 -50.3936)
		(width 0.1016)
		(layer "In4.Cu")
		(net "M_A_DQ19")
	)
	(segment
		(start 166.026592 -62.413134)
		(end 166.44874 -61.990732)
		(width 0.1524)
		(layer "In4.Cu")
		(net "M_A_DQ19")
	)
	(segment
		(start 174.3456 -65.278)
		(end 174.9552 -64.6684)
		(width 0.1524)
		(layer "In4.Cu")
		(net "M_A_DQ19")
	)
	(segment
		(start 105.7656 -50.3936)
		(end 105.2322 -49.8602)
		(width 0.1016)
		(layer "In4.Cu")
		(net "M_A_DQ19")
	)
	(segment
		(start 166.457884 -63.059818)
		(end 166.673784 -63.275718)
		(width 0.1524)
		(layer "In4.Cu")
		(net "M_A_DQ19")
	)
	(segment
		(start 108.583984 -50.876962)
		(end 108.09351 -50.386488)
		(width 0.1016)
		(layer "In4.Cu")
		(net "M_A_DQ19")
	)
	(segment
		(start 118.5418 -52.8828)
		(end 123.4186 -52.8828)
		(width 0.1524)
		(layer "In4.Cu")
		(net "M_A_DQ19")
	)
	(segment
		(start 162.656266 -59.2582)
		(end 164.948616 -61.55055)
		(width 0.1524)
		(layer "In4.Cu")
		(net "M_A_DQ19")
	)
	(segment
		(start 108.09351 -50.386488)
		(end 106.845608 -50.386488)
		(width 0.1016)
		(layer "In4.Cu")
		(net "M_A_DQ19")
	)
	(segment
		(start 166.457884 -62.844426)
		(end 166.457884 -63.059818)
		(width 0.1524)
		(layer "In4.Cu")
		(net "M_A_DQ19")
	)
	(segment
		(start 165.164008 -61.55055)
		(end 165.548056 -61.166248)
		(width 0.1524)
		(layer "In4.Cu")
		(net "M_A_DQ19")
	)
	(segment
		(start 165.5953 -62.197234)
		(end 165.8112 -62.413134)
		(width 0.1524)
		(layer "In4.Cu")
		(net "M_A_DQ19")
	)
	(segment
		(start 123.4186 -52.8828)
		(end 123.8758 -52.4256)
		(width 0.1524)
		(layer "In4.Cu")
		(net "M_A_DQ19")
	)
	(segment
		(start 104.112568 -45.582332)
		(end 104.46004 -45.23486)
		(width 0.1016)
		(layer "In4.Cu")
		(net "M_A_DQ19")
	)
	(segment
		(start 63.10122 -41.8084)
		(end 63.10122 -40.77081)
		(width 0.1143)
		(layer "F.Cu")
		(net "SMBUS_HOST_R_CLK")
	)
	(segment
		(start 62.9158 -40.58539)
		(end 62.15761 -40.58539)
		(width 0.1143)
		(layer "F.Cu")
		(net "SMBUS_HOST_R_CLK")
	)
	(segment
		(start 63.10122 -40.77081)
		(end 62.9158 -40.58539)
		(width 0.1143)
		(layer "F.Cu")
		(net "SMBUS_HOST_R_CLK")
	)
	(segment
		(start 67.2084 -42.2402)
		(end 67.2084 -43.1546)
		(width 0.1143)
		(layer "F.Cu")
		(net "SMBUS_HOST_R_CLK")
	)
	(segment
		(start 67.2084 -43.1546)
		(end 67.2084 -43.9674)
		(width 0.1143)
		(layer "F.Cu")
		(net "SMBUS_HOST_R_CLK")
	)
	(via
		(at 62.15761 -40.58539)
		(size 0.508)
		(drill 0.254)
		(layers "F.Cu" "B.Cu")
		(net "SMBUS_HOST_R_CLK")
	)
	(via
		(at 67.2084 -43.9674)
		(size 0.508)
		(drill 0.254)
		(layers "F.Cu" "B.Cu")
		(net "SMBUS_HOST_R_CLK")
	)
	(via
		(at 67.2084 -43.1546)
		(size 0.7112)
		(drill 0.3556)
		(layers "F.Cu" "B.Cu")
		(net "SMBUS_HOST_R_CLK")
	)
	(segment
		(start 67.2084 -43.9674)
		(end 67.267582 -43.908218)
		(width 0.0889)
		(layer "In7.Cu")
		(net "SMBUS_HOST_R_CLK")
	)
	(segment
		(start 65.447672 -40.58539)
		(end 62.15761 -40.58539)
		(width 0.0889)
		(layer "In7.Cu")
		(net "SMBUS_HOST_R_CLK")
	)
	(segment
		(start 67.267582 -43.908218)
		(end 67.267582 -42.4053)
		(width 0.0889)
		(layer "In7.Cu")
		(net "SMBUS_HOST_R_CLK")
	)
	(segment
		(start 67.267582 -42.4053)
		(end 65.447672 -40.58539)
		(width 0.0889)
		(layer "In7.Cu")
		(net "SMBUS_HOST_R_CLK")
	)
	(segment
		(start 19.4564 -61.9506)
		(end 18.669 -61.9506)
		(width 0.2032)
		(layer "F.Cu")
		(net "VR_PVNN_FB")
	)
	(segment
		(start 18.669 -61.9506)
		(end 18.4404 -62.1792)
		(width 0.2032)
		(layer "F.Cu")
		(net "VR_PVNN_FB")
	)
	(segment
		(start 19.662902 -61.292994)
		(end 19.662902 -61.744098)
		(width 0.2032)
		(layer "F.Cu")
		(net "VR_PVNN_FB")
	)
	(segment
		(start 19.662902 -61.744098)
		(end 19.4564 -61.9506)
		(width 0.2032)
		(layer "F.Cu")
		(net "VR_PVNN_FB")
	)
	(via
		(at 19.4564 -59.72302)
		(size 0.7112)
		(drill 0.3556)
		(layers "F.Cu" "B.Cu")
		(net "VR_PVNN_FB")
	)
	(via
		(at 18.4404 -62.1792)
		(size 0.508)
		(drill 0.254)
		(layers "F.Cu" "B.Cu")
		(net "VR_PVNN_FB")
	)
	(segment
		(start 19.4564 -59.309)
		(end 19.4564 -59.72302)
		(width 0.2032)
		(layer "B.Cu")
		(net "VR_PVNN_FB")
	)
	(segment
		(start 19.1516 -61.468)
		(end 18.4404 -62.1792)
		(width 0.2032)
		(layer "B.Cu")
		(net "VR_PVNN_FB")
	)
	(segment
		(start 19.812 -60.6552)
		(end 19.7866 -60.6298)
		(width 0.2032)
		(layer "B.Cu")
		(net "VR_PVNN_FB")
	)
	(segment
		(start 18.796 -58.6486)
		(end 19.4564 -59.309)
		(width 0.2032)
		(layer "B.Cu")
		(net "VR_PVNN_FB")
	)
	(segment
		(start 19.0246 -60.6298)
		(end 19.0246 -61.2648)
		(width 0.2032)
		(layer "B.Cu")
		(net "VR_PVNN_FB")
	)
	(segment
		(start 19.7866 -60.6298)
		(end 19.0246 -60.6298)
		(width 0.2032)
		(layer "B.Cu")
		(net "VR_PVNN_FB")
	)
	(segment
		(start 19.0246 -60.15482)
		(end 19.0246 -60.6298)
		(width 0.2032)
		(layer "B.Cu")
		(net "VR_PVNN_FB")
	)
	(segment
		(start 19.4564 -59.72302)
		(end 19.0246 -60.15482)
		(width 0.2032)
		(layer "B.Cu")
		(net "VR_PVNN_FB")
	)
	(segment
		(start 19.1516 -61.3918)
		(end 19.1516 -61.468)
		(width 0.2032)
		(layer "B.Cu")
		(net "VR_PVNN_FB")
	)
	(segment
		(start 17.526 -58.6486)
		(end 18.796 -58.6486)
		(width 0.2032)
		(layer "B.Cu")
		(net "VR_PVNN_FB")
	)
	(segment
		(start 19.0246 -61.2648)
		(end 19.1516 -61.3918)
		(width 0.2032)
		(layer "B.Cu")
		(net "VR_PVNN_FB")
	)
	(segment
		(start 138.550142 -69.639942)
		(end 138.284712 -69.374512)
		(width 0.1778)
		(layer "F.Cu")
		(net "M_A_DQ52")
	)
	(segment
		(start 138.284712 -69.374512)
		(end 138.250168 -69.374512)
		(width 0.1778)
		(layer "F.Cu")
		(net "M_A_DQ52")
	)
	(segment
		(start 100.917248 -51.476402)
		(end 100.917248 -50.995834)
		(width 0.1016)
		(layer "F.Cu")
		(net "M_A_DQ52")
	)
	(segment
		(start 100.6475 -51.74615)
		(end 100.917248 -51.476402)
		(width 0.1016)
		(layer "F.Cu")
		(net "M_A_DQ52")
	)
	(segment
		(start 101.5238 -53.957728)
		(end 100.6475 -53.081428)
		(width 0.1016)
		(layer "F.Cu")
		(net "M_A_DQ52")
	)
	(segment
		(start 138.550142 -70.806564)
		(end 138.550142 -69.639942)
		(width 0.1778)
		(layer "F.Cu")
		(net "M_A_DQ52")
	)
	(segment
		(start 100.6475 -53.081428)
		(end 100.6475 -51.74615)
		(width 0.1016)
		(layer "F.Cu")
		(net "M_A_DQ52")
	)
	(segment
		(start 101.5238 -54.9656)
		(end 101.5238 -53.957728)
		(width 0.1016)
		(layer "F.Cu")
		(net "M_A_DQ52")
	)
	(via
		(at 101.5238 -54.9656)
		(size 0.4318)
		(drill 0.2032)
		(layers "F.Cu" "B.Cu")
		(net "M_A_DQ52")
	)
	(via
		(at 138.250168 -69.374512)
		(size 0.4318)
		(drill 0.2032)
		(layers "F.Cu" "B.Cu")
		(net "M_A_DQ52")
	)
	(segment
		(start 138.250168 -70.79996)
		(end 138.250168 -69.374512)
		(width 0.1778)
		(layer "B.Cu")
		(net "M_A_DQ52")
	)
	(segment
		(start 111.0996 -59.944)
		(end 129.8702 -59.944)
		(width 0.1524)
		(layer "In4.Cu")
		(net "M_A_DQ52")
	)
	(segment
		(start 139.2682 -65.60439)
		(end 138.816588 -66.056002)
		(width 0.1524)
		(layer "In4.Cu")
		(net "M_A_DQ52")
	)
	(segment
		(start 138.0744 -66.208402)
		(end 138.0744 -69.222112)
		(width 0.1524)
		(layer "In4.Cu")
		(net "M_A_DQ52")
	)
	(segment
		(start 106.8324 -60.706)
		(end 107.1372 -60.706)
		(width 0.1524)
		(layer "In4.Cu")
		(net "M_A_DQ52")
	)
	(segment
		(start 110.3376 -60.4774)
		(end 110.49 -60.6298)
		(width 0.1524)
		(layer "In4.Cu")
		(net "M_A_DQ52")
	)
	(segment
		(start 110.1852 -59.944)
		(end 110.3376 -60.0964)
		(width 0.1524)
		(layer "In4.Cu")
		(net "M_A_DQ52")
	)
	(segment
		(start 138.816588 -66.056002)
		(end 138.2268 -66.056002)
		(width 0.1524)
		(layer "In4.Cu")
		(net "M_A_DQ52")
	)
	(segment
		(start 109.2708 -60.706)
		(end 109.5756 -60.706)
		(width 0.1524)
		(layer "In4.Cu")
		(net "M_A_DQ52")
	)
	(segment
		(start 103.827072 -58.8518)
		(end 104.919272 -59.944)
		(width 0.1524)
		(layer "In4.Cu")
		(net "M_A_DQ52")
	)
	(segment
		(start 108.0516 -60.706)
		(end 108.3564 -60.706)
		(width 0.1524)
		(layer "In4.Cu")
		(net "M_A_DQ52")
	)
	(segment
		(start 109.728 -60.5536)
		(end 109.728 -60.0964)
		(width 0.1524)
		(layer "In4.Cu")
		(net "M_A_DQ52")
	)
	(segment
		(start 107.7468 -59.944)
		(end 107.8992 -60.0964)
		(width 0.1524)
		(layer "In4.Cu")
		(net "M_A_DQ52")
	)
	(segment
		(start 108.3564 -60.706)
		(end 108.5088 -60.5536)
		(width 0.1524)
		(layer "In4.Cu")
		(net "M_A_DQ52")
	)
	(segment
		(start 110.49 -60.6298)
		(end 110.7948 -60.6298)
		(width 0.1524)
		(layer "In4.Cu")
		(net "M_A_DQ52")
	)
	(segment
		(start 138.0744 -69.222112)
		(end 138.2268 -69.374512)
		(width 0.1524)
		(layer "In4.Cu")
		(net "M_A_DQ52")
	)
	(segment
		(start 109.1184 -60.0964)
		(end 109.1184 -60.5536)
		(width 0.1524)
		(layer "In4.Cu")
		(net "M_A_DQ52")
	)
	(segment
		(start 109.1184 -60.5536)
		(end 109.2708 -60.706)
		(width 0.1524)
		(layer "In4.Cu")
		(net "M_A_DQ52")
	)
	(segment
		(start 108.966 -59.944)
		(end 109.1184 -60.0964)
		(width 0.1524)
		(layer "In4.Cu")
		(net "M_A_DQ52")
	)
	(segment
		(start 138.2268 -69.374512)
		(end 138.250168 -69.374512)
		(width 0.1524)
		(layer "In4.Cu")
		(net "M_A_DQ52")
	)
	(segment
		(start 106.68 -60.0964)
		(end 106.68 -60.5536)
		(width 0.1524)
		(layer "In4.Cu")
		(net "M_A_DQ52")
	)
	(segment
		(start 102.616 -58.8518)
		(end 103.827072 -58.8518)
		(width 0.1524)
		(layer "In4.Cu")
		(net "M_A_DQ52")
	)
	(segment
		(start 107.1372 -60.706)
		(end 107.2896 -60.5536)
		(width 0.1524)
		(layer "In4.Cu")
		(net "M_A_DQ52")
	)
	(segment
		(start 106.68 -60.5536)
		(end 106.8324 -60.706)
		(width 0.1524)
		(layer "In4.Cu")
		(net "M_A_DQ52")
	)
	(segment
		(start 109.728 -60.0964)
		(end 109.8804 -59.944)
		(width 0.1524)
		(layer "In4.Cu")
		(net "M_A_DQ52")
	)
	(segment
		(start 102.1334 -55.5752)
		(end 102.1334 -58.3692)
		(width 0.1524)
		(layer "In4.Cu")
		(net "M_A_DQ52")
	)
	(segment
		(start 129.8702 -59.944)
		(end 130.1496 -60.2234)
		(width 0.1524)
		(layer "In4.Cu")
		(net "M_A_DQ52")
	)
	(segment
		(start 108.6612 -59.944)
		(end 108.966 -59.944)
		(width 0.1524)
		(layer "In4.Cu")
		(net "M_A_DQ52")
	)
	(segment
		(start 104.919272 -59.944)
		(end 106.5276 -59.944)
		(width 0.1524)
		(layer "In4.Cu")
		(net "M_A_DQ52")
	)
	(segment
		(start 106.5276 -59.944)
		(end 106.68 -60.0964)
		(width 0.1524)
		(layer "In4.Cu")
		(net "M_A_DQ52")
	)
	(segment
		(start 109.5756 -60.706)
		(end 109.728 -60.5536)
		(width 0.1524)
		(layer "In4.Cu")
		(net "M_A_DQ52")
	)
	(segment
		(start 110.7948 -60.6298)
		(end 110.9472 -60.4774)
		(width 0.1524)
		(layer "In4.Cu")
		(net "M_A_DQ52")
	)
	(segment
		(start 107.442 -59.944)
		(end 107.7468 -59.944)
		(width 0.1524)
		(layer "In4.Cu")
		(net "M_A_DQ52")
	)
	(segment
		(start 139.2682 -63.7286)
		(end 139.2682 -65.60439)
		(width 0.1524)
		(layer "In4.Cu")
		(net "M_A_DQ52")
	)
	(segment
		(start 135.763 -60.2234)
		(end 139.2682 -63.7286)
		(width 0.1524)
		(layer "In4.Cu")
		(net "M_A_DQ52")
	)
	(segment
		(start 138.2268 -66.056002)
		(end 138.0744 -66.208402)
		(width 0.1524)
		(layer "In4.Cu")
		(net "M_A_DQ52")
	)
	(segment
		(start 110.9472 -60.4774)
		(end 110.9472 -60.0964)
		(width 0.1524)
		(layer "In4.Cu")
		(net "M_A_DQ52")
	)
	(segment
		(start 107.8992 -60.0964)
		(end 107.8992 -60.5536)
		(width 0.1524)
		(layer "In4.Cu")
		(net "M_A_DQ52")
	)
	(segment
		(start 109.8804 -59.944)
		(end 110.1852 -59.944)
		(width 0.1524)
		(layer "In4.Cu")
		(net "M_A_DQ52")
	)
	(segment
		(start 107.2896 -60.5536)
		(end 107.2896 -60.0964)
		(width 0.1524)
		(layer "In4.Cu")
		(net "M_A_DQ52")
	)
	(segment
		(start 110.3376 -60.0964)
		(end 110.3376 -60.4774)
		(width 0.1524)
		(layer "In4.Cu")
		(net "M_A_DQ52")
	)
	(segment
		(start 101.5238 -54.9656)
		(end 102.1334 -55.5752)
		(width 0.1524)
		(layer "In4.Cu")
		(net "M_A_DQ52")
	)
	(segment
		(start 107.8992 -60.5536)
		(end 108.0516 -60.706)
		(width 0.1524)
		(layer "In4.Cu")
		(net "M_A_DQ52")
	)
	(segment
		(start 102.1334 -58.3692)
		(end 102.616 -58.8518)
		(width 0.1524)
		(layer "In4.Cu")
		(net "M_A_DQ52")
	)
	(segment
		(start 107.2896 -60.0964)
		(end 107.442 -59.944)
		(width 0.1524)
		(layer "In4.Cu")
		(net "M_A_DQ52")
	)
	(segment
		(start 110.9472 -60.0964)
		(end 111.0996 -59.944)
		(width 0.1524)
		(layer "In4.Cu")
		(net "M_A_DQ52")
	)
	(segment
		(start 130.1496 -60.2234)
		(end 135.763 -60.2234)
		(width 0.1524)
		(layer "In4.Cu")
		(net "M_A_DQ52")
	)
	(segment
		(start 108.5088 -60.5536)
		(end 108.5088 -60.0964)
		(width 0.1524)
		(layer "In4.Cu")
		(net "M_A_DQ52")
	)
	(segment
		(start 108.5088 -60.0964)
		(end 108.6612 -59.944)
		(width 0.1524)
		(layer "In4.Cu")
		(net "M_A_DQ52")
	)
	(segment
		(start 83.233768 -37.111432)
		(end 83.234784 -37.111432)
		(width 0.1143)
		(layer "F.Cu")
		(net "SPI_CPU_MISO")
	)
	(segment
		(start 57.146952 -36.322)
		(end 58.31586 -37.490908)
		(width 0.1143)
		(layer "F.Cu")
		(net "SPI_CPU_MISO")
	)
	(segment
		(start 68.707 -39.6875)
		(end 69.0118 -39.6875)
		(width 0.1143)
		(layer "F.Cu")
		(net "SPI_CPU_MISO")
	)
	(segment
		(start 82.900266 -37.444934)
		(end 83.233768 -37.111432)
		(width 0.1143)
		(layer "F.Cu")
		(net "SPI_CPU_MISO")
	)
	(segment
		(start 56.4388 -36.068)
		(end 56.6928 -36.322)
		(width 0.1143)
		(layer "F.Cu")
		(net "SPI_CPU_MISO")
	)
	(segment
		(start 65.852294 -37.856414)
		(end 65.597532 -37.856414)
		(width 0.1143)
		(layer "F.Cu")
		(net "SPI_CPU_MISO")
	)
	(segment
		(start 68.072 -38.5826)
		(end 68.072 -39.0779)
		(width 0.1143)
		(layer "F.Cu")
		(net "SPI_CPU_MISO")
	)
	(segment
		(start 67.437 -38.509194)
		(end 67.3354 -38.407594)
		(width 0.1143)
		(layer "F.Cu")
		(net "SPI_CPU_MISO")
	)
	(segment
		(start 66.725292 -37.845492)
		(end 66.370708 -37.490908)
		(width 0.1143)
		(layer "F.Cu")
		(net "SPI_CPU_MISO")
	)
	(segment
		(start 82.885788 -37.444934)
		(end 82.900266 -37.444934)
		(width 0.1143)
		(layer "F.Cu")
		(net "SPI_CPU_MISO")
	)
	(segment
		(start 66.370708 -37.490908)
		(end 66.2178 -37.490908)
		(width 0.1143)
		(layer "F.Cu")
		(net "SPI_CPU_MISO")
	)
	(segment
		(start 67.3354 -38.407594)
		(end 67.115182 -38.407594)
		(width 0.1143)
		(layer "F.Cu")
		(net "SPI_CPU_MISO")
	)
	(segment
		(start 68.6816 -38.5826)
		(end 68.58 -38.481)
		(width 0.1143)
		(layer "F.Cu")
		(net "SPI_CPU_MISO")
	)
	(segment
		(start 67.437 -39.0779)
		(end 67.437 -38.509194)
		(width 0.1143)
		(layer "F.Cu")
		(net "SPI_CPU_MISO")
	)
	(segment
		(start 69.0118 -39.6875)
		(end 69.1134 -39.5859)
		(width 0.1143)
		(layer "F.Cu")
		(net "SPI_CPU_MISO")
	)
	(segment
		(start 66.551302 -38.80993)
		(end 66.308732 -38.56736)
		(width 0.1143)
		(layer "F.Cu")
		(net "SPI_CPU_MISO")
	)
	(segment
		(start 69.0118 -38.883844)
		(end 68.7832 -38.883844)
		(width 0.1143)
		(layer "F.Cu")
		(net "SPI_CPU_MISO")
	)
	(segment
		(start 62.82055 -37.490908)
		(end 62.8904 -37.421058)
		(width 0.1143)
		(layer "F.Cu")
		(net "SPI_CPU_MISO")
	)
	(segment
		(start 67.115182 -38.407594)
		(end 66.712846 -38.80993)
		(width 0.1143)
		(layer "F.Cu")
		(net "SPI_CPU_MISO")
	)
	(segment
		(start 68.072 -39.0779)
		(end 67.9704 -39.1795)
		(width 0.1143)
		(layer "F.Cu")
		(net "SPI_CPU_MISO")
	)
	(segment
		(start 62.96025 -37.490908)
		(end 62.8904 -37.421058)
		(width 0.1143)
		(layer "F.Cu")
		(net "SPI_CPU_MISO")
	)
	(segment
		(start 65.597532 -37.856414)
		(end 65.232026 -37.490908)
		(width 0.1143)
		(layer "F.Cu")
		(net "SPI_CPU_MISO")
	)
	(segment
		(start 65.232026 -37.490908)
		(end 62.96025 -37.490908)
		(width 0.1143)
		(layer "F.Cu")
		(net "SPI_CPU_MISO")
	)
	(segment
		(start 67.9704 -39.1795)
		(end 67.5386 -39.1795)
		(width 0.1143)
		(layer "F.Cu")
		(net "SPI_CPU_MISO")
	)
	(segment
		(start 67.5386 -39.1795)
		(end 67.437 -39.0779)
		(width 0.1143)
		(layer "F.Cu")
		(net "SPI_CPU_MISO")
	)
	(segment
		(start 66.725292 -37.989256)
		(end 66.725292 -37.845492)
		(width 0.1143)
		(layer "F.Cu")
		(net "SPI_CPU_MISO")
	)
	(segment
		(start 58.31586 -37.490908)
		(end 62.82055 -37.490908)
		(width 0.1143)
		(layer "F.Cu")
		(net "SPI_CPU_MISO")
	)
	(segment
		(start 66.308732 -38.56736)
		(end 66.308732 -38.405816)
		(width 0.1143)
		(layer "F.Cu")
		(net "SPI_CPU_MISO")
	)
	(segment
		(start 66.2178 -37.490908)
		(end 65.852294 -37.856414)
		(width 0.1143)
		(layer "F.Cu")
		(net "SPI_CPU_MISO")
	)
	(segment
		(start 68.6816 -38.782244)
		(end 68.6816 -38.5826)
		(width 0.1143)
		(layer "F.Cu")
		(net "SPI_CPU_MISO")
	)
	(segment
		(start 68.1736 -38.481)
		(end 68.072 -38.5826)
		(width 0.1143)
		(layer "F.Cu")
		(net "SPI_CPU_MISO")
	)
	(segment
		(start 56.6928 -36.322)
		(end 57.146952 -36.322)
		(width 0.1143)
		(layer "F.Cu")
		(net "SPI_CPU_MISO")
	)
	(segment
		(start 69.1134 -39.5859)
		(end 69.1134 -38.985444)
		(width 0.1143)
		(layer "F.Cu")
		(net "SPI_CPU_MISO")
	)
	(segment
		(start 66.308732 -38.405816)
		(end 66.725292 -37.989256)
		(width 0.1143)
		(layer "F.Cu")
		(net "SPI_CPU_MISO")
	)
	(segment
		(start 68.58 -38.481)
		(end 68.1736 -38.481)
		(width 0.1143)
		(layer "F.Cu")
		(net "SPI_CPU_MISO")
	)
	(segment
		(start 69.1134 -38.985444)
		(end 69.0118 -38.883844)
		(width 0.1143)
		(layer "F.Cu")
		(net "SPI_CPU_MISO")
	)
	(segment
		(start 66.712846 -38.80993)
		(end 66.551302 -38.80993)
		(width 0.1143)
		(layer "F.Cu")
		(net "SPI_CPU_MISO")
	)
	(segment
		(start 68.7832 -38.883844)
		(end 68.6816 -38.782244)
		(width 0.1143)
		(layer "F.Cu")
		(net "SPI_CPU_MISO")
	)
	(via
		(at 83.234784 -37.111432)
		(size 0.4318)
		(drill 0.2032)
		(layers "F.Cu" "B.Cu")
		(net "SPI_CPU_MISO")
	)
	(via
		(at 68.707 -39.6875)
		(size 0.508)
		(drill 0.254)
		(layers "F.Cu" "B.Cu")
		(net "SPI_CPU_MISO")
	)
	(via
		(at 62.8904 -37.421058)
		(size 0.7112)
		(drill 0.3556)
		(layers "F.Cu" "B.Cu")
		(net "SPI_CPU_MISO")
	)
	(segment
		(start 69.561456 -37.03955)
		(end 68.707 -37.894006)
		(width 0.0889)
		(layer "In2.Cu")
		(net "SPI_CPU_MISO")
	)
	(segment
		(start 80.3529 -36.6903)
		(end 80.264 -36.6014)
		(width 0.0889)
		(layer "In2.Cu")
		(net "SPI_CPU_MISO")
	)
	(segment
		(start 77.5335 -37.4777)
		(end 77.5335 -36.6903)
		(width 0.0889)
		(layer "In2.Cu")
		(net "SPI_CPU_MISO")
	)
	(segment
		(start 77.1525 -36.6014)
		(end 77.0636 -36.6903)
		(width 0.0889)
		(layer "In2.Cu")
		(net "SPI_CPU_MISO")
	)
	(segment
		(start 77.9145 -37.5666)
		(end 77.6224 -37.5666)
		(width 0.0889)
		(layer "In2.Cu")
		(net "SPI_CPU_MISO")
	)
	(segment
		(start 79.7941 -37.5666)
		(end 79.502 -37.5666)
		(width 0.0889)
		(layer "In2.Cu")
		(net "SPI_CPU_MISO")
	)
	(segment
		(start 77.0636 -37.4777)
		(end 76.9747 -37.5666)
		(width 0.0889)
		(layer "In2.Cu")
		(net "SPI_CPU_MISO")
	)
	(segment
		(start 78.8543 -37.5666)
		(end 78.5622 -37.5666)
		(width 0.0889)
		(layer "In2.Cu")
		(net "SPI_CPU_MISO")
	)
	(segment
		(start 78.4733 -37.4777)
		(end 78.4733 -36.6903)
		(width 0.0889)
		(layer "In2.Cu")
		(net "SPI_CPU_MISO")
	)
	(segment
		(start 79.3242 -36.6014)
		(end 79.0321 -36.6014)
		(width 0.0889)
		(layer "In2.Cu")
		(net "SPI_CPU_MISO")
	)
	(segment
		(start 78.9432 -36.6903)
		(end 78.9432 -37.4777)
		(width 0.0889)
		(layer "In2.Cu")
		(net "SPI_CPU_MISO")
	)
	(segment
		(start 79.502 -37.5666)
		(end 79.4131 -37.4777)
		(width 0.0889)
		(layer "In2.Cu")
		(net "SPI_CPU_MISO")
	)
	(segment
		(start 78.3844 -36.6014)
		(end 78.0923 -36.6014)
		(width 0.0889)
		(layer "In2.Cu")
		(net "SPI_CPU_MISO")
	)
	(segment
		(start 79.4131 -36.6903)
		(end 79.3242 -36.6014)
		(width 0.0889)
		(layer "In2.Cu")
		(net "SPI_CPU_MISO")
	)
	(segment
		(start 78.0923 -36.6014)
		(end 78.0034 -36.6903)
		(width 0.0889)
		(layer "In2.Cu")
		(net "SPI_CPU_MISO")
	)
	(segment
		(start 81.823052 -37.5666)
		(end 80.4418 -37.5666)
		(width 0.0889)
		(layer "In2.Cu")
		(net "SPI_CPU_MISO")
	)
	(segment
		(start 82.304128 -37.711634)
		(end 81.968086 -37.711634)
		(width 0.0889)
		(layer "In2.Cu")
		(net "SPI_CPU_MISO")
	)
	(segment
		(start 77.5335 -36.6903)
		(end 77.4446 -36.6014)
		(width 0.0889)
		(layer "In2.Cu")
		(net "SPI_CPU_MISO")
	)
	(segment
		(start 83.234784 -37.111432)
		(end 82.90433 -37.111432)
		(width 0.0889)
		(layer "In2.Cu")
		(net "SPI_CPU_MISO")
	)
	(segment
		(start 76.2 -37.5666)
		(end 75.67295 -37.03955)
		(width 0.0889)
		(layer "In2.Cu")
		(net "SPI_CPU_MISO")
	)
	(segment
		(start 80.3529 -37.4777)
		(end 80.3529 -36.6903)
		(width 0.0889)
		(layer "In2.Cu")
		(net "SPI_CPU_MISO")
	)
	(segment
		(start 68.707 -37.894006)
		(end 68.707 -39.6875)
		(width 0.0889)
		(layer "In2.Cu")
		(net "SPI_CPU_MISO")
	)
	(segment
		(start 79.9719 -36.6014)
		(end 79.883 -36.6903)
		(width 0.0889)
		(layer "In2.Cu")
		(net "SPI_CPU_MISO")
	)
	(segment
		(start 82.90433 -37.111432)
		(end 82.304128 -37.711634)
		(width 0.0889)
		(layer "In2.Cu")
		(net "SPI_CPU_MISO")
	)
	(segment
		(start 77.6224 -37.5666)
		(end 77.5335 -37.4777)
		(width 0.0889)
		(layer "In2.Cu")
		(net "SPI_CPU_MISO")
	)
	(segment
		(start 76.9747 -37.5666)
		(end 76.2 -37.5666)
		(width 0.0889)
		(layer "In2.Cu")
		(net "SPI_CPU_MISO")
	)
	(segment
		(start 77.0636 -36.6903)
		(end 77.0636 -37.4777)
		(width 0.0889)
		(layer "In2.Cu")
		(net "SPI_CPU_MISO")
	)
	(segment
		(start 78.5622 -37.5666)
		(end 78.4733 -37.4777)
		(width 0.0889)
		(layer "In2.Cu")
		(net "SPI_CPU_MISO")
	)
	(segment
		(start 78.0034 -36.6903)
		(end 78.0034 -37.4777)
		(width 0.0889)
		(layer "In2.Cu")
		(net "SPI_CPU_MISO")
	)
	(segment
		(start 79.4131 -37.4777)
		(end 79.4131 -36.6903)
		(width 0.0889)
		(layer "In2.Cu")
		(net "SPI_CPU_MISO")
	)
	(segment
		(start 80.4418 -37.5666)
		(end 80.3529 -37.4777)
		(width 0.0889)
		(layer "In2.Cu")
		(net "SPI_CPU_MISO")
	)
	(segment
		(start 79.883 -37.4777)
		(end 79.7941 -37.5666)
		(width 0.0889)
		(layer "In2.Cu")
		(net "SPI_CPU_MISO")
	)
	(segment
		(start 80.264 -36.6014)
		(end 79.9719 -36.6014)
		(width 0.0889)
		(layer "In2.Cu")
		(net "SPI_CPU_MISO")
	)
	(segment
		(start 78.4733 -36.6903)
		(end 78.3844 -36.6014)
		(width 0.0889)
		(layer "In2.Cu")
		(net "SPI_CPU_MISO")
	)
	(segment
		(start 78.9432 -37.4777)
		(end 78.8543 -37.5666)
		(width 0.0889)
		(layer "In2.Cu")
		(net "SPI_CPU_MISO")
	)
	(segment
		(start 77.4446 -36.6014)
		(end 77.1525 -36.6014)
		(width 0.0889)
		(layer "In2.Cu")
		(net "SPI_CPU_MISO")
	)
	(segment
		(start 81.968086 -37.711634)
		(end 81.823052 -37.5666)
		(width 0.0889)
		(layer "In2.Cu")
		(net "SPI_CPU_MISO")
	)
	(segment
		(start 79.0321 -36.6014)
		(end 78.9432 -36.6903)
		(width 0.0889)
		(layer "In2.Cu")
		(net "SPI_CPU_MISO")
	)
	(segment
		(start 78.0034 -37.4777)
		(end 77.9145 -37.5666)
		(width 0.0889)
		(layer "In2.Cu")
		(net "SPI_CPU_MISO")
	)
	(segment
		(start 79.883 -36.6903)
		(end 79.883 -37.4777)
		(width 0.0889)
		(layer "In2.Cu")
		(net "SPI_CPU_MISO")
	)
	(segment
		(start 75.67295 -37.03955)
		(end 69.561456 -37.03955)
		(width 0.0889)
		(layer "In2.Cu")
		(net "SPI_CPU_MISO")
	)
	(segment
		(start 26.49093 -53.1368)
		(end 25.527 -53.1368)
		(width 0.2032)
		(layer "F.Cu")
		(net "VR_PVCCP_ISUMP")
	)
	(segment
		(start 22.866096 -54.1274)
		(end 22.462998 -54.530498)
		(width 0.2032)
		(layer "F.Cu")
		(net "VR_PVCCP_ISUMP")
	)
	(segment
		(start 26.8478 -50.8)
		(end 26.8478 -52.77993)
		(width 0.2032)
		(layer "F.Cu")
		(net "VR_PVCCP_ISUMP")
	)
	(segment
		(start 26.0858 -47.371)
		(end 26.5938 -47.879)
		(width 0.2032)
		(layer "F.Cu")
		(net "VR_PVCCP_ISUMP")
	)
	(segment
		(start 21.2598 -47.371)
		(end 22.352 -47.371)
		(width 0.2032)
		(layer "F.Cu")
		(net "VR_PVCCP_ISUMP")
	)
	(segment
		(start 22.462998 -54.530498)
		(end 22.462998 -55.547006)
		(width 0.2032)
		(layer "F.Cu")
		(net "VR_PVCCP_ISUMP")
	)
	(segment
		(start 22.352 -47.371)
		(end 26.0858 -47.371)
		(width 0.2032)
		(layer "F.Cu")
		(net "VR_PVCCP_ISUMP")
	)
	(segment
		(start 26.8478 -50.0634)
		(end 26.8478 -50.8)
		(width 0.2032)
		(layer "F.Cu")
		(net "VR_PVCCP_ISUMP")
	)
	(segment
		(start 26.8732 -49.276)
		(end 26.8732 -50.038)
		(width 0.2032)
		(layer "F.Cu")
		(net "VR_PVCCP_ISUMP")
	)
	(segment
		(start 26.5938 -47.879)
		(end 27.5082 -47.879)
		(width 0.2032)
		(layer "F.Cu")
		(net "VR_PVCCP_ISUMP")
	)
	(segment
		(start 24.5618 -54.102)
		(end 23.789894 -54.102)
		(width 0.2032)
		(layer "F.Cu")
		(net "VR_PVCCP_ISUMP")
	)
	(segment
		(start 23.764494 -54.1274)
		(end 22.866096 -54.1274)
		(width 0.2032)
		(layer "F.Cu")
		(net "VR_PVCCP_ISUMP")
	)
	(segment
		(start 26.8478 -52.77993)
		(end 26.49093 -53.1368)
		(width 0.2032)
		(layer "F.Cu")
		(net "VR_PVCCP_ISUMP")
	)
	(segment
		(start 25.527 -53.1368)
		(end 24.5618 -54.102)
		(width 0.2032)
		(layer "F.Cu")
		(net "VR_PVCCP_ISUMP")
	)
	(segment
		(start 27.5082 -48.641)
		(end 26.8732 -49.276)
		(width 0.2032)
		(layer "F.Cu")
		(net "VR_PVCCP_ISUMP")
	)
	(segment
		(start 27.5082 -47.879)
		(end 27.5082 -48.641)
		(width 0.2032)
		(layer "F.Cu")
		(net "VR_PVCCP_ISUMP")
	)
	(segment
		(start 26.8732 -50.038)
		(end 26.8478 -50.0634)
		(width 0.2032)
		(layer "F.Cu")
		(net "VR_PVCCP_ISUMP")
	)
	(segment
		(start 23.789894 -54.102)
		(end 23.764494 -54.1274)
		(width 0.2032)
		(layer "F.Cu")
		(net "VR_PVCCP_ISUMP")
	)
	(via
		(at 22.352 -47.371)
		(size 0.7112)
		(drill 0.3556)
		(layers "F.Cu" "B.Cu")
		(net "VR_PVCCP_ISUMP")
	)
	(segment
		(start 111.713264 -43.196002)
		(end 111.603536 -43.086274)
		(width 0.1016)
		(layer "F.Cu")
		(net "M_A_DQ30")
	)
	(segment
		(start 171.550076 -70.806564)
		(end 171.550076 -70.077076)
		(width 0.1778)
		(layer "F.Cu")
		(net "M_A_DQ30")
	)
	(segment
		(start 114.3 -45.2628)
		(end 112.233202 -43.196002)
		(width 0.1016)
		(layer "F.Cu")
		(net "M_A_DQ30")
	)
	(segment
		(start 170.8912 -69.4182)
		(end 170.8912 -69.2658)
		(width 0.1778)
		(layer "F.Cu")
		(net "M_A_DQ30")
	)
	(segment
		(start 171.550076 -70.077076)
		(end 170.8912 -69.4182)
		(width 0.1778)
		(layer "F.Cu")
		(net "M_A_DQ30")
	)
	(segment
		(start 118.5926 -45.2628)
		(end 114.3 -45.2628)
		(width 0.1016)
		(layer "F.Cu")
		(net "M_A_DQ30")
	)
	(segment
		(start 111.603536 -43.086274)
		(end 111.603028 -43.086274)
		(width 0.1016)
		(layer "F.Cu")
		(net "M_A_DQ30")
	)
	(segment
		(start 112.233202 -43.196002)
		(end 111.713264 -43.196002)
		(width 0.1016)
		(layer "F.Cu")
		(net "M_A_DQ30")
	)
	(via
		(at 118.5926 -45.2628)
		(size 0.4318)
		(drill 0.2032)
		(layers "F.Cu" "B.Cu")
		(net "M_A_DQ30")
	)
	(via
		(at 170.8912 -69.2658)
		(size 0.4318)
		(drill 0.2032)
		(layers "F.Cu" "B.Cu")
		(net "M_A_DQ30")
	)
	(segment
		(start 170.8912 -69.614034)
		(end 170.8912 -69.2658)
		(width 0.1778)
		(layer "B.Cu")
		(net "M_A_DQ30")
	)
	(segment
		(start 170.650154 -69.85508)
		(end 170.8912 -69.614034)
		(width 0.1778)
		(layer "B.Cu")
		(net "M_A_DQ30")
	)
	(segment
		(start 170.650154 -70.79996)
		(end 170.650154 -69.85508)
		(width 0.1778)
		(layer "B.Cu")
		(net "M_A_DQ30")
	)
	(segment
		(start 172.7708 -68.501006)
		(end 172.9232 -68.348606)
		(width 0.1524)
		(layer "In2.Cu")
		(net "M_A_DQ30")
	)
	(segment
		(start 154.9908 -44.2722)
		(end 154.7114 -44.2722)
		(width 0.1524)
		(layer "In2.Cu")
		(net "M_A_DQ30")
	)
	(segment
		(start 118.9736 -44.8818)
		(end 118.5926 -45.2628)
		(width 0.1016)
		(layer "In2.Cu")
		(net "M_A_DQ30")
	)
	(segment
		(start 164.034978 -48.88484)
		(end 161.225738 -46.0756)
		(width 0.1524)
		(layer "In2.Cu")
		(net "M_A_DQ30")
	)
	(segment
		(start 172.14596 -65.26784)
		(end 172.14596 -59.087004)
		(width 0.1524)
		(layer "In2.Cu")
		(net "M_A_DQ30")
	)
	(segment
		(start 161.225738 -46.0756)
		(end 155.2956 -46.0756)
		(width 0.1524)
		(layer "In2.Cu")
		(net "M_A_DQ30")
	)
	(segment
		(start 172.9232 -68.348606)
		(end 172.9232 -67.945)
		(width 0.1524)
		(layer "In2.Cu")
		(net "M_A_DQ30")
	)
	(segment
		(start 172.7708 -67.7926)
		(end 171.249086 -67.7926)
		(width 0.1524)
		(layer "In2.Cu")
		(net "M_A_DQ30")
	)
	(segment
		(start 153.3398 -44.2722)
		(end 153.054558 -44.557442)
		(width 0.1524)
		(layer "In2.Cu")
		(net "M_A_DQ30")
	)
	(segment
		(start 154.7114 -44.2722)
		(end 154.559 -44.4246)
		(width 0.1524)
		(layer "In2.Cu")
		(net "M_A_DQ30")
	)
	(segment
		(start 153.8224 -44.2722)
		(end 153.3398 -44.2722)
		(width 0.1524)
		(layer "In2.Cu")
		(net "M_A_DQ30")
	)
	(segment
		(start 154.559 -44.4246)
		(end 154.559 -45.9232)
		(width 0.1524)
		(layer "In2.Cu")
		(net "M_A_DQ30")
	)
	(segment
		(start 152.311862 -44.2722)
		(end 120.6754 -44.2722)
		(width 0.1524)
		(layer "In2.Cu")
		(net "M_A_DQ30")
	)
	(segment
		(start 171.096686 -66.317114)
		(end 172.14596 -65.26784)
		(width 0.1524)
		(layer "In2.Cu")
		(net "M_A_DQ30")
	)
	(segment
		(start 171.249086 -67.7926)
		(end 171.096686 -67.6402)
		(width 0.1524)
		(layer "In2.Cu")
		(net "M_A_DQ30")
	)
	(segment
		(start 170.9928 -68.775834)
		(end 171.267628 -68.501006)
		(width 0.1524)
		(layer "In2.Cu")
		(net "M_A_DQ30")
	)
	(segment
		(start 152.597104 -44.557442)
		(end 152.311862 -44.2722)
		(width 0.1524)
		(layer "In2.Cu")
		(net "M_A_DQ30")
	)
	(segment
		(start 172.14596 -59.087004)
		(end 164.034978 -50.976022)
		(width 0.1524)
		(layer "In2.Cu")
		(net "M_A_DQ30")
	)
	(segment
		(start 120.6754 -44.2722)
		(end 120.0658 -44.8818)
		(width 0.1016)
		(layer "In2.Cu")
		(net "M_A_DQ30")
	)
	(segment
		(start 164.034978 -50.976022)
		(end 164.034978 -48.88484)
		(width 0.1524)
		(layer "In2.Cu")
		(net "M_A_DQ30")
	)
	(segment
		(start 170.8912 -69.2658)
		(end 170.9928 -69.1642)
		(width 0.1524)
		(layer "In2.Cu")
		(net "M_A_DQ30")
	)
	(segment
		(start 171.096686 -67.6402)
		(end 171.096686 -66.317114)
		(width 0.1524)
		(layer "In2.Cu")
		(net "M_A_DQ30")
	)
	(segment
		(start 153.9748 -45.9232)
		(end 153.9748 -44.4246)
		(width 0.1524)
		(layer "In2.Cu")
		(net "M_A_DQ30")
	)
	(segment
		(start 154.559 -45.9232)
		(end 154.4066 -46.0756)
		(width 0.1524)
		(layer "In2.Cu")
		(net "M_A_DQ30")
	)
	(segment
		(start 155.2956 -46.0756)
		(end 155.1432 -45.9232)
		(width 0.1524)
		(layer "In2.Cu")
		(net "M_A_DQ30")
	)
	(segment
		(start 153.054558 -44.557442)
		(end 152.597104 -44.557442)
		(width 0.1524)
		(layer "In2.Cu")
		(net "M_A_DQ30")
	)
	(segment
		(start 154.4066 -46.0756)
		(end 154.1272 -46.0756)
		(width 0.1524)
		(layer "In2.Cu")
		(net "M_A_DQ30")
	)
	(segment
		(start 155.1432 -44.4246)
		(end 154.9908 -44.2722)
		(width 0.1524)
		(layer "In2.Cu")
		(net "M_A_DQ30")
	)
	(segment
		(start 172.9232 -67.945)
		(end 172.7708 -67.7926)
		(width 0.1524)
		(layer "In2.Cu")
		(net "M_A_DQ30")
	)
	(segment
		(start 155.1432 -45.9232)
		(end 155.1432 -44.4246)
		(width 0.1524)
		(layer "In2.Cu")
		(net "M_A_DQ30")
	)
	(segment
		(start 171.267628 -68.501006)
		(end 172.7708 -68.501006)
		(width 0.1524)
		(layer "In2.Cu")
		(net "M_A_DQ30")
	)
	(segment
		(start 170.9928 -69.1642)
		(end 170.9928 -68.775834)
		(width 0.1524)
		(layer "In2.Cu")
		(net "M_A_DQ30")
	)
	(segment
		(start 120.0658 -44.8818)
		(end 118.9736 -44.8818)
		(width 0.1016)
		(layer "In2.Cu")
		(net "M_A_DQ30")
	)
	(segment
		(start 153.9748 -44.4246)
		(end 153.8224 -44.2722)
		(width 0.1524)
		(layer "In2.Cu")
		(net "M_A_DQ30")
	)
	(segment
		(start 154.1272 -46.0756)
		(end 153.9748 -45.9232)
		(width 0.1524)
		(layer "In2.Cu")
		(net "M_A_DQ30")
	)
	(segment
		(start 95.448628 -43.200574)
		(end 95.022162 -42.774108)
		(width 0.127)
		(layer "F.Cu")
		(net "TP_CPU_RSVD2")
	)
	(segment
		(start 95.022162 -42.774108)
		(end 94.335092 -42.774108)
		(width 0.127)
		(layer "F.Cu")
		(net "TP_CPU_RSVD2")
	)
	(segment
		(start 94.335092 -42.774108)
		(end 94.2594 -42.8498)
		(width 0.127)
		(layer "F.Cu")
		(net "TP_CPU_RSVD2")
	)
	(via
		(at 94.2594 -42.8498)
		(size 0.4318)
		(drill 0.2032)
		(layers "F.Cu" "B.Cu")
		(net "TP_CPU_RSVD2")
	)
	(segment
		(start 94.2594 -42.8498)
		(end 94.2594 -42.0116)
		(width 0.127)
		(layer "B.Cu")
		(net "TP_CPU_RSVD2")
	)
	(segment
		(start 94.2594 -42.0116)
		(end 94.1578 -41.91)
		(width 0.127)
		(layer "B.Cu")
		(net "TP_CPU_RSVD2")
	)
	(segment
		(start 96.858328 -34.584386)
		(end 96.64065 -34.802064)
		(width 0.254)
		(layer "F.Cu")
		(net "P1V35")
	)
	(segment
		(start 97.390458 -43.541696)
		(end 97.458022 -43.541696)
		(width 0.254)
		(layer "F.Cu")
		(net "P1V35")
	)
	(segment
		(start 97.048828 -34.399474)
		(end 97.048828 -34.398966)
		(width 0.254)
		(layer "F.Cu")
		(net "P1V35")
	)
	(segment
		(start 96.863408 -34.584386)
		(end 96.858328 -34.584386)
		(width 0.254)
		(layer "F.Cu")
		(net "P1V35")
	)
	(segment
		(start 97.048828 -43.200574)
		(end 97.048828 -43.200066)
		(width 0.254)
		(layer "F.Cu")
		(net "P1V35")
	)
	(segment
		(start 97.048828 -34.398966)
		(end 96.863408 -34.584386)
		(width 0.254)
		(layer "F.Cu")
		(net "P1V35")
	)
	(segment
		(start 97.048828 -43.200066)
		(end 97.390458 -43.541696)
		(width 0.254)
		(layer "F.Cu")
		(net "P1V35")
	)
	(via
		(at 97.458022 -43.541696)
		(size 0.4318)
		(drill 0.2032)
		(layers "F.Cu" "B.Cu")
		(net "P1V35")
	)
	(via
		(at 95.0468 -35.596576)
		(size 0.4318)
		(drill 0.2032)
		(layers "F.Cu" "B.Cu")
		(net "P1V35")
	)
	(via
		(at 96.64065 -34.802064)
		(size 0.4318)
		(drill 0.2032)
		(layers "F.Cu" "B.Cu")
		(net "P1V35")
	)
	(via
		(at 95.0468 -34.796476)
		(size 0.4318)
		(drill 0.2032)
		(layers "F.Cu" "B.Cu")
		(net "P1V35")
	)
	(via
		(at 87.652606 -18.564606)
		(size 0.7112)
		(drill 0.4064)
		(layers "F.Cu" "B.Cu")
		(net "P1V35")
	)
	(via
		(at 95.7072 -35.179)
		(size 0.7112)
		(drill 0.3556)
		(layers "F.Cu" "B.Cu")
		(net "P1V35")
	)
	(segment
		(start 97.553526 -43.6372)
		(end 97.458022 -43.541696)
		(width 0.381)
		(layer "B.Cu")
		(net "P1V35")
	)
	(segment
		(start 88.011 -19.8882)
		(end 88.011 -18.9484)
		(width 1.016)
		(layer "B.Cu")
		(net "P1V35")
	)
	(segment
		(start 87.8078 -18.7452)
		(end 87.8078 -18.7198)
		(width 1.016)
		(layer "B.Cu")
		(net "P1V35")
	)
	(segment
		(start 88.011 -18.9484)
		(end 87.8078 -18.7452)
		(width 1.016)
		(layer "B.Cu")
		(net "P1V35")
	)
	(segment
		(start 98.171 -43.6372)
		(end 97.553526 -43.6372)
		(width 0.381)
		(layer "B.Cu")
		(net "P1V35")
	)
	(segment
		(start 87.8078 -18.7198)
		(end 87.652606 -18.564606)
		(width 1.016)
		(layer "B.Cu")
		(net "P1V35")
	)
	(segment
		(start 89.9922 -25.527)
		(end 89.9922 -20.9042)
		(width 1.016)
		(layer "In2.Cu")
		(net "P1V35")
	)
	(segment
		(start 90.904314 -26.439114)
		(end 89.9922 -25.527)
		(width 1.016)
		(layer "In2.Cu")
		(net "P1V35")
	)
	(segment
		(start 97.260918 -35.631628)
		(end 97.83953 -36.21024)
		(width 0.2794)
		(layer "In2.Cu")
		(net "P1V35")
	)
	(segment
		(start 89.9922 -20.9042)
		(end 87.652606 -18.564606)
		(width 1.016)
		(layer "In2.Cu")
		(net "P1V35")
	)
	(segment
		(start 95.8342 -35.631628)
		(end 97.260918 -35.631628)
		(width 0.2794)
		(layer "In2.Cu")
		(net "P1V35")
	)
	(segment
		(start 97.83953 -36.90493)
		(end 98.7806 -37.846)
		(width 0.2794)
		(layer "In2.Cu")
		(net "P1V35")
	)
	(segment
		(start 98.7806 -37.846)
		(end 98.7806 -42.099484)
		(width 0.2794)
		(layer "In2.Cu")
		(net "P1V35")
	)
	(segment
		(start 97.458022 -43.422062)
		(end 97.458022 -43.541696)
		(width 0.2794)
		(layer "In2.Cu")
		(net "P1V35")
	)
	(segment
		(start 97.83953 -36.21024)
		(end 97.83953 -36.90493)
		(width 0.2794)
		(layer "In2.Cu")
		(net "P1V35")
	)
	(segment
		(start 98.7806 -42.099484)
		(end 97.458022 -43.422062)
		(width 0.2794)
		(layer "In2.Cu")
		(net "P1V35")
	)
	(segment
		(start 144.850104 -62.59322)
		(end 144.850104 -63.379096)
		(width 0.1778)
		(layer "F.Cu")
		(net "M_A_DQ35")
	)
	(segment
		(start 144.351248 -63.877952)
		(end 144.351248 -64.315848)
		(width 0.1778)
		(layer "F.Cu")
		(net "M_A_DQ35")
	)
	(segment
		(start 96.80956 -47.74184)
		(end 97.264982 -47.74184)
		(width 0.1524)
		(layer "F.Cu")
		(net "M_A_DQ35")
	)
	(segment
		(start 144.351248 -64.315848)
		(end 144.355058 -64.319658)
		(width 0.1778)
		(layer "F.Cu")
		(net "M_A_DQ35")
	)
	(segment
		(start 144.355058 -64.319658)
		(end 144.355058 -64.350392)
		(width 0.1778)
		(layer "F.Cu")
		(net "M_A_DQ35")
	)
	(segment
		(start 144.850104 -63.379096)
		(end 144.351248 -63.877952)
		(width 0.1778)
		(layer "F.Cu")
		(net "M_A_DQ35")
	)
	(segment
		(start 97.264982 -47.74184)
		(end 97.366328 -47.640494)
		(width 0.1524)
		(layer "F.Cu")
		(net "M_A_DQ35")
	)
	(via
		(at 144.355058 -64.350392)
		(size 0.4318)
		(drill 0.2032)
		(layers "F.Cu" "B.Cu")
		(net "M_A_DQ35")
	)
	(via
		(at 96.80956 -47.74184)
		(size 0.4318)
		(drill 0.2032)
		(layers "F.Cu" "B.Cu")
		(net "M_A_DQ35")
	)
	(segment
		(start 144.351248 -63.909448)
		(end 144.351248 -64.315848)
		(width 0.1778)
		(layer "B.Cu")
		(net "M_A_DQ35")
	)
	(segment
		(start 144.351248 -64.315848)
		(end 144.355058 -64.319658)
		(width 0.1778)
		(layer "B.Cu")
		(net "M_A_DQ35")
	)
	(segment
		(start 143.950182 -63.508382)
		(end 144.351248 -63.909448)
		(width 0.1778)
		(layer "B.Cu")
		(net "M_A_DQ35")
	)
	(segment
		(start 143.950182 -62.599824)
		(end 143.950182 -63.508382)
		(width 0.1778)
		(layer "B.Cu")
		(net "M_A_DQ35")
	)
	(segment
		(start 144.355058 -64.319658)
		(end 144.355058 -64.350392)
		(width 0.1778)
		(layer "B.Cu")
		(net "M_A_DQ35")
	)
	(segment
		(start 143.8656 -65.3034)
		(end 143.8656 -64.963294)
		(width 0.1524)
		(layer "In4.Cu")
		(net "M_A_DQ35")
	)
	(segment
		(start 145.415 -66.2432)
		(end 145.669 -65.9892)
		(width 0.1524)
		(layer "In4.Cu")
		(net "M_A_DQ35")
	)
	(segment
		(start 145.669 -65.6082)
		(end 145.5166 -65.4558)
		(width 0.1524)
		(layer "In4.Cu")
		(net "M_A_DQ35")
	)
	(segment
		(start 103.4796 -53.467)
		(end 105.1306 -55.118)
		(width 0.1524)
		(layer "In4.Cu")
		(net "M_A_DQ35")
	)
	(segment
		(start 98.806 -52.4764)
		(end 99.0854 -52.7558)
		(width 0.1524)
		(layer "In4.Cu")
		(net "M_A_DQ35")
	)
	(segment
		(start 142.9004 -63.445898)
		(end 142.748 -63.598298)
		(width 0.1524)
		(layer "In4.Cu")
		(net "M_A_DQ35")
	)
	(segment
		(start 96.56318 -49.16678)
		(end 97.204784 -49.16678)
		(width 0.1016)
		(layer "In4.Cu")
		(net "M_A_DQ35")
	)
	(segment
		(start 141.8844 -65.8876)
		(end 142.523718 -66.526918)
		(width 0.1524)
		(layer "In4.Cu")
		(net "M_A_DQ35")
	)
	(segment
		(start 98.44786 -50.16754)
		(end 98.44786 -51.30546)
		(width 0.1016)
		(layer "In4.Cu")
		(net "M_A_DQ35")
	)
	(segment
		(start 133.158738 -58.4962)
		(end 136.525 -58.4962)
		(width 0.1524)
		(layer "In4.Cu")
		(net "M_A_DQ35")
	)
	(segment
		(start 100.9269 -52.4383)
		(end 101.6635 -52.4383)
		(width 0.1524)
		(layer "In4.Cu")
		(net "M_A_DQ35")
	)
	(segment
		(start 145.5166 -65.4558)
		(end 144.018 -65.4558)
		(width 0.1524)
		(layer "In4.Cu")
		(net "M_A_DQ35")
	)
	(segment
		(start 142.523718 -66.526918)
		(end 142.523718 -67.051682)
		(width 0.1524)
		(layer "In4.Cu")
		(net "M_A_DQ35")
	)
	(segment
		(start 143.326612 -67.183)
		(end 143.326612 -66.294)
		(width 0.1524)
		(layer "In4.Cu")
		(net "M_A_DQ35")
	)
	(segment
		(start 142.9004 -62.4078)
		(end 142.9004 -63.445898)
		(width 0.1524)
		(layer "In4.Cu")
		(net "M_A_DQ35")
	)
	(segment
		(start 102.6922 -53.467)
		(end 103.4796 -53.467)
		(width 0.1524)
		(layer "In4.Cu")
		(net "M_A_DQ35")
	)
	(segment
		(start 98.806 -51.6636)
		(end 98.806 -52.4764)
		(width 0.1524)
		(layer "In4.Cu")
		(net "M_A_DQ35")
	)
	(segment
		(start 132.523738 -57.8612)
		(end 133.158738 -58.4962)
		(width 0.1524)
		(layer "In4.Cu")
		(net "M_A_DQ35")
	)
	(segment
		(start 140.9192 -62.2554)
		(end 141.2748 -62.611)
		(width 0.1524)
		(layer "In4.Cu")
		(net "M_A_DQ35")
	)
	(segment
		(start 145.0848 -66.2432)
		(end 145.415 -66.2432)
		(width 0.1524)
		(layer "In4.Cu")
		(net "M_A_DQ35")
	)
	(segment
		(start 143.936212 -66.1416)
		(end 144.088612 -66.294)
		(width 0.1524)
		(layer "In4.Cu")
		(net "M_A_DQ35")
	)
	(segment
		(start 143.326612 -66.294)
		(end 143.479012 -66.1416)
		(width 0.1524)
		(layer "In4.Cu")
		(net "M_A_DQ35")
	)
	(segment
		(start 144.78 -67.1576)
		(end 144.78 -66.548)
		(width 0.1524)
		(layer "In4.Cu")
		(net "M_A_DQ35")
	)
	(segment
		(start 97.68332 -49.403)
		(end 98.44786 -50.16754)
		(width 0.1016)
		(layer "In4.Cu")
		(net "M_A_DQ35")
	)
	(segment
		(start 142.0368 -63.598298)
		(end 141.8844 -63.750698)
		(width 0.1524)
		(layer "In4.Cu")
		(net "M_A_DQ35")
	)
	(segment
		(start 136.8806 -58.8518)
		(end 137.7188 -58.8518)
		(width 0.1524)
		(layer "In4.Cu")
		(net "M_A_DQ35")
	)
	(segment
		(start 137.7188 -58.8518)
		(end 140.1953 -61.3283)
		(width 0.1524)
		(layer "In4.Cu")
		(net "M_A_DQ35")
	)
	(segment
		(start 99.0854 -52.7558)
		(end 100.6094 -52.7558)
		(width 0.1524)
		(layer "In4.Cu")
		(net "M_A_DQ35")
	)
	(segment
		(start 141.9606 -62.611)
		(end 142.3162 -62.2554)
		(width 0.1524)
		(layer "In4.Cu")
		(net "M_A_DQ35")
	)
	(segment
		(start 144.355058 -64.473836)
		(end 144.355058 -64.350392)
		(width 0.1524)
		(layer "In4.Cu")
		(net "M_A_DQ35")
	)
	(segment
		(start 97.441004 -49.403)
		(end 97.68332 -49.403)
		(width 0.1016)
		(layer "In4.Cu")
		(net "M_A_DQ35")
	)
	(segment
		(start 145.669 -65.9892)
		(end 145.669 -65.6082)
		(width 0.1524)
		(layer "In4.Cu")
		(net "M_A_DQ35")
	)
	(segment
		(start 142.523718 -67.051682)
		(end 142.807436 -67.3354)
		(width 0.1524)
		(layer "In4.Cu")
		(net "M_A_DQ35")
	)
	(segment
		(start 144.78 -66.548)
		(end 145.0848 -66.2432)
		(width 0.1524)
		(layer "In4.Cu")
		(net "M_A_DQ35")
	)
	(segment
		(start 96.77654 -47.77486)
		(end 96.65208 -47.77486)
		(width 0.1016)
		(layer "In4.Cu")
		(net "M_A_DQ35")
	)
	(segment
		(start 105.1306 -57.2389)
		(end 105.7529 -57.8612)
		(width 0.1524)
		(layer "In4.Cu")
		(net "M_A_DQ35")
	)
	(segment
		(start 143.174212 -67.3354)
		(end 143.326612 -67.183)
		(width 0.1524)
		(layer "In4.Cu")
		(net "M_A_DQ35")
	)
	(segment
		(start 100.6094 -52.7558)
		(end 100.9269 -52.4383)
		(width 0.1524)
		(layer "In4.Cu")
		(net "M_A_DQ35")
	)
	(segment
		(start 96.65208 -47.77486)
		(end 96.3168 -48.11014)
		(width 0.1016)
		(layer "In4.Cu")
		(net "M_A_DQ35")
	)
	(segment
		(start 142.748 -63.598298)
		(end 142.0368 -63.598298)
		(width 0.1524)
		(layer "In4.Cu")
		(net "M_A_DQ35")
	)
	(segment
		(start 144.241012 -67.31)
		(end 144.6276 -67.31)
		(width 0.1524)
		(layer "In4.Cu")
		(net "M_A_DQ35")
	)
	(segment
		(start 105.7529 -57.8612)
		(end 132.523738 -57.8612)
		(width 0.1524)
		(layer "In4.Cu")
		(net "M_A_DQ35")
	)
	(segment
		(start 101.6635 -52.4383)
		(end 102.6922 -53.467)
		(width 0.1524)
		(layer "In4.Cu")
		(net "M_A_DQ35")
	)
	(segment
		(start 97.204784 -49.16678)
		(end 97.441004 -49.403)
		(width 0.1016)
		(layer "In4.Cu")
		(net "M_A_DQ35")
	)
	(segment
		(start 141.2748 -62.611)
		(end 141.9606 -62.611)
		(width 0.1524)
		(layer "In4.Cu")
		(net "M_A_DQ35")
	)
	(segment
		(start 144.6276 -67.31)
		(end 144.78 -67.1576)
		(width 0.1524)
		(layer "In4.Cu")
		(net "M_A_DQ35")
	)
	(segment
		(start 96.80956 -47.74184)
		(end 96.77654 -47.77486)
		(width 0.1016)
		(layer "In4.Cu")
		(net "M_A_DQ35")
	)
	(segment
		(start 105.1306 -55.118)
		(end 105.1306 -57.2389)
		(width 0.1524)
		(layer "In4.Cu")
		(net "M_A_DQ35")
	)
	(segment
		(start 96.3168 -48.9204)
		(end 96.56318 -49.16678)
		(width 0.1016)
		(layer "In4.Cu")
		(net "M_A_DQ35")
	)
	(segment
		(start 98.44786 -51.30546)
		(end 98.806 -51.6636)
		(width 0.1524)
		(layer "In4.Cu")
		(net "M_A_DQ35")
	)
	(segment
		(start 142.3162 -62.2554)
		(end 142.748 -62.2554)
		(width 0.1524)
		(layer "In4.Cu")
		(net "M_A_DQ35")
	)
	(segment
		(start 140.1953 -61.3283)
		(end 140.1953 -61.9633)
		(width 0.1524)
		(layer "In4.Cu")
		(net "M_A_DQ35")
	)
	(segment
		(start 144.088612 -67.1576)
		(end 144.241012 -67.31)
		(width 0.1524)
		(layer "In4.Cu")
		(net "M_A_DQ35")
	)
	(segment
		(start 140.1953 -61.9633)
		(end 140.4874 -62.2554)
		(width 0.1524)
		(layer "In4.Cu")
		(net "M_A_DQ35")
	)
	(segment
		(start 143.479012 -66.1416)
		(end 143.936212 -66.1416)
		(width 0.1524)
		(layer "In4.Cu")
		(net "M_A_DQ35")
	)
	(segment
		(start 143.8656 -64.963294)
		(end 144.355058 -64.473836)
		(width 0.1524)
		(layer "In4.Cu")
		(net "M_A_DQ35")
	)
	(segment
		(start 142.748 -62.2554)
		(end 142.9004 -62.4078)
		(width 0.1524)
		(layer "In4.Cu")
		(net "M_A_DQ35")
	)
	(segment
		(start 142.807436 -67.3354)
		(end 143.174212 -67.3354)
		(width 0.1524)
		(layer "In4.Cu")
		(net "M_A_DQ35")
	)
	(segment
		(start 96.3168 -48.11014)
		(end 96.3168 -48.9204)
		(width 0.1016)
		(layer "In4.Cu")
		(net "M_A_DQ35")
	)
	(segment
		(start 144.018 -65.4558)
		(end 143.8656 -65.3034)
		(width 0.1524)
		(layer "In4.Cu")
		(net "M_A_DQ35")
	)
	(segment
		(start 141.8844 -63.750698)
		(end 141.8844 -65.8876)
		(width 0.1524)
		(layer "In4.Cu")
		(net "M_A_DQ35")
	)
	(segment
		(start 144.088612 -66.294)
		(end 144.088612 -67.1576)
		(width 0.1524)
		(layer "In4.Cu")
		(net "M_A_DQ35")
	)
	(segment
		(start 136.525 -58.4962)
		(end 136.8806 -58.8518)
		(width 0.1524)
		(layer "In4.Cu")
		(net "M_A_DQ35")
	)
	(segment
		(start 140.4874 -62.2554)
		(end 140.9192 -62.2554)
		(width 0.1524)
		(layer "In4.Cu")
		(net "M_A_DQ35")
	)
	(segment
		(start 64.01435 -39.5732)
		(end 63.67145 -39.5732)
		(width 0.1143)
		(layer "F.Cu")
		(net "SPI_CPU_MOSI")
	)
	(segment
		(start 65.1256 -40.4876)
		(end 65.1256 -40.0812)
		(width 0.1143)
		(layer "F.Cu")
		(net "SPI_CPU_MOSI")
	)
	(segment
		(start 81.646268 -36.505134)
		(end 82.1182 -36.977066)
		(width 0.1143)
		(layer "F.Cu")
		(net "SPI_CPU_MOSI")
	)
	(segment
		(start 54.244748 -39.28745)
		(end 58.24855 -39.28745)
		(width 0.1143)
		(layer "F.Cu")
		(net "SPI_CPU_MOSI")
	)
	(segment
		(start 67.933824 -40.679624)
		(end 67.792092 -40.679624)
		(width 0.1143)
		(layer "F.Cu")
		(net "SPI_CPU_MOSI")
	)
	(segment
		(start 63.09995 -38.976808)
		(end 62.98565 -39.091108)
		(width 0.1143)
		(layer "F.Cu")
		(net "SPI_CPU_MOSI")
	)
	(segment
		(start 64.5922 -38.976808)
		(end 64.217042 -38.976808)
		(width 0.1143)
		(layer "F.Cu")
		(net "SPI_CPU_MOSI")
	)
	(segment
		(start 50.865532 -38.292532)
		(end 50.865532 -38.292786)
		(width 0.1143)
		(layer "F.Cu")
		(net "SPI_CPU_MOSI")
	)
	(segment
		(start 67.778122 -40.665654)
		(end 65.303654 -40.665654)
		(width 0.1143)
		(layer "F.Cu")
		(net "SPI_CPU_MOSI")
	)
	(segment
		(start 62.29985 -38.976808)
		(end 58.559192 -38.976808)
		(width 0.1143)
		(layer "F.Cu")
		(net "SPI_CPU_MOSI")
	)
	(segment
		(start 62.41415 -39.4589)
		(end 62.41415 -39.091108)
		(width 0.1143)
		(layer "F.Cu")
		(net "SPI_CPU_MOSI")
	)
	(segment
		(start 64.6938 -39.3446)
		(end 64.6938 -39.078408)
		(width 0.1143)
		(layer "F.Cu")
		(net "SPI_CPU_MOSI")
	)
	(segment
		(start 53.954934 -38.997636)
		(end 54.244748 -39.28745)
		(width 0.1143)
		(layer "F.Cu")
		(net "SPI_CPU_MOSI")
	)
	(segment
		(start 48.5902 -35.3568)
		(end 48.5902 -36.0172)
		(width 0.1143)
		(layer "F.Cu")
		(net "SPI_CPU_MOSI")
	)
	(segment
		(start 65.303654 -40.665654)
		(end 65.1256 -40.4876)
		(width 0.1143)
		(layer "F.Cu")
		(net "SPI_CPU_MOSI")
	)
	(segment
		(start 64.12865 -39.0652)
		(end 64.12865 -39.4589)
		(width 0.1143)
		(layer "F.Cu")
		(net "SPI_CPU_MOSI")
	)
	(segment
		(start 53.540152 -38.5826)
		(end 53.954934 -38.997382)
		(width 0.1143)
		(layer "F.Cu")
		(net "SPI_CPU_MOSI")
	)
	(segment
		(start 58.24855 -39.28745)
		(end 58.377328 -39.158672)
		(width 0.1143)
		(layer "F.Cu")
		(net "SPI_CPU_MOSI")
	)
	(segment
		(start 58.559192 -38.976808)
		(end 58.377328 -39.158672)
		(width 0.1143)
		(layer "F.Cu")
		(net "SPI_CPU_MOSI")
	)
	(segment
		(start 63.67145 -39.5732)
		(end 63.55715 -39.4589)
		(width 0.1143)
		(layer "F.Cu")
		(net "SPI_CPU_MOSI")
	)
	(segment
		(start 50.865532 -38.292786)
		(end 51.155346 -38.5826)
		(width 0.1143)
		(layer "F.Cu")
		(net "SPI_CPU_MOSI")
	)
	(segment
		(start 62.87135 -39.5732)
		(end 62.52845 -39.5732)
		(width 0.1143)
		(layer "F.Cu")
		(net "SPI_CPU_MOSI")
	)
	(segment
		(start 64.217042 -38.976808)
		(end 64.12865 -39.0652)
		(width 0.1143)
		(layer "F.Cu")
		(net "SPI_CPU_MOSI")
	)
	(segment
		(start 65.3288 -39.878)
		(end 65.3288 -39.689532)
		(width 0.1143)
		(layer "F.Cu")
		(net "SPI_CPU_MOSI")
	)
	(segment
		(start 62.52845 -39.5732)
		(end 62.41415 -39.4589)
		(width 0.1143)
		(layer "F.Cu")
		(net "SPI_CPU_MOSI")
	)
	(segment
		(start 62.98565 -39.091108)
		(end 62.98565 -39.4589)
		(width 0.1143)
		(layer "F.Cu")
		(net "SPI_CPU_MOSI")
	)
	(segment
		(start 48.5902 -36.0172)
		(end 50.865532 -38.292532)
		(width 0.1143)
		(layer "F.Cu")
		(net "SPI_CPU_MOSI")
	)
	(segment
		(start 64.8208 -39.4716)
		(end 64.6938 -39.3446)
		(width 0.1143)
		(layer "F.Cu")
		(net "SPI_CPU_MOSI")
	)
	(segment
		(start 63.55715 -39.4589)
		(end 63.55715 -39.091108)
		(width 0.1143)
		(layer "F.Cu")
		(net "SPI_CPU_MOSI")
	)
	(segment
		(start 63.55715 -39.091108)
		(end 63.44285 -38.976808)
		(width 0.1143)
		(layer "F.Cu")
		(net "SPI_CPU_MOSI")
	)
	(segment
		(start 65.110868 -39.4716)
		(end 64.8208 -39.4716)
		(width 0.1143)
		(layer "F.Cu")
		(net "SPI_CPU_MOSI")
	)
	(segment
		(start 62.41415 -39.091108)
		(end 62.29985 -38.976808)
		(width 0.1143)
		(layer "F.Cu")
		(net "SPI_CPU_MOSI")
	)
	(segment
		(start 64.12865 -39.4589)
		(end 64.01435 -39.5732)
		(width 0.1143)
		(layer "F.Cu")
		(net "SPI_CPU_MOSI")
	)
	(segment
		(start 62.98565 -39.4589)
		(end 62.87135 -39.5732)
		(width 0.1143)
		(layer "F.Cu")
		(net "SPI_CPU_MOSI")
	)
	(segment
		(start 64.6938 -39.078408)
		(end 64.5922 -38.976808)
		(width 0.1143)
		(layer "F.Cu")
		(net "SPI_CPU_MOSI")
	)
	(segment
		(start 82.1182 -36.977066)
		(end 82.1182 -37.349684)
		(width 0.1143)
		(layer "F.Cu")
		(net "SPI_CPU_MOSI")
	)
	(segment
		(start 65.3288 -39.689532)
		(end 65.110868 -39.4716)
		(width 0.1143)
		(layer "F.Cu")
		(net "SPI_CPU_MOSI")
	)
	(segment
		(start 65.1256 -40.0812)
		(end 65.3288 -39.878)
		(width 0.1143)
		(layer "F.Cu")
		(net "SPI_CPU_MOSI")
	)
	(segment
		(start 67.792092 -40.679624)
		(end 67.778122 -40.665654)
		(width 0.1143)
		(layer "F.Cu")
		(net "SPI_CPU_MOSI")
	)
	(segment
		(start 53.954934 -38.997382)
		(end 53.954934 -38.997636)
		(width 0.1143)
		(layer "F.Cu")
		(net "SPI_CPU_MOSI")
	)
	(segment
		(start 51.155346 -38.5826)
		(end 53.540152 -38.5826)
		(width 0.1143)
		(layer "F.Cu")
		(net "SPI_CPU_MOSI")
	)
	(segment
		(start 63.44285 -38.976808)
		(end 63.09995 -38.976808)
		(width 0.1143)
		(layer "F.Cu")
		(net "SPI_CPU_MOSI")
	)
	(via
		(at 82.1182 -37.349684)
		(size 0.4318)
		(drill 0.2032)
		(layers "F.Cu" "B.Cu")
		(net "SPI_CPU_MOSI")
	)
	(via
		(at 58.377328 -39.158672)
		(size 0.7112)
		(drill 0.3556)
		(layers "F.Cu" "B.Cu")
		(net "SPI_CPU_MOSI")
	)
	(via
		(at 67.933824 -40.679624)
		(size 0.508)
		(drill 0.254)
		(layers "F.Cu" "B.Cu")
		(net "SPI_CPU_MOSI")
	)
	(segment
		(start 79.0702 -33.3502)
		(end 79.0702 -34.301684)
		(width 0.0889)
		(layer "In2.Cu")
		(net "SPI_CPU_MOSI")
	)
	(segment
		(start 73.533 -34.6964)
		(end 73.533 -33.4264)
		(width 0.0889)
		(layer "In2.Cu")
		(net "SPI_CPU_MOSI")
	)
	(segment
		(start 73.6346 -33.3248)
		(end 77.311504 -33.3248)
		(width 0.0889)
		(layer "In2.Cu")
		(net "SPI_CPU_MOSI")
	)
	(segment
		(start 73.10755 -35.12185)
		(end 73.533 -34.6964)
		(width 0.0889)
		(layer "In2.Cu")
		(net "SPI_CPU_MOSI")
	)
	(segment
		(start 66.944748 -36.585652)
		(end 68.40855 -35.12185)
		(width 0.0889)
		(layer "In2.Cu")
		(net "SPI_CPU_MOSI")
	)
	(segment
		(start 67.933824 -40.679624)
		(end 67.933824 -40.429942)
		(width 0.0889)
		(layer "In2.Cu")
		(net "SPI_CPU_MOSI")
	)
	(segment
		(start 66.944748 -39.440866)
		(end 66.944748 -36.585652)
		(width 0.0889)
		(layer "In2.Cu")
		(net "SPI_CPU_MOSI")
	)
	(segment
		(start 78.4098 -32.6898)
		(end 79.0702 -33.3502)
		(width 0.0889)
		(layer "In2.Cu")
		(net "SPI_CPU_MOSI")
	)
	(segment
		(start 67.933824 -40.429942)
		(end 66.944748 -39.440866)
		(width 0.0889)
		(layer "In2.Cu")
		(net "SPI_CPU_MOSI")
	)
	(segment
		(start 77.946504 -32.6898)
		(end 78.4098 -32.6898)
		(width 0.0889)
		(layer "In2.Cu")
		(net "SPI_CPU_MOSI")
	)
	(segment
		(start 73.533 -33.4264)
		(end 73.6346 -33.3248)
		(width 0.0889)
		(layer "In2.Cu")
		(net "SPI_CPU_MOSI")
	)
	(segment
		(start 68.40855 -35.12185)
		(end 73.10755 -35.12185)
		(width 0.0889)
		(layer "In2.Cu")
		(net "SPI_CPU_MOSI")
	)
	(segment
		(start 79.0702 -34.301684)
		(end 82.1182 -37.349684)
		(width 0.0889)
		(layer "In2.Cu")
		(net "SPI_CPU_MOSI")
	)
	(segment
		(start 77.311504 -33.3248)
		(end 77.946504 -32.6898)
		(width 0.0889)
		(layer "In2.Cu")
		(net "SPI_CPU_MOSI")
	)
	(via
		(at 78.81874 -17.272)
		(size 0.7112)
		(drill 0.3556)
		(layers "F.Cu" "B.Cu")
		(net "TPS74801_P1V35_IN")
	)
	(segment
		(start 100.5078 -55.118)
		(end 100.0506 -54.6608)
		(width 0.1016)
		(layer "F.Cu")
		(net "M_A_DQ48")
	)
	(segment
		(start 99.8982 -53.3146)
		(end 99.8982 -51.905662)
		(width 0.1016)
		(layer "F.Cu")
		(net "M_A_DQ48")
	)
	(segment
		(start 99.8982 -51.905662)
		(end 100.300028 -51.503834)
		(width 0.1016)
		(layer "F.Cu")
		(net "M_A_DQ48")
	)
	(segment
		(start 100.0506 -54.6608)
		(end 100.0506 -53.467)
		(width 0.1016)
		(layer "F.Cu")
		(net "M_A_DQ48")
	)
	(segment
		(start 138.3792 -64.686688)
		(end 138.3792 -64.7954)
		(width 0.1778)
		(layer "F.Cu")
		(net "M_A_DQ48")
	)
	(segment
		(start 138.1252 -64.432688)
		(end 138.3792 -64.686688)
		(width 0.1778)
		(layer "F.Cu")
		(net "M_A_DQ48")
	)
	(segment
		(start 138.250168 -63.679832)
		(end 138.1252 -63.8048)
		(width 0.1778)
		(layer "F.Cu")
		(net "M_A_DQ48")
	)
	(segment
		(start 138.1252 -63.8048)
		(end 138.1252 -64.432688)
		(width 0.1778)
		(layer "F.Cu")
		(net "M_A_DQ48")
	)
	(segment
		(start 100.0506 -53.467)
		(end 99.8982 -53.3146)
		(width 0.1016)
		(layer "F.Cu")
		(net "M_A_DQ48")
	)
	(segment
		(start 138.250168 -62.59322)
		(end 138.250168 -63.679832)
		(width 0.1778)
		(layer "F.Cu")
		(net "M_A_DQ48")
	)
	(via
		(at 138.3792 -64.7954)
		(size 0.4318)
		(drill 0.2032)
		(layers "F.Cu" "B.Cu")
		(net "M_A_DQ48")
	)
	(via
		(at 100.5078 -55.118)
		(size 0.4318)
		(drill 0.2032)
		(layers "F.Cu" "B.Cu")
		(net "M_A_DQ48")
	)
	(segment
		(start 138.550142 -62.599824)
		(end 138.550142 -63.379858)
		(width 0.1778)
		(layer "B.Cu")
		(net "M_A_DQ48")
	)
	(segment
		(start 138.1252 -64.5414)
		(end 138.3792 -64.7954)
		(width 0.1778)
		(layer "B.Cu")
		(net "M_A_DQ48")
	)
	(segment
		(start 138.1252 -63.8048)
		(end 138.1252 -64.5414)
		(width 0.1778)
		(layer "B.Cu")
		(net "M_A_DQ48")
	)
	(segment
		(start 138.550142 -63.379858)
		(end 138.1252 -63.8048)
		(width 0.1778)
		(layer "B.Cu")
		(net "M_A_DQ48")
	)
	(segment
		(start 116.078 -61.2648)
		(end 116.078 -62.6872)
		(width 0.1524)
		(layer "In4.Cu")
		(net "M_A_DQ48")
	)
	(segment
		(start 138.3792 -64.686688)
		(end 138.1379 -64.445388)
		(width 0.1524)
		(layer "In4.Cu")
		(net "M_A_DQ48")
	)
	(segment
		(start 105.068624 -63.006224)
		(end 105.068624 -61.754258)
		(width 0.1524)
		(layer "In4.Cu")
		(net "M_A_DQ48")
	)
	(segment
		(start 116.078 -62.6872)
		(end 115.9256 -62.8396)
		(width 0.1524)
		(layer "In4.Cu")
		(net "M_A_DQ48")
	)
	(segment
		(start 138.1379 -63.774066)
		(end 135.476234 -61.1124)
		(width 0.1524)
		(layer "In4.Cu")
		(net "M_A_DQ48")
	)
	(segment
		(start 112.268 -64.5668)
		(end 112.1156 -64.7192)
		(width 0.1524)
		(layer "In4.Cu")
		(net "M_A_DQ48")
	)
	(segment
		(start 112.268 -64.1604)
		(end 112.268 -64.5668)
		(width 0.1524)
		(layer "In4.Cu")
		(net "M_A_DQ48")
	)
	(segment
		(start 101.0158 -55.6514)
		(end 100.5078 -55.1434)
		(width 0.1524)
		(layer "In4.Cu")
		(net "M_A_DQ48")
	)
	(segment
		(start 105.4862 -63.4238)
		(end 105.068624 -63.006224)
		(width 0.1524)
		(layer "In4.Cu")
		(net "M_A_DQ48")
	)
	(segment
		(start 102.877366 -59.563)
		(end 102.235 -59.563)
		(width 0.1524)
		(layer "In4.Cu")
		(net "M_A_DQ48")
	)
	(segment
		(start 116.2304 -61.1124)
		(end 116.078 -61.2648)
		(width 0.1524)
		(layer "In4.Cu")
		(net "M_A_DQ48")
	)
	(segment
		(start 138.3792 -64.7954)
		(end 138.3792 -64.686688)
		(width 0.1524)
		(layer "In4.Cu")
		(net "M_A_DQ48")
	)
	(segment
		(start 110.2614 -63.8556)
		(end 110.4138 -64.008)
		(width 0.1524)
		(layer "In4.Cu")
		(net "M_A_DQ48")
	)
	(segment
		(start 108.499148 -63.4238)
		(end 105.4862 -63.4238)
		(width 0.1524)
		(layer "In4.Cu")
		(net "M_A_DQ48")
	)
	(segment
		(start 110.2614 -63.4492)
		(end 110.2614 -63.8556)
		(width 0.1524)
		(layer "In4.Cu")
		(net "M_A_DQ48")
	)
	(segment
		(start 112.1156 -64.008)
		(end 112.268 -64.1604)
		(width 0.1524)
		(layer "In4.Cu")
		(net "M_A_DQ48")
	)
	(segment
		(start 110.4138 -63.2968)
		(end 110.2614 -63.4492)
		(width 0.1524)
		(layer "In4.Cu")
		(net "M_A_DQ48")
	)
	(segment
		(start 105.068624 -61.754258)
		(end 102.877366 -59.563)
		(width 0.1524)
		(layer "In4.Cu")
		(net "M_A_DQ48")
	)
	(segment
		(start 112.1156 -64.7192)
		(end 109.794548 -64.7192)
		(width 0.1524)
		(layer "In4.Cu")
		(net "M_A_DQ48")
	)
	(segment
		(start 114.870738 -63.2968)
		(end 110.4138 -63.2968)
		(width 0.1524)
		(layer "In4.Cu")
		(net "M_A_DQ48")
	)
	(segment
		(start 115.327938 -62.8396)
		(end 114.870738 -63.2968)
		(width 0.1524)
		(layer "In4.Cu")
		(net "M_A_DQ48")
	)
	(segment
		(start 100.5078 -55.1434)
		(end 100.5078 -55.118)
		(width 0.1524)
		(layer "In4.Cu")
		(net "M_A_DQ48")
	)
	(segment
		(start 135.476234 -61.1124)
		(end 116.2304 -61.1124)
		(width 0.1524)
		(layer "In4.Cu")
		(net "M_A_DQ48")
	)
	(segment
		(start 109.794548 -64.7192)
		(end 108.499148 -63.4238)
		(width 0.1524)
		(layer "In4.Cu")
		(net "M_A_DQ48")
	)
	(segment
		(start 102.235 -59.563)
		(end 101.0158 -58.3438)
		(width 0.1524)
		(layer "In4.Cu")
		(net "M_A_DQ48")
	)
	(segment
		(start 115.9256 -62.8396)
		(end 115.327938 -62.8396)
		(width 0.1524)
		(layer "In4.Cu")
		(net "M_A_DQ48")
	)
	(segment
		(start 101.0158 -58.3438)
		(end 101.0158 -55.6514)
		(width 0.1524)
		(layer "In4.Cu")
		(net "M_A_DQ48")
	)
	(segment
		(start 110.4138 -64.008)
		(end 112.1156 -64.008)
		(width 0.1524)
		(layer "In4.Cu")
		(net "M_A_DQ48")
	)
	(segment
		(start 138.1379 -64.445388)
		(end 138.1379 -63.774066)
		(width 0.1524)
		(layer "In4.Cu")
		(net "M_A_DQ48")
	)
	(via
		(at 80.518 -21.5646)
		(size 0.7112)
		(drill 0.3556)
		(layers "F.Cu" "B.Cu")
		(net "TPS74801_1V35_EN")
	)
	(segment
		(start 80.966056 -20.545044)
		(end 80.966056 -21.116544)
		(width 0.254)
		(layer "B.Cu")
		(net "TPS74801_1V35_EN")
	)
	(segment
		(start 80.966056 -21.116544)
		(end 80.518 -21.5646)
		(width 0.254)
		(layer "B.Cu")
		(net "TPS74801_1V35_EN")
	)
	(segment
		(start 79.248 -23.2156)
		(end 80.01 -23.2156)
		(width 0.254)
		(layer "B.Cu")
		(net "TPS74801_1V35_EN")
	)
	(segment
		(start 80.0608 -22.0218)
		(end 80.0608 -22.4282)
		(width 0.254)
		(layer "B.Cu")
		(net "TPS74801_1V35_EN")
	)
	(segment
		(start 80.01 -23.2156)
		(end 80.0608 -23.1648)
		(width 0.254)
		(layer "B.Cu")
		(net "TPS74801_1V35_EN")
	)
	(segment
		(start 80.0608 -23.1648)
		(end 80.0608 -22.4282)
		(width 0.254)
		(layer "B.Cu")
		(net "TPS74801_1V35_EN")
	)
	(segment
		(start 80.518 -21.5646)
		(end 80.0608 -22.0218)
		(width 0.254)
		(layer "B.Cu")
		(net "TPS74801_1V35_EN")
	)
	(segment
		(start 140.349986 -69.446394)
		(end 140.191998 -69.288406)
		(width 0.1778)
		(layer "F.Cu")
		(net "M_A_DQ46")
	)
	(segment
		(start 140.349986 -70.806564)
		(end 140.349986 -69.446394)
		(width 0.1778)
		(layer "F.Cu")
		(net "M_A_DQ46")
	)
	(segment
		(start 103.6574 -56.007)
		(end 103.6574 -54.0004)
		(width 0.1016)
		(layer "F.Cu")
		(net "M_A_DQ46")
	)
	(segment
		(start 103.312468 -53.655468)
		(end 103.312468 -52.448714)
		(width 0.1016)
		(layer "F.Cu")
		(net "M_A_DQ46")
	)
	(segment
		(start 103.6574 -54.0004)
		(end 103.312468 -53.655468)
		(width 0.1016)
		(layer "F.Cu")
		(net "M_A_DQ46")
	)
	(via
		(at 140.191998 -69.288406)
		(size 0.4318)
		(drill 0.2032)
		(layers "F.Cu" "B.Cu")
		(net "M_A_DQ46")
	)
	(via
		(at 103.6574 -56.007)
		(size 0.4318)
		(drill 0.2032)
		(layers "F.Cu" "B.Cu")
		(net "M_A_DQ46")
	)
	(segment
		(start 140.191998 -69.339206)
		(end 140.191998 -69.288406)
		(width 0.1778)
		(layer "B.Cu")
		(net "M_A_DQ46")
	)
	(segment
		(start 140.050012 -70.79996)
		(end 140.050012 -69.481192)
		(width 0.1778)
		(layer "B.Cu")
		(net "M_A_DQ46")
	)
	(segment
		(start 140.050012 -69.481192)
		(end 140.191998 -69.339206)
		(width 0.1778)
		(layer "B.Cu")
		(net "M_A_DQ46")
	)
	(segment
		(start 122.918982 -60.958984)
		(end 126.922784 -60.958984)
		(width 0.1524)
		(layer "In2.Cu")
		(net "M_A_DQ46")
	)
	(segment
		(start 126.922784 -60.958984)
		(end 127.531622 -61.567822)
		(width 0.1524)
		(layer "In2.Cu")
		(net "M_A_DQ46")
	)
	(segment
		(start 129.208022 -62.6618)
		(end 129.360422 -62.5094)
		(width 0.1524)
		(layer "In2.Cu")
		(net "M_A_DQ46")
	)
	(segment
		(start 105.451402 -59.299602)
		(end 121.2596 -59.299602)
		(width 0.1524)
		(layer "In2.Cu")
		(net "M_A_DQ46")
	)
	(segment
		(start 129.817622 -61.4299)
		(end 129.970022 -61.5823)
		(width 0.1524)
		(layer "In2.Cu")
		(net "M_A_DQ46")
	)
	(segment
		(start 128.903222 -62.6618)
		(end 129.208022 -62.6618)
		(width 0.1524)
		(layer "In2.Cu")
		(net "M_A_DQ46")
	)
	(segment
		(start 129.360422 -61.5823)
		(end 129.512822 -61.4299)
		(width 0.1524)
		(layer "In2.Cu")
		(net "M_A_DQ46")
	)
	(segment
		(start 130.427222 -62.6618)
		(end 130.579622 -62.5094)
		(width 0.1524)
		(layer "In2.Cu")
		(net "M_A_DQ46")
	)
	(segment
		(start 128.293622 -61.4299)
		(end 128.598422 -61.4299)
		(width 0.1524)
		(layer "In2.Cu")
		(net "M_A_DQ46")
	)
	(segment
		(start 121.2596 -59.299602)
		(end 122.918982 -60.958984)
		(width 0.1524)
		(layer "In2.Cu")
		(net "M_A_DQ46")
	)
	(segment
		(start 140.191998 -66.462402)
		(end 140.191998 -69.288406)
		(width 0.1524)
		(layer "In2.Cu")
		(net "M_A_DQ46")
	)
	(segment
		(start 130.579622 -62.5094)
		(end 130.579622 -61.5823)
		(width 0.1524)
		(layer "In2.Cu")
		(net "M_A_DQ46")
	)
	(segment
		(start 128.598422 -61.4299)
		(end 128.750822 -61.5823)
		(width 0.1524)
		(layer "In2.Cu")
		(net "M_A_DQ46")
	)
	(segment
		(start 130.579622 -61.5823)
		(end 130.732022 -61.4299)
		(width 0.1524)
		(layer "In2.Cu")
		(net "M_A_DQ46")
	)
	(segment
		(start 127.684022 -62.6618)
		(end 127.988822 -62.6618)
		(width 0.1524)
		(layer "In2.Cu")
		(net "M_A_DQ46")
	)
	(segment
		(start 141.351 -65.3034)
		(end 140.191998 -66.462402)
		(width 0.1524)
		(layer "In2.Cu")
		(net "M_A_DQ46")
	)
	(segment
		(start 129.360422 -62.5094)
		(end 129.360422 -61.5823)
		(width 0.1524)
		(layer "In2.Cu")
		(net "M_A_DQ46")
	)
	(segment
		(start 130.122422 -62.6618)
		(end 130.427222 -62.6618)
		(width 0.1524)
		(layer "In2.Cu")
		(net "M_A_DQ46")
	)
	(segment
		(start 129.970022 -61.5823)
		(end 129.970022 -62.5094)
		(width 0.1524)
		(layer "In2.Cu")
		(net "M_A_DQ46")
	)
	(segment
		(start 139.7889 -61.4299)
		(end 141.351 -62.992)
		(width 0.1524)
		(layer "In2.Cu")
		(net "M_A_DQ46")
	)
	(segment
		(start 129.970022 -62.5094)
		(end 130.122422 -62.6618)
		(width 0.1524)
		(layer "In2.Cu")
		(net "M_A_DQ46")
	)
	(segment
		(start 104.1908 -56.5404)
		(end 104.1908 -58.039)
		(width 0.1524)
		(layer "In2.Cu")
		(net "M_A_DQ46")
	)
	(segment
		(start 129.512822 -61.4299)
		(end 129.817622 -61.4299)
		(width 0.1524)
		(layer "In2.Cu")
		(net "M_A_DQ46")
	)
	(segment
		(start 128.141222 -61.5823)
		(end 128.293622 -61.4299)
		(width 0.1524)
		(layer "In2.Cu")
		(net "M_A_DQ46")
	)
	(segment
		(start 127.531622 -61.567822)
		(end 127.531622 -62.5094)
		(width 0.1524)
		(layer "In2.Cu")
		(net "M_A_DQ46")
	)
	(segment
		(start 130.732022 -61.4299)
		(end 139.7889 -61.4299)
		(width 0.1524)
		(layer "In2.Cu")
		(net "M_A_DQ46")
	)
	(segment
		(start 128.141222 -62.5094)
		(end 128.141222 -61.5823)
		(width 0.1524)
		(layer "In2.Cu")
		(net "M_A_DQ46")
	)
	(segment
		(start 127.531622 -62.5094)
		(end 127.684022 -62.6618)
		(width 0.1524)
		(layer "In2.Cu")
		(net "M_A_DQ46")
	)
	(segment
		(start 128.750822 -61.5823)
		(end 128.750822 -62.5094)
		(width 0.1524)
		(layer "In2.Cu")
		(net "M_A_DQ46")
	)
	(segment
		(start 103.6574 -56.007)
		(end 104.1908 -56.5404)
		(width 0.1524)
		(layer "In2.Cu")
		(net "M_A_DQ46")
	)
	(segment
		(start 104.1908 -58.039)
		(end 105.451402 -59.299602)
		(width 0.1524)
		(layer "In2.Cu")
		(net "M_A_DQ46")
	)
	(segment
		(start 128.750822 -62.5094)
		(end 128.903222 -62.6618)
		(width 0.1524)
		(layer "In2.Cu")
		(net "M_A_DQ46")
	)
	(segment
		(start 141.351 -62.992)
		(end 141.351 -65.3034)
		(width 0.1524)
		(layer "In2.Cu")
		(net "M_A_DQ46")
	)
	(segment
		(start 127.988822 -62.6618)
		(end 128.141222 -62.5094)
		(width 0.1524)
		(layer "In2.Cu")
		(net "M_A_DQ46")
	)
	(via
		(at 86.4108 -18.1356)
		(size 0.7112)
		(drill 0.3556)
		(layers "F.Cu" "B.Cu")
		(net "TPS74801_1V35_OUT")
	)
	(via
		(at 86.268052 -17.053052)
		(size 0.7112)
		(drill 0.4064)
		(layers "F.Cu" "B.Cu")
		(net "TPS74801_1V35_OUT")
	)
	(segment
		(start 86.5378 -19.9644)
		(end 86.5632 -19.939)
		(width 0.3048)
		(layer "B.Cu")
		(net "TPS74801_1V35_OUT")
	)
	(segment
		(start 86.5378 -20.701)
		(end 86.5378 -19.9644)
		(width 0.3048)
		(layer "B.Cu")
		(net "TPS74801_1V35_OUT")
	)
	(segment
		(start 86.4108 -18.1356)
		(end 86.5632 -18.288)
		(width 0.3048)
		(layer "B.Cu")
		(net "TPS74801_1V35_OUT")
	)
	(segment
		(start 86.5632 -18.288)
		(end 86.5632 -19.939)
		(width 0.3048)
		(layer "B.Cu")
		(net "TPS74801_1V35_OUT")
	)
	(segment
		(start 98.030538 -57.417462)
		(end 98.425 -57.023)
		(width 0.1016)
		(layer "F.Cu")
		(net "M_A_DQ51")
	)
	(segment
		(start 135.250174 -63.276226)
		(end 134.62 -63.9064)
		(width 0.1778)
		(layer "F.Cu")
		(net "M_A_DQ51")
	)
	(segment
		(start 98.425 -52.789328)
		(end 98.328988 -52.693316)
		(width 0.1016)
		(layer "F.Cu")
		(net "M_A_DQ51")
	)
	(segment
		(start 98.030538 -57.531)
		(end 98.030538 -57.417462)
		(width 0.1016)
		(layer "F.Cu")
		(net "M_A_DQ51")
	)
	(segment
		(start 135.250174 -62.59322)
		(end 135.250174 -63.276226)
		(width 0.1778)
		(layer "F.Cu")
		(net "M_A_DQ51")
	)
	(segment
		(start 98.328988 -51.973734)
		(end 98.461068 -51.841654)
		(width 0.1016)
		(layer "F.Cu")
		(net "M_A_DQ51")
	)
	(segment
		(start 134.62 -64.76619)
		(end 134.62381 -64.77)
		(width 0.1778)
		(layer "F.Cu")
		(net "M_A_DQ51")
	)
	(segment
		(start 98.425 -57.023)
		(end 98.425 -52.789328)
		(width 0.1016)
		(layer "F.Cu")
		(net "M_A_DQ51")
	)
	(segment
		(start 134.62 -63.9064)
		(end 134.62 -64.76619)
		(width 0.1778)
		(layer "F.Cu")
		(net "M_A_DQ51")
	)
	(segment
		(start 98.328988 -52.693316)
		(end 98.328988 -51.973734)
		(width 0.1016)
		(layer "F.Cu")
		(net "M_A_DQ51")
	)
	(via
		(at 98.030538 -57.531)
		(size 0.4318)
		(drill 0.2032)
		(layers "F.Cu" "B.Cu")
		(net "M_A_DQ51")
	)
	(via
		(at 134.62381 -64.77)
		(size 0.4318)
		(drill 0.2032)
		(layers "F.Cu" "B.Cu")
		(net "M_A_DQ51")
	)
	(segment
		(start 134.349998 -63.661798)
		(end 134.5946 -63.9064)
		(width 0.1778)
		(layer "B.Cu")
		(net "M_A_DQ51")
	)
	(segment
		(start 134.5946 -63.9064)
		(end 134.5946 -64.74079)
		(width 0.1778)
		(layer "B.Cu")
		(net "M_A_DQ51")
	)
	(segment
		(start 134.5946 -64.74079)
		(end 134.62381 -64.77)
		(width 0.1778)
		(layer "B.Cu")
		(net "M_A_DQ51")
	)
	(segment
		(start 134.349998 -62.599824)
		(end 134.349998 -63.661798)
		(width 0.1778)
		(layer "B.Cu")
		(net "M_A_DQ51")
	)
	(segment
		(start 108.321602 -68.59905)
		(end 107.602274 -67.879722)
		(width 0.1524)
		(layer "In4.Cu")
		(net "M_A_DQ51")
	)
	(segment
		(start 103.480362 -67.879722)
		(end 97.210626 -61.609986)
		(width 0.1524)
		(layer "In4.Cu")
		(net "M_A_DQ51")
	)
	(segment
		(start 134.62381 -64.77)
		(end 134.62 -64.77381)
		(width 0.1524)
		(layer "In4.Cu")
		(net "M_A_DQ51")
	)
	(segment
		(start 107.602274 -67.879722)
		(end 103.480362 -67.879722)
		(width 0.1524)
		(layer "In4.Cu")
		(net "M_A_DQ51")
	)
	(segment
		(start 130.576574 -66.3448)
		(end 130.576574 -68.453)
		(width 0.1524)
		(layer "In4.Cu")
		(net "M_A_DQ51")
	)
	(segment
		(start 129.3114 -66.1924)
		(end 126.90475 -68.59905)
		(width 0.1524)
		(layer "In4.Cu")
		(net "M_A_DQ51")
	)
	(segment
		(start 97.210626 -59.583574)
		(end 98.030538 -58.763662)
		(width 0.1016)
		(layer "In4.Cu")
		(net "M_A_DQ51")
	)
	(segment
		(start 134.62 -64.77381)
		(end 134.62 -64.897)
		(width 0.1524)
		(layer "In4.Cu")
		(net "M_A_DQ51")
	)
	(segment
		(start 130.728974 -66.1924)
		(end 130.576574 -66.3448)
		(width 0.1524)
		(layer "In4.Cu")
		(net "M_A_DQ51")
	)
	(segment
		(start 126.90475 -68.59905)
		(end 108.321602 -68.59905)
		(width 0.1524)
		(layer "In4.Cu")
		(net "M_A_DQ51")
	)
	(segment
		(start 133.9088 -66.1924)
		(end 130.728974 -66.1924)
		(width 0.1524)
		(layer "In4.Cu")
		(net "M_A_DQ51")
	)
	(segment
		(start 129.966974 -66.3448)
		(end 129.814574 -66.1924)
		(width 0.1524)
		(layer "In4.Cu")
		(net "M_A_DQ51")
	)
	(segment
		(start 130.424174 -68.6054)
		(end 130.119374 -68.6054)
		(width 0.1524)
		(layer "In4.Cu")
		(net "M_A_DQ51")
	)
	(segment
		(start 134.20471 -65.31229)
		(end 134.20471 -65.89649)
		(width 0.1524)
		(layer "In4.Cu")
		(net "M_A_DQ51")
	)
	(segment
		(start 97.210626 -61.609986)
		(end 97.210626 -59.583574)
		(width 0.1016)
		(layer "In4.Cu")
		(net "M_A_DQ51")
	)
	(segment
		(start 129.814574 -66.1924)
		(end 129.3114 -66.1924)
		(width 0.1524)
		(layer "In4.Cu")
		(net "M_A_DQ51")
	)
	(segment
		(start 134.62 -64.897)
		(end 134.20471 -65.31229)
		(width 0.1524)
		(layer "In4.Cu")
		(net "M_A_DQ51")
	)
	(segment
		(start 129.966974 -68.453)
		(end 129.966974 -66.3448)
		(width 0.1524)
		(layer "In4.Cu")
		(net "M_A_DQ51")
	)
	(segment
		(start 130.119374 -68.6054)
		(end 129.966974 -68.453)
		(width 0.1524)
		(layer "In4.Cu")
		(net "M_A_DQ51")
	)
	(segment
		(start 98.030538 -58.763662)
		(end 98.030538 -57.531)
		(width 0.1016)
		(layer "In4.Cu")
		(net "M_A_DQ51")
	)
	(segment
		(start 134.20471 -65.89649)
		(end 133.9088 -66.1924)
		(width 0.1524)
		(layer "In4.Cu")
		(net "M_A_DQ51")
	)
	(segment
		(start 130.576574 -68.453)
		(end 130.424174 -68.6054)
		(width 0.1524)
		(layer "In4.Cu")
		(net "M_A_DQ51")
	)
	(segment
		(start 88.920828 -40.716454)
		(end 88.920828 -40.720772)
		(width 0.1143)
		(layer "F.Cu")
		(net "CTBTRIGOUT")
	)
	(segment
		(start 88.920828 -40.720772)
		(end 88.5698 -41.0718)
		(width 0.1143)
		(layer "F.Cu")
		(net "CTBTRIGOUT")
	)
	(via
		(at 80.854296 -44.887896)
		(size 0.7112)
		(drill 0.3556)
		(layers "F.Cu" "B.Cu")
		(net "CTBTRIGOUT")
	)
	(via
		(at 88.5698 -41.0718)
		(size 0.4318)
		(drill 0.2032)
		(layers "F.Cu" "B.Cu")
		(net "CTBTRIGOUT")
	)
	(segment
		(start 81.70926 -44.032932)
		(end 80.854296 -44.887896)
		(width 0.1143)
		(layer "B.Cu")
		(net "CTBTRIGOUT")
	)
	(segment
		(start 88.388698 -41.0718)
		(end 88.014048 -41.44645)
		(width 0.1143)
		(layer "B.Cu")
		(net "CTBTRIGOUT")
	)
	(segment
		(start 82.103214 -43.297348)
		(end 81.928716 -43.297348)
		(width 0.1143)
		(layer "B.Cu")
		(net "CTBTRIGOUT")
	)
	(segment
		(start 87.483696 -41.44645)
		(end 86.487 -42.443146)
		(width 0.1143)
		(layer "B.Cu")
		(net "CTBTRIGOUT")
	)
	(segment
		(start 80.410558 -45.331634)
		(end 80.854296 -44.887896)
		(width 0.1143)
		(layer "B.Cu")
		(net "CTBTRIGOUT")
	)
	(segment
		(start 80.410558 -46.691042)
		(end 80.410558 -45.331634)
		(width 0.1143)
		(layer "B.Cu")
		(net "CTBTRIGOUT")
	)
	(segment
		(start 86.487 -42.443146)
		(end 82.957416 -42.443146)
		(width 0.1143)
		(layer "B.Cu")
		(net "CTBTRIGOUT")
	)
	(segment
		(start 76.073 -47.66564)
		(end 76.454 -47.28464)
		(width 0.1143)
		(layer "B.Cu")
		(net "CTBTRIGOUT")
	)
	(segment
		(start 75.6158 -50.673)
		(end 76.073 -50.2158)
		(width 0.1143)
		(layer "B.Cu")
		(net "CTBTRIGOUT")
	)
	(segment
		(start 79.81696 -47.28464)
		(end 80.410558 -46.691042)
		(width 0.1143)
		(layer "B.Cu")
		(net "CTBTRIGOUT")
	)
	(segment
		(start 81.70926 -43.516804)
		(end 81.70926 -44.032932)
		(width 0.1143)
		(layer "B.Cu")
		(net "CTBTRIGOUT")
	)
	(segment
		(start 88.5698 -41.0718)
		(end 88.388698 -41.0718)
		(width 0.1143)
		(layer "B.Cu")
		(net "CTBTRIGOUT")
	)
	(segment
		(start 75.3618 -50.673)
		(end 75.6158 -50.673)
		(width 0.1143)
		(layer "B.Cu")
		(net "CTBTRIGOUT")
	)
	(segment
		(start 76.073 -50.2158)
		(end 76.073 -47.66564)
		(width 0.1143)
		(layer "B.Cu")
		(net "CTBTRIGOUT")
	)
	(segment
		(start 82.957416 -42.443146)
		(end 82.103214 -43.297348)
		(width 0.1143)
		(layer "B.Cu")
		(net "CTBTRIGOUT")
	)
	(segment
		(start 88.014048 -41.44645)
		(end 87.483696 -41.44645)
		(width 0.1143)
		(layer "B.Cu")
		(net "CTBTRIGOUT")
	)
	(segment
		(start 81.928716 -43.297348)
		(end 81.70926 -43.516804)
		(width 0.1143)
		(layer "B.Cu")
		(net "CTBTRIGOUT")
	)
	(segment
		(start 76.454 -47.28464)
		(end 79.81696 -47.28464)
		(width 0.1143)
		(layer "B.Cu")
		(net "CTBTRIGOUT")
	)
	(segment
		(start 153.850086 -62.59322)
		(end 153.850086 -63.836296)
		(width 0.2159)
		(layer "F.Cu")
		(net "M_A_CK_DN3")
	)
	(segment
		(start 103.049578 -46.983904)
		(end 103.325168 -47.259494)
		(width 0.1016)
		(layer "F.Cu")
		(net "M_A_CK_DN3")
	)
	(segment
		(start 153.7462 -64.304672)
		(end 153.434796 -64.616076)
		(width 0.2159)
		(layer "F.Cu")
		(net "M_A_CK_DN3")
	)
	(segment
		(start 102.928674 -46.983904)
		(end 103.049578 -46.983904)
		(width 0.1016)
		(layer "F.Cu")
		(net "M_A_CK_DN3")
	)
	(segment
		(start 153.850086 -63.836296)
		(end 153.7462 -63.940182)
		(width 0.2159)
		(layer "F.Cu")
		(net "M_A_CK_DN3")
	)
	(segment
		(start 153.7462 -63.940182)
		(end 153.7462 -64.304672)
		(width 0.2159)
		(layer "F.Cu")
		(net "M_A_CK_DN3")
	)
	(via
		(at 153.434796 -64.616076)
		(size 0.4318)
		(drill 0.2032)
		(layers "F.Cu" "B.Cu")
		(net "M_A_CK_DN3")
	)
	(via
		(at 102.928674 -46.983904)
		(size 0.4318)
		(drill 0.2032)
		(layers "F.Cu" "B.Cu")
		(net "M_A_CK_DN3")
	)
	(segment
		(start 111.321596 -52.749196)
		(end 110.598204 -52.749196)
		(width 0.1905)
		(layer "In7.Cu")
		(net "M_A_CK_DN3")
	)
	(segment
		(start 135.849106 -51.498246)
		(end 133.312154 -51.498246)
		(width 0.1905)
		(layer "In7.Cu")
		(net "M_A_CK_DN3")
	)
	(segment
		(start 122.420634 -51.498246)
		(end 118.910354 -51.498246)
		(width 0.1905)
		(layer "In7.Cu")
		(net "M_A_CK_DN3")
	)
	(segment
		(start 143.1036 -52.15255)
		(end 142.449296 -51.498246)
		(width 0.1905)
		(layer "In7.Cu")
		(net "M_A_CK_DN3")
	)
	(segment
		(start 155.2321 -61.510164)
		(end 155.00604 -61.284104)
		(width 0.1905)
		(layer "In7.Cu")
		(net "M_A_CK_DN3")
	)
	(segment
		(start 153.434796 -64.616076)
		(end 153.647648 -64.403224)
		(width 0.1905)
		(layer "In7.Cu")
		(net "M_A_CK_DN3")
	)
	(segment
		(start 112.4712 -53.0606)
		(end 111.633 -53.0606)
		(width 0.1905)
		(layer "In7.Cu")
		(net "M_A_CK_DN3")
	)
	(segment
		(start 148.185124 -53.85816)
		(end 147.613624 -53.85816)
		(width 0.1905)
		(layer "In7.Cu")
		(net "M_A_CK_DN3")
	)
	(segment
		(start 155.00604 -61.284104)
		(end 155.00604 -60.712604)
		(width 0.1905)
		(layer "In7.Cu")
		(net "M_A_CK_DN3")
	)
	(segment
		(start 152.160732 -56.36514)
		(end 149.427692 -53.6321)
		(width 0.1905)
		(layer "In7.Cu")
		(net "M_A_CK_DN3")
	)
	(segment
		(start 138.15949 -51.498246)
		(end 137.587736 -52.07)
		(width 0.1905)
		(layer "In7.Cu")
		(net "M_A_CK_DN3")
	)
	(segment
		(start 108.272834 -52.749196)
		(end 108.177838 -52.6542)
		(width 0.1016)
		(layer "In7.Cu")
		(net "M_A_CK_DN3")
	)
	(segment
		(start 153.647648 -62.904116)
		(end 154.194764 -62.357)
		(width 0.1905)
		(layer "In7.Cu")
		(net "M_A_CK_DN3")
	)
	(segment
		(start 111.633 -53.0606)
		(end 111.321596 -52.749196)
		(width 0.1905)
		(layer "In7.Cu")
		(net "M_A_CK_DN3")
	)
	(segment
		(start 145.336514 -52.15255)
		(end 143.1036 -52.15255)
		(width 0.1905)
		(layer "In7.Cu")
		(net "M_A_CK_DN3")
	)
	(segment
		(start 149.427692 -53.6321)
		(end 148.411184 -53.6321)
		(width 0.1905)
		(layer "In7.Cu")
		(net "M_A_CK_DN3")
	)
	(segment
		(start 110.598204 -52.749196)
		(end 110.2106 -53.1368)
		(width 0.1905)
		(layer "In7.Cu")
		(net "M_A_CK_DN3")
	)
	(segment
		(start 112.776 -52.7558)
		(end 112.4712 -53.0606)
		(width 0.1905)
		(layer "In7.Cu")
		(net "M_A_CK_DN3")
	)
	(segment
		(start 122.662188 -51.7398)
		(end 122.420634 -51.498246)
		(width 0.1905)
		(layer "In7.Cu")
		(net "M_A_CK_DN3")
	)
	(segment
		(start 127.190246 -51.498246)
		(end 123.253754 -51.498246)
		(width 0.1905)
		(layer "In7.Cu")
		(net "M_A_CK_DN3")
	)
	(segment
		(start 154.956764 -62.357)
		(end 155.2321 -62.081664)
		(width 0.1905)
		(layer "In7.Cu")
		(net "M_A_CK_DN3")
	)
	(segment
		(start 132.321046 -51.498246)
		(end 131.762754 -51.498246)
		(width 0.1905)
		(layer "In7.Cu")
		(net "M_A_CK_DN3")
	)
	(segment
		(start 106.33837 -52.6542)
		(end 105.44937 -51.7652)
		(width 0.1016)
		(layer "In7.Cu")
		(net "M_A_CK_DN3")
	)
	(segment
		(start 113.6142 -53.0606)
		(end 113.3094 -52.7558)
		(width 0.1905)
		(layer "In7.Cu")
		(net "M_A_CK_DN3")
	)
	(segment
		(start 131.536694 -51.724306)
		(end 130.997706 -51.724306)
		(width 0.1905)
		(layer "In7.Cu")
		(net "M_A_CK_DN3")
	)
	(segment
		(start 155.00604 -60.712604)
		(end 155.2321 -60.486544)
		(width 0.1905)
		(layer "In7.Cu")
		(net "M_A_CK_DN3")
	)
	(segment
		(start 142.449296 -51.498246)
		(end 138.15949 -51.498246)
		(width 0.1905)
		(layer "In7.Cu")
		(net "M_A_CK_DN3")
	)
	(segment
		(start 108.177838 -52.6542)
		(end 106.33837 -52.6542)
		(width 0.1016)
		(layer "In7.Cu")
		(net "M_A_CK_DN3")
	)
	(segment
		(start 130.997706 -51.724306)
		(end 130.771646 -51.498246)
		(width 0.1905)
		(layer "In7.Cu")
		(net "M_A_CK_DN3")
	)
	(segment
		(start 103.2764 -47.2948)
		(end 102.965504 -46.983904)
		(width 0.1016)
		(layer "In7.Cu")
		(net "M_A_CK_DN3")
	)
	(segment
		(start 113.3094 -52.7558)
		(end 112.776 -52.7558)
		(width 0.1905)
		(layer "In7.Cu")
		(net "M_A_CK_DN3")
	)
	(segment
		(start 147.387564 -53.6321)
		(end 146.816064 -53.6321)
		(width 0.1905)
		(layer "In7.Cu")
		(net "M_A_CK_DN3")
	)
	(segment
		(start 117.348 -53.0606)
		(end 113.6142 -53.0606)
		(width 0.1905)
		(layer "In7.Cu")
		(net "M_A_CK_DN3")
	)
	(segment
		(start 110.2106 -53.1368)
		(end 109.175804 -53.1368)
		(width 0.1905)
		(layer "In7.Cu")
		(net "M_A_CK_DN3")
	)
	(segment
		(start 136.42086 -52.07)
		(end 135.849106 -51.498246)
		(width 0.1905)
		(layer "In7.Cu")
		(net "M_A_CK_DN3")
	)
	(segment
		(start 127.416306 -51.724306)
		(end 127.190246 -51.498246)
		(width 0.1905)
		(layer "In7.Cu")
		(net "M_A_CK_DN3")
	)
	(segment
		(start 104.0892 -51.231292)
		(end 104.0892 -48.064928)
		(width 0.1016)
		(layer "In7.Cu")
		(net "M_A_CK_DN3")
	)
	(segment
		(start 103.522272 -47.9298)
		(end 103.2764 -47.683928)
		(width 0.1016)
		(layer "In7.Cu")
		(net "M_A_CK_DN3")
	)
	(segment
		(start 146.816064 -53.6321)
		(end 145.336514 -52.15255)
		(width 0.1905)
		(layer "In7.Cu")
		(net "M_A_CK_DN3")
	)
	(segment
		(start 155.2321 -62.081664)
		(end 155.2321 -61.510164)
		(width 0.1905)
		(layer "In7.Cu")
		(net "M_A_CK_DN3")
	)
	(segment
		(start 104.0892 -48.064928)
		(end 103.954072 -47.9298)
		(width 0.1016)
		(layer "In7.Cu")
		(net "M_A_CK_DN3")
	)
	(segment
		(start 133.086094 -51.724306)
		(end 132.547106 -51.724306)
		(width 0.1905)
		(layer "In7.Cu")
		(net "M_A_CK_DN3")
	)
	(segment
		(start 147.613624 -53.85816)
		(end 147.387564 -53.6321)
		(width 0.1905)
		(layer "In7.Cu")
		(net "M_A_CK_DN3")
	)
	(segment
		(start 132.547106 -51.724306)
		(end 132.321046 -51.498246)
		(width 0.1905)
		(layer "In7.Cu")
		(net "M_A_CK_DN3")
	)
	(segment
		(start 133.312154 -51.498246)
		(end 133.086094 -51.724306)
		(width 0.1905)
		(layer "In7.Cu")
		(net "M_A_CK_DN3")
	)
	(segment
		(start 153.647648 -64.403224)
		(end 153.647648 -62.904116)
		(width 0.1905)
		(layer "In7.Cu")
		(net "M_A_CK_DN3")
	)
	(segment
		(start 127.752094 -51.724306)
		(end 127.416306 -51.724306)
		(width 0.1905)
		(layer "In7.Cu")
		(net "M_A_CK_DN3")
	)
	(segment
		(start 123.0122 -51.7398)
		(end 122.662188 -51.7398)
		(width 0.1905)
		(layer "In7.Cu")
		(net "M_A_CK_DN3")
	)
	(segment
		(start 118.910354 -51.498246)
		(end 117.348 -53.0606)
		(width 0.1905)
		(layer "In7.Cu")
		(net "M_A_CK_DN3")
	)
	(segment
		(start 103.954072 -47.9298)
		(end 103.522272 -47.9298)
		(width 0.1016)
		(layer "In7.Cu")
		(net "M_A_CK_DN3")
	)
	(segment
		(start 105.44937 -51.7652)
		(end 104.623108 -51.7652)
		(width 0.1016)
		(layer "In7.Cu")
		(net "M_A_CK_DN3")
	)
	(segment
		(start 127.978154 -51.498246)
		(end 127.752094 -51.724306)
		(width 0.1905)
		(layer "In7.Cu")
		(net "M_A_CK_DN3")
	)
	(segment
		(start 103.2764 -47.683928)
		(end 103.2764 -47.2948)
		(width 0.1016)
		(layer "In7.Cu")
		(net "M_A_CK_DN3")
	)
	(segment
		(start 108.7882 -52.749196)
		(end 108.272834 -52.749196)
		(width 0.1905)
		(layer "In7.Cu")
		(net "M_A_CK_DN3")
	)
	(segment
		(start 104.623108 -51.7652)
		(end 104.0892 -51.231292)
		(width 0.1016)
		(layer "In7.Cu")
		(net "M_A_CK_DN3")
	)
	(segment
		(start 131.762754 -51.498246)
		(end 131.536694 -51.724306)
		(width 0.1905)
		(layer "In7.Cu")
		(net "M_A_CK_DN3")
	)
	(segment
		(start 155.2321 -60.486544)
		(end 155.2321 -57.396634)
		(width 0.1905)
		(layer "In7.Cu")
		(net "M_A_CK_DN3")
	)
	(segment
		(start 109.175804 -53.1368)
		(end 108.7882 -52.749196)
		(width 0.1905)
		(layer "In7.Cu")
		(net "M_A_CK_DN3")
	)
	(segment
		(start 154.200606 -56.36514)
		(end 152.160732 -56.36514)
		(width 0.1905)
		(layer "In7.Cu")
		(net "M_A_CK_DN3")
	)
	(segment
		(start 137.587736 -52.07)
		(end 136.42086 -52.07)
		(width 0.1905)
		(layer "In7.Cu")
		(net "M_A_CK_DN3")
	)
	(segment
		(start 154.194764 -62.357)
		(end 154.956764 -62.357)
		(width 0.1905)
		(layer "In7.Cu")
		(net "M_A_CK_DN3")
	)
	(segment
		(start 123.253754 -51.498246)
		(end 123.0122 -51.7398)
		(width 0.1905)
		(layer "In7.Cu")
		(net "M_A_CK_DN3")
	)
	(segment
		(start 155.2321 -57.396634)
		(end 154.200606 -56.36514)
		(width 0.1905)
		(layer "In7.Cu")
		(net "M_A_CK_DN3")
	)
	(segment
		(start 102.965504 -46.983904)
		(end 102.928674 -46.983904)
		(width 0.1016)
		(layer "In7.Cu")
		(net "M_A_CK_DN3")
	)
	(segment
		(start 130.771646 -51.498246)
		(end 127.978154 -51.498246)
		(width 0.1905)
		(layer "In7.Cu")
		(net "M_A_CK_DN3")
	)
	(segment
		(start 148.411184 -53.6321)
		(end 148.185124 -53.85816)
		(width 0.1905)
		(layer "In7.Cu")
		(net "M_A_CK_DN3")
	)
	(segment
		(start 117.318028 -9.8171)
		(end 113.393474 -9.8171)
		(width 0.1143)
		(layer "F.Cu")
		(net "IRQ_NMI")
	)
	(segment
		(start 117.987064 -13.669264)
		(end 117.987064 -10.486136)
		(width 0.1143)
		(layer "F.Cu")
		(net "IRQ_NMI")
	)
	(segment
		(start 119.278146 -14.960346)
		(end 117.987064 -13.669264)
		(width 0.1143)
		(layer "F.Cu")
		(net "IRQ_NMI")
	)
	(segment
		(start 113.393474 -9.8171)
		(end 110.961424 -7.38505)
		(width 0.1143)
		(layer "F.Cu")
		(net "IRQ_NMI")
	)
	(segment
		(start 108.375704 -6.43255)
		(end 108.30687 -6.363716)
		(width 0.1143)
		(layer "F.Cu")
		(net "IRQ_NMI")
	)
	(segment
		(start 117.987064 -10.486136)
		(end 117.318028 -9.8171)
		(width 0.1143)
		(layer "F.Cu")
		(net "IRQ_NMI")
	)
	(segment
		(start 110.48365 -7.38505)
		(end 109.53115 -6.43255)
		(width 0.1143)
		(layer "F.Cu")
		(net "IRQ_NMI")
	)
	(segment
		(start 69.35724 -47.347124)
		(end 69.35724 -48.100996)
		(width 0.1143)
		(layer "F.Cu")
		(net "IRQ_NMI")
	)
	(segment
		(start 126.178564 -25.8064)
		(end 123.406154 -25.8064)
		(width 0.1143)
		(layer "F.Cu")
		(net "IRQ_NMI")
	)
	(segment
		(start 119.278146 -21.678392)
		(end 119.278146 -14.960346)
		(width 0.1143)
		(layer "F.Cu")
		(net "IRQ_NMI")
	)
	(segment
		(start 128.166114 -27.79395)
		(end 126.178564 -25.8064)
		(width 0.1143)
		(layer "F.Cu")
		(net "IRQ_NMI")
	)
	(segment
		(start 132.1308 -27.79395)
		(end 128.166114 -27.79395)
		(width 0.1143)
		(layer "F.Cu")
		(net "IRQ_NMI")
	)
	(segment
		(start 110.961424 -7.38505)
		(end 110.48365 -7.38505)
		(width 0.1143)
		(layer "F.Cu")
		(net "IRQ_NMI")
	)
	(segment
		(start 123.406154 -25.8064)
		(end 119.278146 -21.678392)
		(width 0.1143)
		(layer "F.Cu")
		(net "IRQ_NMI")
	)
	(segment
		(start 109.53115 -6.43255)
		(end 108.375704 -6.43255)
		(width 0.1143)
		(layer "F.Cu")
		(net "IRQ_NMI")
	)
	(segment
		(start 69.360796 -47.343568)
		(end 69.35724 -47.347124)
		(width 0.1143)
		(layer "F.Cu")
		(net "IRQ_NMI")
	)
	(via
		(at 69.35724 -48.100996)
		(size 0.508)
		(drill 0.254)
		(layers "F.Cu" "B.Cu")
		(net "IRQ_NMI")
	)
	(via
		(at 69.360796 -47.343568)
		(size 0.7112)
		(drill 0.3556)
		(layers "F.Cu" "B.Cu")
		(net "IRQ_NMI")
	)
	(via
		(at 108.30687 -6.363716)
		(size 0.508)
		(drill 0.254)
		(layers "F.Cu" "B.Cu")
		(net "IRQ_NMI")
	)
	(segment
		(start 69.596 -47.2948)
		(end 69.35724 -47.53356)
		(width 0.1143)
		(layer "B.Cu")
		(net "IRQ_NMI")
	)
	(segment
		(start 69.35724 -47.53356)
		(end 69.35724 -48.100996)
		(width 0.1143)
		(layer "B.Cu")
		(net "IRQ_NMI")
	)
	(segment
		(start 95.591884 -14.07795)
		(end 90.949272 -14.07795)
		(width 0.0889)
		(layer "In9.Cu")
		(net "IRQ_NMI")
	)
	(segment
		(start 84.416138 -13.8811)
		(end 83.336638 -12.8016)
		(width 0.0889)
		(layer "In9.Cu")
		(net "IRQ_NMI")
	)
	(segment
		(start 80.772 -12.372594)
		(end 80.772 -10.177018)
		(width 0.0889)
		(layer "In9.Cu")
		(net "IRQ_NMI")
	)
	(segment
		(start 69.35724 -47.69104)
		(end 69.35724 -48.100996)
		(width 0.0889)
		(layer "In9.Cu")
		(net "IRQ_NMI")
	)
	(segment
		(start 62.442344 -16.64335)
		(end 64.13627 -18.337276)
		(width 0.0889)
		(layer "In9.Cu")
		(net "IRQ_NMI")
	)
	(segment
		(start 79.748888 -9.15035)
		(end 66.651124 -9.15035)
		(width 0.0889)
		(layer "In9.Cu")
		(net "IRQ_NMI")
	)
	(segment
		(start 81.201006 -12.8016)
		(end 80.772 -12.372594)
		(width 0.0889)
		(layer "In9.Cu")
		(net "IRQ_NMI")
	)
	(segment
		(start 66.651124 -9.15035)
		(end 61.46165 -14.339824)
		(width 0.0889)
		(layer "In9.Cu")
		(net "IRQ_NMI")
	)
	(segment
		(start 64.8716 -42.552366)
		(end 64.8716 -43.964606)
		(width 0.0889)
		(layer "In9.Cu")
		(net "IRQ_NMI")
	)
	(segment
		(start 95.98914 -14.475206)
		(end 95.591884 -14.07795)
		(width 0.0889)
		(layer "In9.Cu")
		(net "IRQ_NMI")
	)
	(segment
		(start 80.772 -10.177018)
		(end 80.764634 -10.166096)
		(width 0.0889)
		(layer "In9.Cu")
		(net "IRQ_NMI")
	)
	(segment
		(start 64.13627 -18.911062)
		(end 63.641732 -19.4056)
		(width 0.0889)
		(layer "In9.Cu")
		(net "IRQ_NMI")
	)
	(segment
		(start 108.30687 -6.363716)
		(end 108.29925 -6.363716)
		(width 0.0889)
		(layer "In9.Cu")
		(net "IRQ_NMI")
	)
	(segment
		(start 108.29925 -6.363716)
		(end 108.29925 -11.740642)
		(width 0.0889)
		(layer "In9.Cu")
		(net "IRQ_NMI")
	)
	(segment
		(start 64.13627 -18.337276)
		(end 64.13627 -18.911062)
		(width 0.0889)
		(layer "In9.Cu")
		(net "IRQ_NMI")
	)
	(segment
		(start 68.9864 -47.3202)
		(end 69.35724 -47.69104)
		(width 0.0889)
		(layer "In9.Cu")
		(net "IRQ_NMI")
	)
	(segment
		(start 62.283086 -16.64335)
		(end 62.442344 -16.64335)
		(width 0.0889)
		(layer "In9.Cu")
		(net "IRQ_NMI")
	)
	(segment
		(start 89.263474 -13.240004)
		(end 88.622378 -13.8811)
		(width 0.0889)
		(layer "In9.Cu")
		(net "IRQ_NMI")
	)
	(segment
		(start 61.46165 -14.339824)
		(end 61.46165 -15.821914)
		(width 0.0889)
		(layer "In9.Cu")
		(net "IRQ_NMI")
	)
	(segment
		(start 90.949272 -14.07795)
		(end 90.111326 -13.240004)
		(width 0.0889)
		(layer "In9.Cu")
		(net "IRQ_NMI")
	)
	(segment
		(start 63.641732 -19.4056)
		(end 63.641732 -41.322498)
		(width 0.0889)
		(layer "In9.Cu")
		(net "IRQ_NMI")
	)
	(segment
		(start 64.8716 -43.964606)
		(end 68.227194 -47.3202)
		(width 0.0889)
		(layer "In9.Cu")
		(net "IRQ_NMI")
	)
	(segment
		(start 88.622378 -13.8811)
		(end 84.416138 -13.8811)
		(width 0.0889)
		(layer "In9.Cu")
		(net "IRQ_NMI")
	)
	(segment
		(start 108.29925 -11.740642)
		(end 105.564686 -14.475206)
		(width 0.0889)
		(layer "In9.Cu")
		(net "IRQ_NMI")
	)
	(segment
		(start 105.564686 -14.475206)
		(end 95.98914 -14.475206)
		(width 0.0889)
		(layer "In9.Cu")
		(net "IRQ_NMI")
	)
	(segment
		(start 63.641732 -41.322498)
		(end 64.8716 -42.552366)
		(width 0.0889)
		(layer "In9.Cu")
		(net "IRQ_NMI")
	)
	(segment
		(start 80.764634 -10.166096)
		(end 79.748888 -9.15035)
		(width 0.0889)
		(layer "In9.Cu")
		(net "IRQ_NMI")
	)
	(segment
		(start 90.111326 -13.240004)
		(end 89.263474 -13.240004)
		(width 0.0889)
		(layer "In9.Cu")
		(net "IRQ_NMI")
	)
	(segment
		(start 68.227194 -47.3202)
		(end 68.9864 -47.3202)
		(width 0.0889)
		(layer "In9.Cu")
		(net "IRQ_NMI")
	)
	(segment
		(start 83.336638 -12.8016)
		(end 81.201006 -12.8016)
		(width 0.0889)
		(layer "In9.Cu")
		(net "IRQ_NMI")
	)
	(segment
		(start 61.46165 -15.821914)
		(end 62.283086 -16.64335)
		(width 0.0889)
		(layer "In9.Cu")
		(net "IRQ_NMI")
	)
	(via
		(at 33.10001 -22.995382)
		(size 0.508)
		(drill 0.254)
		(layers "F.Cu" "B.Cu")
		(net "PWRGD_P1V35_PG")
	)
	(via
		(at 76.1492 -21.8313)
		(size 0.508)
		(drill 0.254)
		(layers "F.Cu" "B.Cu")
		(net "PWRGD_P1V35_PG")
	)
	(via
		(at 29.461714 -20.978114)
		(size 0.7112)
		(drill 0.3556)
		(layers "F.Cu" "B.Cu")
		(net "PWRGD_P1V35_PG")
	)
	(segment
		(start 31.4706 -22.987)
		(end 29.461714 -20.978114)
		(width 0.254)
		(layer "B.Cu")
		(net "PWRGD_P1V35_PG")
	)
	(segment
		(start 78.7908 -19.1262)
		(end 78.7908 -19.8374)
		(width 0.254)
		(layer "B.Cu")
		(net "PWRGD_P1V35_PG")
	)
	(segment
		(start 79.069692 -18.847308)
		(end 78.7908 -19.1262)
		(width 0.254)
		(layer "B.Cu")
		(net "PWRGD_P1V35_PG")
	)
	(segment
		(start 78.7908 -19.8374)
		(end 77.8764 -20.7518)
		(width 0.254)
		(layer "B.Cu")
		(net "PWRGD_P1V35_PG")
	)
	(segment
		(start 77.343 -20.7772)
		(end 77.1906 -20.7772)
		(width 0.254)
		(layer "B.Cu")
		(net "PWRGD_P1V35_PG")
	)
	(segment
		(start 20.338796 -20.479004)
		(end 19.3548 -21.463)
		(width 0.254)
		(layer "B.Cu")
		(net "PWRGD_P1V35_PG")
	)
	(segment
		(start 28.962604 -20.479004)
		(end 20.338796 -20.479004)
		(width 0.254)
		(layer "B.Cu")
		(net "PWRGD_P1V35_PG")
	)
	(segment
		(start 29.461714 -20.978114)
		(end 28.962604 -20.479004)
		(width 0.254)
		(layer "B.Cu")
		(net "PWRGD_P1V35_PG")
	)
	(segment
		(start 33.10001 -22.995382)
		(end 33.091628 -22.987)
		(width 0.254)
		(layer "B.Cu")
		(net "PWRGD_P1V35_PG")
	)
	(segment
		(start 77.1906 -20.7772)
		(end 76.1492 -21.8186)
		(width 0.254)
		(layer "B.Cu")
		(net "PWRGD_P1V35_PG")
	)
	(segment
		(start 79.918306 -18.847308)
		(end 79.069692 -18.847308)
		(width 0.254)
		(layer "B.Cu")
		(net "PWRGD_P1V35_PG")
	)
	(segment
		(start 77.8764 -20.7518)
		(end 77.3684 -20.7518)
		(width 0.254)
		(layer "B.Cu")
		(net "PWRGD_P1V35_PG")
	)
	(segment
		(start 76.1492 -21.8186)
		(end 76.1492 -21.8313)
		(width 0.254)
		(layer "B.Cu")
		(net "PWRGD_P1V35_PG")
	)
	(segment
		(start 77.3684 -20.7518)
		(end 77.343 -20.7772)
		(width 0.254)
		(layer "B.Cu")
		(net "PWRGD_P1V35_PG")
	)
	(segment
		(start 33.091628 -22.987)
		(end 31.4706 -22.987)
		(width 0.254)
		(layer "B.Cu")
		(net "PWRGD_P1V35_PG")
	)
	(segment
		(start 54.560216 -21.893784)
		(end 60.654184 -21.893784)
		(width 0.254)
		(layer "In4.Cu")
		(net "PWRGD_P1V35_PG")
	)
	(segment
		(start 50.726848 -19.304)
		(end 53.673248 -22.2504)
		(width 0.254)
		(layer "In4.Cu")
		(net "PWRGD_P1V35_PG")
	)
	(segment
		(start 53.673248 -22.2504)
		(end 54.2036 -22.2504)
		(width 0.254)
		(layer "In4.Cu")
		(net "PWRGD_P1V35_PG")
	)
	(segment
		(start 40.710104 -20.828)
		(end 41.243504 -20.2946)
		(width 0.254)
		(layer "In4.Cu")
		(net "PWRGD_P1V35_PG")
	)
	(segment
		(start 61.1378 -22.3774)
		(end 62.810136 -22.3774)
		(width 0.254)
		(layer "In4.Cu")
		(net "PWRGD_P1V35_PG")
	)
	(segment
		(start 60.654184 -21.893784)
		(end 61.1378 -22.3774)
		(width 0.254)
		(layer "In4.Cu")
		(net "PWRGD_P1V35_PG")
	)
	(segment
		(start 63.788036 -21.3995)
		(end 75.7174 -21.3995)
		(width 0.254)
		(layer "In4.Cu")
		(net "PWRGD_P1V35_PG")
	)
	(segment
		(start 44.7802 -20.2946)
		(end 45.7708 -19.304)
		(width 0.254)
		(layer "In4.Cu")
		(net "PWRGD_P1V35_PG")
	)
	(segment
		(start 34.3662 -20.828)
		(end 40.710104 -20.828)
		(width 0.254)
		(layer "In4.Cu")
		(net "PWRGD_P1V35_PG")
	)
	(segment
		(start 33.10001 -22.09419)
		(end 34.3662 -20.828)
		(width 0.254)
		(layer "In4.Cu")
		(net "PWRGD_P1V35_PG")
	)
	(segment
		(start 62.810136 -22.3774)
		(end 63.788036 -21.3995)
		(width 0.254)
		(layer "In4.Cu")
		(net "PWRGD_P1V35_PG")
	)
	(segment
		(start 33.10001 -22.995382)
		(end 33.10001 -22.09419)
		(width 0.254)
		(layer "In4.Cu")
		(net "PWRGD_P1V35_PG")
	)
	(segment
		(start 75.7174 -21.3995)
		(end 76.1492 -21.8313)
		(width 0.254)
		(layer "In4.Cu")
		(net "PWRGD_P1V35_PG")
	)
	(segment
		(start 45.7708 -19.304)
		(end 50.726848 -19.304)
		(width 0.254)
		(layer "In4.Cu")
		(net "PWRGD_P1V35_PG")
	)
	(segment
		(start 54.2036 -22.2504)
		(end 54.560216 -21.893784)
		(width 0.254)
		(layer "In4.Cu")
		(net "PWRGD_P1V35_PG")
	)
	(segment
		(start 41.243504 -20.2946)
		(end 44.7802 -20.2946)
		(width 0.254)
		(layer "In4.Cu")
		(net "PWRGD_P1V35_PG")
	)
	(segment
		(start 177.09769 -66.937128)
		(end 176.832768 -66.672206)
		(width 0.1778)
		(layer "F.Cu")
		(net "M_A_DQS_DP2")
	)
	(segment
		(start 176.950116 -70.053708)
		(end 177.09769 -69.906134)
		(width 0.1778)
		(layer "F.Cu")
		(net "M_A_DQS_DP2")
	)
	(segment
		(start 106.735118 -45.241718)
		(end 106.528108 -45.034708)
		(width 0.1016)
		(layer "F.Cu")
		(net "M_A_DQS_DP2")
	)
	(segment
		(start 176.950116 -70.806564)
		(end 176.950116 -70.053708)
		(width 0.1778)
		(layer "F.Cu")
		(net "M_A_DQS_DP2")
	)
	(segment
		(start 177.09769 -69.906134)
		(end 177.09769 -66.937128)
		(width 0.1778)
		(layer "F.Cu")
		(net "M_A_DQS_DP2")
	)
	(segment
		(start 106.914188 -45.241718)
		(end 106.735118 -45.241718)
		(width 0.1016)
		(layer "F.Cu")
		(net "M_A_DQS_DP2")
	)
	(segment
		(start 106.528108 -45.034708)
		(end 106.528108 -44.927774)
		(width 0.1016)
		(layer "F.Cu")
		(net "M_A_DQS_DP2")
	)
	(via
		(at 176.832768 -66.672206)
		(size 0.4318)
		(drill 0.2032)
		(layers "F.Cu" "B.Cu")
		(net "M_A_DQS_DP2")
	)
	(via
		(at 106.914188 -45.241718)
		(size 0.4318)
		(drill 0.2032)
		(layers "F.Cu" "B.Cu")
		(net "M_A_DQS_DP2")
	)
	(segment
		(start 176.950116 -63.349124)
		(end 176.98847 -63.387478)
		(width 0.1778)
		(layer "B.Cu")
		(net "M_A_DQS_DP2")
	)
	(segment
		(start 177.1904 -64.591692)
		(end 177.1904 -66.314574)
		(width 0.1778)
		(layer "B.Cu")
		(net "M_A_DQS_DP2")
	)
	(segment
		(start 177.1904 -66.314574)
		(end 176.832768 -66.672206)
		(width 0.1778)
		(layer "B.Cu")
		(net "M_A_DQS_DP2")
	)
	(segment
		(start 176.98847 -63.387478)
		(end 176.98847 -64.389762)
		(width 0.1778)
		(layer "B.Cu")
		(net "M_A_DQS_DP2")
	)
	(segment
		(start 176.950116 -62.599824)
		(end 176.950116 -63.349124)
		(width 0.1778)
		(layer "B.Cu")
		(net "M_A_DQS_DP2")
	)
	(segment
		(start 176.98847 -64.389762)
		(end 177.1904 -64.591692)
		(width 0.1778)
		(layer "B.Cu")
		(net "M_A_DQS_DP2")
	)
	(segment
		(start 151.638 -56.007)
		(end 148.7678 -53.1368)
		(width 0.1524)
		(layer "In4.Cu")
		(net "M_A_DQS_DP2")
	)
	(segment
		(start 162.710114 -56.007)
		(end 151.638 -56.007)
		(width 0.1524)
		(layer "In4.Cu")
		(net "M_A_DQS_DP2")
	)
	(segment
		(start 107.133136 -45.639736)
		(end 107.133136 -45.3644)
		(width 0.1016)
		(layer "In4.Cu")
		(net "M_A_DQS_DP2")
	)
	(segment
		(start 170.467528 -61.6966)
		(end 167.402764 -58.631836)
		(width 0.1524)
		(layer "In4.Cu")
		(net "M_A_DQS_DP2")
	)
	(segment
		(start 167.402764 -58.631836)
		(end 165.33495 -58.631836)
		(width 0.1524)
		(layer "In4.Cu")
		(net "M_A_DQS_DP2")
	)
	(segment
		(start 148.7678 -52.197)
		(end 148.336 -51.7652)
		(width 0.1524)
		(layer "In4.Cu")
		(net "M_A_DQS_DP2")
	)
	(segment
		(start 109.38256 -46.72076)
		(end 107.367832 -46.72076)
		(width 0.1016)
		(layer "In4.Cu")
		(net "M_A_DQS_DP2")
	)
	(segment
		(start 177.03419 -66.470784)
		(end 177.03419 -63.623952)
		(width 0.1524)
		(layer "In4.Cu")
		(net "M_A_DQS_DP2")
	)
	(segment
		(start 107.010454 -45.241718)
		(end 106.914188 -45.241718)
		(width 0.1016)
		(layer "In4.Cu")
		(net "M_A_DQS_DP2")
	)
	(segment
		(start 111.8743 -50.2031)
		(end 111.8743 -49.250346)
		(width 0.1524)
		(layer "In4.Cu")
		(net "M_A_DQS_DP2")
	)
	(segment
		(start 144.684496 -51.7652)
		(end 143.008096 -50.0888)
		(width 0.1524)
		(layer "In4.Cu")
		(net "M_A_DQS_DP2")
	)
	(segment
		(start 148.336 -51.7652)
		(end 144.684496 -51.7652)
		(width 0.1524)
		(layer "In4.Cu")
		(net "M_A_DQS_DP2")
	)
	(segment
		(start 110.891066 -47.826422)
		(end 110.873286 -47.808642)
		(width 0.1016)
		(layer "In4.Cu")
		(net "M_A_DQS_DP2")
	)
	(segment
		(start 110.781338 -47.662338)
		(end 110.324138 -47.662338)
		(width 0.1016)
		(layer "In4.Cu")
		(net "M_A_DQS_DP2")
	)
	(segment
		(start 110.324138 -47.662338)
		(end 109.38256 -46.72076)
		(width 0.1016)
		(layer "In4.Cu")
		(net "M_A_DQS_DP2")
	)
	(segment
		(start 111.8743 -49.250346)
		(end 111.7473 -49.123346)
		(width 0.1524)
		(layer "In4.Cu")
		(net "M_A_DQS_DP2")
	)
	(segment
		(start 111.7473 -49.123346)
		(end 111.7473 -48.682656)
		(width 0.1524)
		(layer "In4.Cu")
		(net "M_A_DQS_DP2")
	)
	(segment
		(start 117.0178 -51.8414)
		(end 113.5126 -51.8414)
		(width 0.1524)
		(layer "In4.Cu")
		(net "M_A_DQS_DP2")
	)
	(segment
		(start 106.983784 -46.336712)
		(end 106.983784 -45.789088)
		(width 0.1016)
		(layer "In4.Cu")
		(net "M_A_DQS_DP2")
	)
	(segment
		(start 118.3132 -50.546)
		(end 117.0178 -51.8414)
		(width 0.1524)
		(layer "In4.Cu")
		(net "M_A_DQS_DP2")
	)
	(segment
		(start 176.832768 -66.672206)
		(end 177.03419 -66.470784)
		(width 0.1524)
		(layer "In4.Cu")
		(net "M_A_DQS_DP2")
	)
	(segment
		(start 165.33495 -58.631836)
		(end 162.710114 -56.007)
		(width 0.1524)
		(layer "In4.Cu")
		(net "M_A_DQS_DP2")
	)
	(segment
		(start 148.7678 -53.1368)
		(end 148.7678 -52.197)
		(width 0.1524)
		(layer "In4.Cu")
		(net "M_A_DQS_DP2")
	)
	(segment
		(start 113.5126 -51.8414)
		(end 111.8743 -50.2031)
		(width 0.1524)
		(layer "In4.Cu")
		(net "M_A_DQS_DP2")
	)
	(segment
		(start 177.03419 -63.623952)
		(end 175.106838 -61.6966)
		(width 0.1524)
		(layer "In4.Cu")
		(net "M_A_DQS_DP2")
	)
	(segment
		(start 110.873286 -47.808642)
		(end 110.873286 -47.754286)
		(width 0.1016)
		(layer "In4.Cu")
		(net "M_A_DQS_DP2")
	)
	(segment
		(start 111.7473 -48.682656)
		(end 110.891066 -47.826422)
		(width 0.1524)
		(layer "In4.Cu")
		(net "M_A_DQS_DP2")
	)
	(segment
		(start 106.983784 -45.789088)
		(end 107.133136 -45.639736)
		(width 0.1016)
		(layer "In4.Cu")
		(net "M_A_DQS_DP2")
	)
	(segment
		(start 107.133136 -45.3644)
		(end 107.010454 -45.241718)
		(width 0.1016)
		(layer "In4.Cu")
		(net "M_A_DQS_DP2")
	)
	(segment
		(start 122.450352 -50.546)
		(end 118.3132 -50.546)
		(width 0.1524)
		(layer "In4.Cu")
		(net "M_A_DQS_DP2")
	)
	(segment
		(start 122.907552 -50.0888)
		(end 122.450352 -50.546)
		(width 0.1524)
		(layer "In4.Cu")
		(net "M_A_DQS_DP2")
	)
	(segment
		(start 107.367832 -46.72076)
		(end 106.983784 -46.336712)
		(width 0.1016)
		(layer "In4.Cu")
		(net "M_A_DQS_DP2")
	)
	(segment
		(start 175.106838 -61.6966)
		(end 170.467528 -61.6966)
		(width 0.1524)
		(layer "In4.Cu")
		(net "M_A_DQS_DP2")
	)
	(segment
		(start 110.873286 -47.754286)
		(end 110.781338 -47.662338)
		(width 0.1016)
		(layer "In4.Cu")
		(net "M_A_DQS_DP2")
	)
	(segment
		(start 143.008096 -50.0888)
		(end 122.907552 -50.0888)
		(width 0.1524)
		(layer "In4.Cu")
		(net "M_A_DQS_DP2")
	)
	(segment
		(start 83.606894 -39.091108)
		(end 83.606894 -39.07282)
		(width 0.1143)
		(layer "F.Cu")
		(net "FLEX_CLK_SE0")
	)
	(segment
		(start 83.266788 -39.431214)
		(end 83.606894 -39.091108)
		(width 0.1143)
		(layer "F.Cu")
		(net "FLEX_CLK_SE0")
	)
	(via
		(at 83.606894 -39.07282)
		(size 0.4318)
		(drill 0.2032)
		(layers "F.Cu" "B.Cu")
		(net "FLEX_CLK_SE0")
	)
	(via
		(at 80.2386 -39.857934)
		(size 0.7112)
		(drill 0.3556)
		(layers "F.Cu" "B.Cu")
		(net "FLEX_CLK_SE0")
	)
	(segment
		(start 73.7108 -38.227)
		(end 74.4728 -37.465)
		(width 0.1143)
		(layer "B.Cu")
		(net "FLEX_CLK_SE0")
	)
	(segment
		(start 81.807558 -38.71595)
		(end 82.248502 -38.71595)
		(width 0.1143)
		(layer "B.Cu")
		(net "FLEX_CLK_SE0")
	)
	(segment
		(start 80.21955 -39.876984)
		(end 77.471016 -39.876984)
		(width 0.1143)
		(layer "B.Cu")
		(net "FLEX_CLK_SE0")
	)
	(segment
		(start 80.2386 -39.857934)
		(end 80.21955 -39.876984)
		(width 0.1143)
		(layer "B.Cu")
		(net "FLEX_CLK_SE0")
	)
	(segment
		(start 74.474832 -37.462968)
		(end 74.4728 -37.465)
		(width 0.1143)
		(layer "B.Cu")
		(net "FLEX_CLK_SE0")
	)
	(segment
		(start 82.266028 -38.733476)
		(end 83.018884 -38.733476)
		(width 0.1143)
		(layer "B.Cu")
		(net "FLEX_CLK_SE0")
	)
	(segment
		(start 83.358228 -39.07282)
		(end 83.606894 -39.07282)
		(width 0.1143)
		(layer "B.Cu")
		(net "FLEX_CLK_SE0")
	)
	(segment
		(start 80.2386 -39.857934)
		(end 80.665574 -39.857934)
		(width 0.1143)
		(layer "B.Cu")
		(net "FLEX_CLK_SE0")
	)
	(segment
		(start 75.057 -37.462968)
		(end 74.474832 -37.462968)
		(width 0.1143)
		(layer "B.Cu")
		(net "FLEX_CLK_SE0")
	)
	(segment
		(start 83.018884 -38.733476)
		(end 83.358228 -39.07282)
		(width 0.1143)
		(layer "B.Cu")
		(net "FLEX_CLK_SE0")
	)
	(segment
		(start 82.248502 -38.71595)
		(end 82.266028 -38.733476)
		(width 0.1143)
		(layer "B.Cu")
		(net "FLEX_CLK_SE0")
	)
	(segment
		(start 77.471016 -39.876984)
		(end 75.057 -37.462968)
		(width 0.1143)
		(layer "B.Cu")
		(net "FLEX_CLK_SE0")
	)
	(segment
		(start 73.7108 -38.354)
		(end 73.7108 -38.227)
		(width 0.1143)
		(layer "B.Cu")
		(net "FLEX_CLK_SE0")
	)
	(segment
		(start 80.665574 -39.857934)
		(end 81.807558 -38.71595)
		(width 0.1143)
		(layer "B.Cu")
		(net "FLEX_CLK_SE0")
	)
	(via
		(at 79.2734 -21.5392)
		(size 0.7112)
		(drill 0.3556)
		(layers "F.Cu" "B.Cu")
		(net "TPS74801_1V35_BIAS")
	)
	(segment
		(start 78.9432 -21.8694)
		(end 79.2734 -21.5392)
		(width 0.3048)
		(layer "B.Cu")
		(net "TPS74801_1V35_BIAS")
	)
	(segment
		(start 79.918306 -20.894294)
		(end 79.918306 -19.497294)
		(width 0.3048)
		(layer "B.Cu")
		(net "TPS74801_1V35_BIAS")
	)
	(segment
		(start 78.486 -22.8854)
		(end 78.9432 -22.4282)
		(width 0.3048)
		(layer "B.Cu")
		(net "TPS74801_1V35_BIAS")
	)
	(segment
		(start 79.2734 -21.5392)
		(end 79.918306 -20.894294)
		(width 0.3048)
		(layer "B.Cu")
		(net "TPS74801_1V35_BIAS")
	)
	(segment
		(start 78.486 -23.2156)
		(end 78.486 -22.8854)
		(width 0.3048)
		(layer "B.Cu")
		(net "TPS74801_1V35_BIAS")
	)
	(segment
		(start 78.9432 -22.4282)
		(end 78.9432 -21.8694)
		(width 0.3048)
		(layer "B.Cu")
		(net "TPS74801_1V35_BIAS")
	)
	(segment
		(start 95.377 -52.377848)
		(end 95.494348 -52.2605)
		(width 0.1016)
		(layer "F.Cu")
		(net "M_A_DQ62")
	)
	(segment
		(start 95.375984 -50.40503)
		(end 95.235268 -50.264314)
		(width 0.1016)
		(layer "F.Cu")
		(net "M_A_DQ62")
	)
	(segment
		(start 95.375984 -51.650138)
		(end 95.375984 -50.40503)
		(width 0.1016)
		(layer "F.Cu")
		(net "M_A_DQ62")
	)
	(segment
		(start 94.6912 -56.2864)
		(end 95.123 -55.8546)
		(width 0.1016)
		(layer "F.Cu")
		(net "M_A_DQ62")
	)
	(segment
		(start 95.123 -53.3146)
		(end 95.377 -53.0606)
		(width 0.1016)
		(layer "F.Cu")
		(net "M_A_DQ62")
	)
	(segment
		(start 95.123 -55.8546)
		(end 95.123 -53.3146)
		(width 0.1016)
		(layer "F.Cu")
		(net "M_A_DQ62")
	)
	(segment
		(start 130.750056 -70.806564)
		(end 130.750056 -68.957444)
		(width 0.1778)
		(layer "F.Cu")
		(net "M_A_DQ62")
	)
	(segment
		(start 95.494348 -52.2605)
		(end 95.494348 -51.768502)
		(width 0.1016)
		(layer "F.Cu")
		(net "M_A_DQ62")
	)
	(segment
		(start 95.377 -53.0606)
		(end 95.377 -52.377848)
		(width 0.1016)
		(layer "F.Cu")
		(net "M_A_DQ62")
	)
	(segment
		(start 130.750056 -68.957444)
		(end 130.7846 -68.9229)
		(width 0.1778)
		(layer "F.Cu")
		(net "M_A_DQ62")
	)
	(segment
		(start 95.494348 -51.768502)
		(end 95.375984 -51.650138)
		(width 0.1016)
		(layer "F.Cu")
		(net "M_A_DQ62")
	)
	(via
		(at 94.6912 -56.2864)
		(size 0.4318)
		(drill 0.2032)
		(layers "F.Cu" "B.Cu")
		(net "M_A_DQ62")
	)
	(via
		(at 130.7846 -68.9229)
		(size 0.4318)
		(drill 0.2032)
		(layers "F.Cu" "B.Cu")
		(net "M_A_DQ62")
	)
	(segment
		(start 130.450082 -70.79996)
		(end 130.450082 -69.257418)
		(width 0.1778)
		(layer "B.Cu")
		(net "M_A_DQ62")
	)
	(segment
		(start 130.450082 -69.257418)
		(end 130.7846 -68.9229)
		(width 0.1778)
		(layer "B.Cu")
		(net "M_A_DQ62")
	)
	(segment
		(start 94.615 -56.3626)
		(end 94.6912 -56.2864)
		(width 0.1016)
		(layer "In7.Cu")
		(net "M_A_DQ62")
	)
	(segment
		(start 117.348 -66.3956)
		(end 116.713 -67.0306)
		(width 0.1524)
		(layer "In7.Cu")
		(net "M_A_DQ62")
	)
	(segment
		(start 130.7846 -68.9229)
		(end 130.616198 -68.754498)
		(width 0.1524)
		(layer "In7.Cu")
		(net "M_A_DQ62")
	)
	(segment
		(start 123.786138 -66.763138)
		(end 123.786138 -66.762884)
		(width 0.1524)
		(layer "In7.Cu")
		(net "M_A_DQ62")
	)
	(segment
		(start 126.017528 -67.639692)
		(end 124.662692 -67.639692)
		(width 0.1524)
		(layer "In7.Cu")
		(net "M_A_DQ62")
	)
	(segment
		(start 129.69748 -63.95974)
		(end 126.017528 -67.639692)
		(width 0.1524)
		(layer "In7.Cu")
		(net "M_A_DQ62")
	)
	(segment
		(start 130.616198 -68.754498)
		(end 130.616198 -66.945002)
		(width 0.1524)
		(layer "In7.Cu")
		(net "M_A_DQ62")
	)
	(segment
		(start 123.786138 -66.762884)
		(end 123.444254 -66.421)
		(width 0.1524)
		(layer "In7.Cu")
		(net "M_A_DQ62")
	)
	(segment
		(start 94.615 -58.674)
		(end 94.615 -56.3626)
		(width 0.1016)
		(layer "In7.Cu")
		(net "M_A_DQ62")
	)
	(segment
		(start 130.616198 -66.945002)
		(end 131.3434 -66.2178)
		(width 0.1524)
		(layer "In7.Cu")
		(net "M_A_DQ62")
	)
	(segment
		(start 131.3434 -64.778636)
		(end 130.524504 -63.95974)
		(width 0.1524)
		(layer "In7.Cu")
		(net "M_A_DQ62")
	)
	(segment
		(start 124.662692 -67.639692)
		(end 123.786138 -66.763138)
		(width 0.1524)
		(layer "In7.Cu")
		(net "M_A_DQ62")
	)
	(segment
		(start 100.680266 -67.0306)
		(end 95.831152 -62.181486)
		(width 0.1524)
		(layer "In7.Cu")
		(net "M_A_DQ62")
	)
	(segment
		(start 95.831152 -59.890152)
		(end 94.615 -58.674)
		(width 0.1016)
		(layer "In7.Cu")
		(net "M_A_DQ62")
	)
	(segment
		(start 123.4186 -66.3956)
		(end 117.348 -66.3956)
		(width 0.1524)
		(layer "In7.Cu")
		(net "M_A_DQ62")
	)
	(segment
		(start 123.444 -66.421)
		(end 123.4186 -66.3956)
		(width 0.1524)
		(layer "In7.Cu")
		(net "M_A_DQ62")
	)
	(segment
		(start 116.713 -67.0306)
		(end 100.680266 -67.0306)
		(width 0.1524)
		(layer "In7.Cu")
		(net "M_A_DQ62")
	)
	(segment
		(start 131.3434 -66.2178)
		(end 131.3434 -64.778636)
		(width 0.1524)
		(layer "In7.Cu")
		(net "M_A_DQ62")
	)
	(segment
		(start 130.524504 -63.95974)
		(end 129.69748 -63.95974)
		(width 0.1524)
		(layer "In7.Cu")
		(net "M_A_DQ62")
	)
	(segment
		(start 95.831152 -62.181486)
		(end 95.831152 -59.890152)
		(width 0.1524)
		(layer "In7.Cu")
		(net "M_A_DQ62")
	)
	(segment
		(start 123.444254 -66.421)
		(end 123.444 -66.421)
		(width 0.1524)
		(layer "In7.Cu")
		(net "M_A_DQ62")
	)
	(segment
		(start 88.991694 -41.417494)
		(end 89.3064 -41.7322)
		(width 0.1143)
		(layer "F.Cu")
		(net "CTBTRIGINOUT")
	)
	(segment
		(start 88.920828 -41.417494)
		(end 88.991694 -41.417494)
		(width 0.1143)
		(layer "F.Cu")
		(net "CTBTRIGINOUT")
	)
	(via
		(at 89.3064 -41.7322)
		(size 0.4318)
		(drill 0.2032)
		(layers "F.Cu" "B.Cu")
		(net "CTBTRIGINOUT")
	)
	(via
		(at 90.144346 -41.909492)
		(size 0.7112)
		(drill 0.3556)
		(layers "F.Cu" "B.Cu")
		(net "CTBTRIGINOUT")
	)
	(segment
		(start 89.967054 -41.7322)
		(end 90.144346 -41.909492)
		(width 0.1143)
		(layer "B.Cu")
		(net "CTBTRIGINOUT")
	)
	(segment
		(start 89.3064 -41.7322)
		(end 89.967054 -41.7322)
		(width 0.1143)
		(layer "B.Cu")
		(net "CTBTRIGINOUT")
	)
	(segment
		(start 90.424 -42.189146)
		(end 90.144346 -41.909492)
		(width 0.1143)
		(layer "B.Cu")
		(net "CTBTRIGINOUT")
	)
	(segment
		(start 90.424 -42.8244)
		(end 90.424 -42.189146)
		(width 0.1143)
		(layer "B.Cu")
		(net "CTBTRIGINOUT")
	)
	(via
		(at 84.4296 -21.6916)
		(size 0.7112)
		(drill 0.3556)
		(layers "F.Cu" "B.Cu")
		(net "TPS74801_1V35_SS")
	)
	(segment
		(start 83.6422 -21.59)
		(end 83.7438 -21.6916)
		(width 0.254)
		(layer "B.Cu")
		(net "TPS74801_1V35_SS")
	)
	(segment
		(start 83.7438 -21.6916)
		(end 84.4296 -21.6916)
		(width 0.254)
		(layer "B.Cu")
		(net "TPS74801_1V35_SS")
	)
	(segment
		(start 83.566 -21.5138)
		(end 83.6422 -21.59)
		(width 0.254)
		(layer "B.Cu")
		(net "TPS74801_1V35_SS")
	)
	(segment
		(start 83.566 -20.545044)
		(end 83.566 -21.5138)
		(width 0.254)
		(layer "B.Cu")
		(net "TPS74801_1V35_SS")
	)
	(segment
		(start 104.266746 -41.656254)
		(end 104.5972 -41.3258)
		(width 0.1016)
		(layer "F.Cu")
		(net "M_A_DQ4")
	)
	(segment
		(start 104.242108 -41.656254)
		(end 104.266746 -41.656254)
		(width 0.1016)
		(layer "F.Cu")
		(net "M_A_DQ4")
	)
	(segment
		(start 188.950092 -70.806564)
		(end 188.950092 -69.317108)
		(width 0.1778)
		(layer "F.Cu")
		(net "M_A_DQ4")
	)
	(segment
		(start 188.950092 -69.317108)
		(end 189.0268 -69.2404)
		(width 0.1778)
		(layer "F.Cu")
		(net "M_A_DQ4")
	)
	(via
		(at 189.0268 -69.2404)
		(size 0.4318)
		(drill 0.2032)
		(layers "F.Cu" "B.Cu")
		(net "M_A_DQ4")
	)
	(via
		(at 104.5972 -41.3258)
		(size 0.4318)
		(drill 0.2032)
		(layers "F.Cu" "B.Cu")
		(net "M_A_DQ4")
	)
	(segment
		(start 189.1284 -69.342)
		(end 189.0268 -69.2404)
		(width 0.1778)
		(layer "B.Cu")
		(net "M_A_DQ4")
	)
	(segment
		(start 189.250066 -70.79996)
		(end 189.250066 -70.193916)
		(width 0.1778)
		(layer "B.Cu")
		(net "M_A_DQ4")
	)
	(segment
		(start 189.250066 -70.193916)
		(end 189.1284 -69.342)
		(width 0.1778)
		(layer "B.Cu")
		(net "M_A_DQ4")
	)
	(segment
		(start 159.04972 -42.573702)
		(end 153.871168 -39.671244)
		(width 0.1524)
		(layer "In7.Cu")
		(net "M_A_DQ4")
	)
	(segment
		(start 189.772798 -63.771526)
		(end 186.935872 -60.9346)
		(width 0.1524)
		(layer "In7.Cu")
		(net "M_A_DQ4")
	)
	(segment
		(start 189.772798 -64.643)
		(end 189.772798 -63.771526)
		(width 0.1524)
		(layer "In7.Cu")
		(net "M_A_DQ4")
	)
	(segment
		(start 153.871168 -39.671244)
		(end 151.303482 -39.671244)
		(width 0.1524)
		(layer "In7.Cu")
		(net "M_A_DQ4")
	)
	(segment
		(start 105.6259 -40.5003)
		(end 106.454702 -39.671498)
		(width 0.1016)
		(layer "In7.Cu")
		(net "M_A_DQ4")
	)
	(segment
		(start 104.5972 -41.3258)
		(end 105.6259 -40.5003)
		(width 0.1016)
		(layer "In7.Cu")
		(net "M_A_DQ4")
	)
	(segment
		(start 171.5516 -49.5808)
		(end 159.04972 -42.573702)
		(width 0.1524)
		(layer "In7.Cu")
		(net "M_A_DQ4")
	)
	(segment
		(start 189.0268 -69.2404)
		(end 189.757304 -64.766698)
		(width 0.1524)
		(layer "In7.Cu")
		(net "M_A_DQ4")
	)
	(segment
		(start 186.935872 -60.9346)
		(end 171.5516 -49.5808)
		(width 0.1524)
		(layer "In7.Cu")
		(net "M_A_DQ4")
	)
	(segment
		(start 151.302974 -39.671498)
		(end 112.1918 -39.671498)
		(width 0.1524)
		(layer "In7.Cu")
		(net "M_A_DQ4")
	)
	(segment
		(start 189.757304 -64.766698)
		(end 189.772798 -64.643)
		(width 0.1524)
		(layer "In7.Cu")
		(net "M_A_DQ4")
	)
	(segment
		(start 151.303482 -39.671244)
		(end 151.302974 -39.671498)
		(width 0.1524)
		(layer "In7.Cu")
		(net "M_A_DQ4")
	)
	(segment
		(start 106.454702 -39.671498)
		(end 112.1918 -39.671498)
		(width 0.1016)
		(layer "In7.Cu")
		(net "M_A_DQ4")
	)
	(segment
		(start 64.10198 -42.672)
		(end 64.10198 -41.8084)
		(width 0.1143)
		(layer "F.Cu")
		(net "SMBUS_HOST_R_DATA")
	)
	(segment
		(start 61.341 -42.799)
		(end 61.66485 -43.12285)
		(width 0.1143)
		(layer "F.Cu")
		(net "SMBUS_HOST_R_DATA")
	)
	(segment
		(start 60.9473 -41.9735)
		(end 60.9473 -42.4053)
		(width 0.1143)
		(layer "F.Cu")
		(net "SMBUS_HOST_R_DATA")
	)
	(segment
		(start 61.66485 -43.12285)
		(end 63.65113 -43.12285)
		(width 0.1143)
		(layer "F.Cu")
		(net "SMBUS_HOST_R_DATA")
	)
	(segment
		(start 63.65113 -43.12285)
		(end 64.10198 -42.672)
		(width 0.1143)
		(layer "F.Cu")
		(net "SMBUS_HOST_R_DATA")
	)
	(segment
		(start 60.452 -41.4782)
		(end 60.9473 -41.9735)
		(width 0.1143)
		(layer "F.Cu")
		(net "SMBUS_HOST_R_DATA")
	)
	(segment
		(start 60.9473 -42.4053)
		(end 61.341 -42.799)
		(width 0.1143)
		(layer "F.Cu")
		(net "SMBUS_HOST_R_DATA")
	)
	(via
		(at 61.341 -42.799)
		(size 0.7112)
		(drill 0.3556)
		(layers "F.Cu" "B.Cu")
		(net "SMBUS_HOST_R_DATA")
	)
	(segment
		(start 76.20635 -45.563028)
		(end 75.565 -46.204378)
		(width 0.1143)
		(layer "F.Cu")
		(net "SMB_CLK1_SPKR")
	)
	(segment
		(start 80.17256 -43.151044)
		(end 79.914496 -43.151044)
		(width 0.1143)
		(layer "F.Cu")
		(net "SMB_CLK1_SPKR")
	)
	(segment
		(start 74.4728 -47.117)
		(end 74.652378 -47.117)
		(width 0.1143)
		(layer "F.Cu")
		(net "SMB_CLK1_SPKR")
	)
	(segment
		(start 76.20635 -43.919394)
		(end 76.20635 -45.563028)
		(width 0.1143)
		(layer "F.Cu")
		(net "SMB_CLK1_SPKR")
	)
	(segment
		(start 74.4982 -47.9552)
		(end 74.4982 -47.1424)
		(width 0.1143)
		(layer "F.Cu")
		(net "SMB_CLK1_SPKR")
	)
	(segment
		(start 81.097628 -42.918634)
		(end 80.40497 -42.918634)
		(width 0.1143)
		(layer "F.Cu")
		(net "SMB_CLK1_SPKR")
	)
	(segment
		(start 74.652378 -47.117)
		(end 75.565 -46.204378)
		(width 0.1143)
		(layer "F.Cu")
		(net "SMB_CLK1_SPKR")
	)
	(segment
		(start 80.40497 -42.918634)
		(end 80.17256 -43.151044)
		(width 0.1143)
		(layer "F.Cu")
		(net "SMB_CLK1_SPKR")
	)
	(segment
		(start 79.914496 -43.151044)
		(end 79.79283 -43.029378)
		(width 0.1143)
		(layer "F.Cu")
		(net "SMB_CLK1_SPKR")
	)
	(segment
		(start 77.096366 -43.029378)
		(end 76.20635 -43.919394)
		(width 0.1143)
		(layer "F.Cu")
		(net "SMB_CLK1_SPKR")
	)
	(segment
		(start 79.79283 -43.029378)
		(end 77.096366 -43.029378)
		(width 0.1143)
		(layer "F.Cu")
		(net "SMB_CLK1_SPKR")
	)
	(segment
		(start 74.4982 -47.1424)
		(end 74.4728 -47.117)
		(width 0.1143)
		(layer "F.Cu")
		(net "SMB_CLK1_SPKR")
	)
	(via
		(at 75.565 -46.204378)
		(size 0.7112)
		(drill 0.3556)
		(layers "F.Cu" "B.Cu")
		(net "SMB_CLK1_SPKR")
	)
	(segment
		(start 90.188542 -38.862)
		(end 90.2462 -38.862)
		(width 0.1143)
		(layer "F.Cu")
		(net "RCOMP_CORE_LVT")
	)
	(segment
		(start 90.2462 -38.862)
		(end 90.2716 -38.8366)
		(width 0.1143)
		(layer "F.Cu")
		(net "RCOMP_CORE_LVT")
	)
	(segment
		(start 89.850468 -39.200074)
		(end 90.188542 -38.862)
		(width 0.1143)
		(layer "F.Cu")
		(net "RCOMP_CORE_LVT")
	)
	(via
		(at 88.258904 -38.91534)
		(size 0.7112)
		(drill 0.3556)
		(layers "F.Cu" "B.Cu")
		(net "RCOMP_CORE_LVT")
	)
	(via
		(at 90.2716 -38.8366)
		(size 0.4318)
		(drill 0.2032)
		(layers "F.Cu" "B.Cu")
		(net "RCOMP_CORE_LVT")
	)
	(segment
		(start 89.482168 -38.8112)
		(end 89.177368 -38.5064)
		(width 0.1143)
		(layer "B.Cu")
		(net "RCOMP_CORE_LVT")
	)
	(segment
		(start 89.177368 -38.5064)
		(end 88.66886 -38.5064)
		(width 0.1143)
		(layer "B.Cu")
		(net "RCOMP_CORE_LVT")
	)
	(segment
		(start 90.2716 -38.8366)
		(end 90.2462 -38.8112)
		(width 0.1143)
		(layer "B.Cu")
		(net "RCOMP_CORE_LVT")
	)
	(segment
		(start 88.25992 -38.91534)
		(end 88.258904 -38.91534)
		(width 0.1143)
		(layer "B.Cu")
		(net "RCOMP_CORE_LVT")
	)
	(segment
		(start 88.66886 -38.5064)
		(end 88.25992 -38.91534)
		(width 0.1143)
		(layer "B.Cu")
		(net "RCOMP_CORE_LVT")
	)
	(segment
		(start 89.662 -38.8112)
		(end 89.482168 -38.8112)
		(width 0.1143)
		(layer "B.Cu")
		(net "RCOMP_CORE_LVT")
	)
	(segment
		(start 90.2462 -38.8112)
		(end 89.662 -38.8112)
		(width 0.1143)
		(layer "B.Cu")
		(net "RCOMP_CORE_LVT")
	)
	(segment
		(start 89.847674 -44.000674)
		(end 89.4842 -43.6372)
		(width 0.254)
		(layer "F.Cu")
		(net "P1V8_STBY")
	)
	(segment
		(start 89.850468 -44.000674)
		(end 89.847674 -44.000674)
		(width 0.254)
		(layer "F.Cu")
		(net "P1V8_STBY")
	)
	(segment
		(start 91.823032 -37.973)
		(end 91.821 -37.973)
		(width 0.254)
		(layer "F.Cu")
		(net "P1V8_STBY")
	)
	(segment
		(start 89.4842 -43.6372)
		(end 89.4588 -43.6372)
		(width 0.254)
		(layer "F.Cu")
		(net "P1V8_STBY")
	)
	(segment
		(start 60.86602 -29.0322)
		(end 59.9694 -29.0322)
		(width 0.635)
		(layer "F.Cu")
		(net "P1V8_STBY")
	)
	(segment
		(start 61.10351 -28.79471)
		(end 60.86602 -29.0322)
		(width 0.635)
		(layer "F.Cu")
		(net "P1V8_STBY")
	)
	(segment
		(start 89.124028 -43.971972)
		(end 89.4588 -43.6372)
		(width 0.254)
		(layer "F.Cu")
		(net "P1V8_STBY")
	)
	(segment
		(start 92.248228 -38.398196)
		(end 91.823032 -37.973)
		(width 0.254)
		(layer "F.Cu")
		(net "P1V8_STBY")
	)
	(segment
		(start 89.124028 -44.000674)
		(end 89.124028 -43.971972)
		(width 0.254)
		(layer "F.Cu")
		(net "P1V8_STBY")
	)
	(segment
		(start 92.248228 -38.399974)
		(end 92.248228 -38.398196)
		(width 0.254)
		(layer "F.Cu")
		(net "P1V8_STBY")
	)
	(segment
		(start 91.821 -38.029642)
		(end 91.821 -37.973)
		(width 0.254)
		(layer "F.Cu")
		(net "P1V8_STBY")
	)
	(segment
		(start 91.450668 -38.399974)
		(end 91.821 -38.029642)
		(width 0.254)
		(layer "F.Cu")
		(net "P1V8_STBY")
	)
	(via
		(at 65.6336 -16.6624)
		(size 0.7112)
		(drill 0.4064)
		(layers "F.Cu" "B.Cu")
		(net "P1V8_STBY")
	)
	(via
		(at 20.828 -45.085)
		(size 0.7112)
		(drill 0.4064)
		(layers "F.Cu" "B.Cu")
		(net "P1V8_STBY")
	)
	(via
		(at 89.4588 -43.6372)
		(size 0.4318)
		(drill 0.2032)
		(layers "F.Cu" "B.Cu")
		(net "P1V8_STBY")
	)
	(via
		(at 61.10351 -28.79471)
		(size 0.7112)
		(drill 0.4064)
		(layers "F.Cu" "B.Cu")
		(net "P1V8_STBY")
	)
	(via
		(at 78.036674 -41.670986)
		(size 0.508)
		(drill 0.254)
		(layers "F.Cu" "B.Cu")
		(net "P1V8_STBY")
	)
	(via
		(at 76.1492 -20.9042)
		(size 0.508)
		(drill 0.254)
		(layers "F.Cu" "B.Cu")
		(net "P1V8_STBY")
	)
	(via
		(at 30.099 -31.877)
		(size 0.508)
		(drill 0.254)
		(layers "F.Cu" "B.Cu")
		(net "P1V8_STBY")
	)
	(via
		(at 21.519388 -46.792388)
		(size 0.7112)
		(drill 0.3556)
		(layers "F.Cu" "B.Cu")
		(net "P1V8_STBY")
	)
	(via
		(at 91.821 -37.973)
		(size 0.4318)
		(drill 0.2032)
		(layers "F.Cu" "B.Cu")
		(net "P1V8_STBY")
	)
	(segment
		(start 89.535 -43.7134)
		(end 89.4588 -43.6372)
		(width 0.3048)
		(layer "B.Cu")
		(net "P1V8_STBY")
	)
	(segment
		(start 89.535 -44.1198)
		(end 89.535 -43.7134)
		(width 0.3048)
		(layer "B.Cu")
		(net "P1V8_STBY")
	)
	(segment
		(start 21.519388 -46.792388)
		(end 20.828 -46.101)
		(width 0.635)
		(layer "B.Cu")
		(net "P1V8_STBY")
	)
	(segment
		(start 23.749 -49.022)
		(end 21.519388 -46.792388)
		(width 0.635)
		(layer "B.Cu")
		(net "P1V8_STBY")
	)
	(segment
		(start 76.1492 -20.9042)
		(end 76.1492 -19.8882)
		(width 0.508)
		(layer "B.Cu")
		(net "P1V8_STBY")
	)
	(segment
		(start 20.828 -46.101)
		(end 20.828 -45.085)
		(width 0.635)
		(layer "B.Cu")
		(net "P1V8_STBY")
	)
	(segment
		(start 24.1046 -49.022)
		(end 23.749 -49.022)
		(width 0.635)
		(layer "B.Cu")
		(net "P1V8_STBY")
	)
	(segment
		(start 76.1492 -19.8882)
		(end 76.3016 -19.7358)
		(width 0.508)
		(layer "B.Cu")
		(net "P1V8_STBY")
	)
	(segment
		(start 61.5188 -25.941274)
		(end 61.4553 -25.877774)
		(width 0.635)
		(layer "In2.Cu")
		(net "P1V8_STBY")
	)
	(segment
		(start 89.8525 -40.72128)
		(end 89.8525 -43.2435)
		(width 0.254)
		(layer "In2.Cu")
		(net "P1V8_STBY")
	)
	(segment
		(start 65.6082 -16.6878)
		(end 65.6336 -16.6624)
		(width 0.635)
		(layer "In2.Cu")
		(net "P1V8_STBY")
	)
	(segment
		(start 82.270854 -43.111928)
		(end 82.796126 -43.6372)
		(width 0.381)
		(layer "In2.Cu")
		(net "P1V8_STBY")
	)
	(segment
		(start 79.477616 -43.111928)
		(end 82.270854 -43.111928)
		(width 0.381)
		(layer "In2.Cu")
		(net "P1V8_STBY")
	)
	(segment
		(start 62.1792 -24.553926)
		(end 62.1792 -22.668484)
		(width 0.635)
		(layer "In2.Cu")
		(net "P1V8_STBY")
	)
	(segment
		(start 65.6082 -19.239484)
		(end 65.6082 -16.6878)
		(width 0.635)
		(layer "In2.Cu")
		(net "P1V8_STBY")
	)
	(segment
		(start 90.8558 -36.399978)
		(end 90.441018 -35.985196)
		(width 0.254)
		(layer "In2.Cu")
		(net "P1V8_STBY")
	)
	(segment
		(start 61.4553 -25.277826)
		(end 62.1792 -24.553926)
		(width 0.635)
		(layer "In2.Cu")
		(net "P1V8_STBY")
	)
	(segment
		(start 82.796126 -43.6372)
		(end 89.4588 -43.6372)
		(width 0.381)
		(layer "In2.Cu")
		(net "P1V8_STBY")
	)
	(segment
		(start 78.036674 -41.670986)
		(end 79.477616 -43.111928)
		(width 0.381)
		(layer "In2.Cu")
		(net "P1V8_STBY")
	)
	(segment
		(start 91.821 -37.973)
		(end 91.722956 -37.973)
		(width 0.254)
		(layer "In2.Cu")
		(net "P1V8_STBY")
	)
	(segment
		(start 90.441018 -35.985196)
		(end 90.072718 -35.985196)
		(width 0.254)
		(layer "In2.Cu")
		(net "P1V8_STBY")
	)
	(segment
		(start 89.80424 -40.67302)
		(end 89.8525 -40.72128)
		(width 0.254)
		(layer "In2.Cu")
		(net "P1V8_STBY")
	)
	(segment
		(start 89.80424 -36.253674)
		(end 89.80424 -40.67302)
		(width 0.254)
		(layer "In2.Cu")
		(net "P1V8_STBY")
	)
	(segment
		(start 61.10351 -28.79471)
		(end 61.5188 -28.37942)
		(width 0.635)
		(layer "In2.Cu")
		(net "P1V8_STBY")
	)
	(segment
		(start 62.1792 -22.668484)
		(end 65.6082 -19.239484)
		(width 0.635)
		(layer "In2.Cu")
		(net "P1V8_STBY")
	)
	(segment
		(start 89.8525 -43.2435)
		(end 89.4588 -43.6372)
		(width 0.254)
		(layer "In2.Cu")
		(net "P1V8_STBY")
	)
	(segment
		(start 61.5188 -28.37942)
		(end 61.5188 -25.941274)
		(width 0.635)
		(layer "In2.Cu")
		(net "P1V8_STBY")
	)
	(segment
		(start 91.722956 -37.973)
		(end 90.8558 -37.105844)
		(width 0.254)
		(layer "In2.Cu")
		(net "P1V8_STBY")
	)
	(segment
		(start 90.8558 -37.105844)
		(end 90.8558 -36.399978)
		(width 0.254)
		(layer "In2.Cu")
		(net "P1V8_STBY")
	)
	(segment
		(start 90.072718 -35.985196)
		(end 89.80424 -36.253674)
		(width 0.254)
		(layer "In2.Cu")
		(net "P1V8_STBY")
	)
	(segment
		(start 61.4553 -25.877774)
		(end 61.4553 -25.277826)
		(width 0.635)
		(layer "In2.Cu")
		(net "P1V8_STBY")
	)
	(segment
		(start 29.9085 -34.142426)
		(end 30.099 -33.951926)
		(width 0.635)
		(layer "In4.Cu")
		(net "P1V8_STBY")
	)
	(segment
		(start 28.621228 -35.1917)
		(end 29.107638 -35.1917)
		(width 0.635)
		(layer "In4.Cu")
		(net "P1V8_STBY")
	)
	(segment
		(start 20.828 -44.9326)
		(end 27.7241 -38.0365)
		(width 0.635)
		(layer "In4.Cu")
		(net "P1V8_STBY")
	)
	(segment
		(start 29.9085 -34.390838)
		(end 29.9085 -34.142426)
		(width 0.635)
		(layer "In4.Cu")
		(net "P1V8_STBY")
	)
	(segment
		(start 29.107638 -35.1917)
		(end 29.9085 -34.390838)
		(width 0.635)
		(layer "In4.Cu")
		(net "P1V8_STBY")
	)
	(segment
		(start 30.099 -33.951926)
		(end 30.099 -31.877)
		(width 0.635)
		(layer "In4.Cu")
		(net "P1V8_STBY")
	)
	(segment
		(start 27.7241 -38.0365)
		(end 27.7241 -36.088828)
		(width 0.635)
		(layer "In4.Cu")
		(net "P1V8_STBY")
	)
	(segment
		(start 20.828 -45.085)
		(end 20.828 -44.9326)
		(width 0.635)
		(layer "In4.Cu")
		(net "P1V8_STBY")
	)
	(segment
		(start 27.7241 -36.088828)
		(end 28.621228 -35.1917)
		(width 0.635)
		(layer "In4.Cu")
		(net "P1V8_STBY")
	)
	(segment
		(start 65.6336 -16.6624)
		(end 66.268854 -16.6624)
		(width 0.508)
		(layer "In7.Cu")
		(net "P1V8_STBY")
	)
	(segment
		(start 55.8546 -27.6606)
		(end 51.943 -27.6606)
		(width 0.635)
		(layer "In7.Cu")
		(net "P1V8_STBY")
	)
	(segment
		(start 44.162726 -20.4597)
		(end 44.124626 -20.4597)
		(width 0.635)
		(layer "In7.Cu")
		(net "P1V8_STBY")
	)
	(segment
		(start 33.17875 -16.17345)
		(end 29.5021 -19.8501)
		(width 0.635)
		(layer "In7.Cu")
		(net "P1V8_STBY")
	)
	(segment
		(start 74.9808 -20.9042)
		(end 76.1492 -20.9042)
		(width 0.508)
		(layer "In7.Cu")
		(net "P1V8_STBY")
	)
	(segment
		(start 29.5021 -31.2801)
		(end 30.099 -31.877)
		(width 0.635)
		(layer "In7.Cu")
		(net "P1V8_STBY")
	)
	(segment
		(start 29.5021 -19.8501)
		(end 29.5021 -31.2801)
		(width 0.635)
		(layer "In7.Cu")
		(net "P1V8_STBY")
	)
	(segment
		(start 39.774876 -16.10995)
		(end 35.8775 -16.10995)
		(width 0.635)
		(layer "In7.Cu")
		(net "P1V8_STBY")
	)
	(segment
		(start 70.757796 -16.681196)
		(end 74.9808 -20.9042)
		(width 0.508)
		(layer "In7.Cu")
		(net "P1V8_STBY")
	)
	(segment
		(start 66.28765 -16.681196)
		(end 70.757796 -16.681196)
		(width 0.508)
		(layer "In7.Cu")
		(net "P1V8_STBY")
	)
	(segment
		(start 51.943 -27.6606)
		(end 51.435 -27.1526)
		(width 0.635)
		(layer "In7.Cu")
		(net "P1V8_STBY")
	)
	(segment
		(start 35.814 -16.17345)
		(end 33.17875 -16.17345)
		(width 0.635)
		(layer "In7.Cu")
		(net "P1V8_STBY")
	)
	(segment
		(start 56.98871 -28.79471)
		(end 55.8546 -27.6606)
		(width 0.635)
		(layer "In7.Cu")
		(net "P1V8_STBY")
	)
	(segment
		(start 51.435 -27.1526)
		(end 49.46396 -27.1526)
		(width 0.635)
		(layer "In7.Cu")
		(net "P1V8_STBY")
	)
	(segment
		(start 49.46396 -27.1526)
		(end 47.293276 -24.981916)
		(width 0.635)
		(layer "In7.Cu")
		(net "P1V8_STBY")
	)
	(segment
		(start 44.124626 -20.4597)
		(end 39.774876 -16.10995)
		(width 0.635)
		(layer "In7.Cu")
		(net "P1V8_STBY")
	)
	(segment
		(start 66.268854 -16.6624)
		(end 66.28765 -16.681196)
		(width 0.508)
		(layer "In7.Cu")
		(net "P1V8_STBY")
	)
	(segment
		(start 35.8775 -16.10995)
		(end 35.814 -16.17345)
		(width 0.635)
		(layer "In7.Cu")
		(net "P1V8_STBY")
	)
	(segment
		(start 47.293276 -24.981916)
		(end 47.293276 -23.59025)
		(width 0.635)
		(layer "In7.Cu")
		(net "P1V8_STBY")
	)
	(segment
		(start 61.10351 -28.79471)
		(end 56.98871 -28.79471)
		(width 0.635)
		(layer "In7.Cu")
		(net "P1V8_STBY")
	)
	(segment
		(start 47.293276 -23.59025)
		(end 44.162726 -20.4597)
		(width 0.635)
		(layer "In7.Cu")
		(net "P1V8_STBY")
	)
	(segment
		(start 76.7461 -21.5011)
		(end 76.7461 -22.079204)
		(width 0.381)
		(layer "In9.Cu")
		(net "P1V8_STBY")
	)
	(segment
		(start 76.454 -23.077932)
		(end 76.0476 -23.484332)
		(width 0.381)
		(layer "In9.Cu")
		(net "P1V8_STBY")
	)
	(segment
		(start 76.0476 -24.13)
		(end 75.4761 -24.7015)
		(width 0.381)
		(layer "In9.Cu")
		(net "P1V8_STBY")
	)
	(segment
		(start 75.4761 -25.4508)
		(end 75.873356 -25.848056)
		(width 0.381)
		(layer "In9.Cu")
		(net "P1V8_STBY")
	)
	(segment
		(start 76.1492 -20.9042)
		(end 76.7461 -21.5011)
		(width 0.381)
		(layer "In9.Cu")
		(net "P1V8_STBY")
	)
	(segment
		(start 76.7461 -22.079204)
		(end 76.454 -22.371304)
		(width 0.381)
		(layer "In9.Cu")
		(net "P1V8_STBY")
	)
	(segment
		(start 76.962 -40.066722)
		(end 78.036674 -41.141396)
		(width 0.381)
		(layer "In9.Cu")
		(net "P1V8_STBY")
	)
	(segment
		(start 75.873356 -35.555428)
		(end 75.8317 -35.597084)
		(width 0.381)
		(layer "In9.Cu")
		(net "P1V8_STBY")
	)
	(segment
		(start 75.8317 -35.597084)
		(end 75.8317 -37.246052)
		(width 0.381)
		(layer "In9.Cu")
		(net "P1V8_STBY")
	)
	(segment
		(start 75.4761 -24.7015)
		(end 75.4761 -25.4508)
		(width 0.381)
		(layer "In9.Cu")
		(net "P1V8_STBY")
	)
	(segment
		(start 76.0476 -23.484332)
		(end 76.0476 -24.13)
		(width 0.381)
		(layer "In9.Cu")
		(net "P1V8_STBY")
	)
	(segment
		(start 76.454 -22.371304)
		(end 76.454 -23.077932)
		(width 0.381)
		(layer "In9.Cu")
		(net "P1V8_STBY")
	)
	(segment
		(start 75.873356 -25.848056)
		(end 75.873356 -35.555428)
		(width 0.381)
		(layer "In9.Cu")
		(net "P1V8_STBY")
	)
	(segment
		(start 78.036674 -41.141396)
		(end 78.036674 -41.670986)
		(width 0.381)
		(layer "In9.Cu")
		(net "P1V8_STBY")
	)
	(segment
		(start 76.962 -38.376352)
		(end 76.962 -40.066722)
		(width 0.381)
		(layer "In9.Cu")
		(net "P1V8_STBY")
	)
	(segment
		(start 75.8317 -37.246052)
		(end 76.962 -38.376352)
		(width 0.381)
		(layer "In9.Cu")
		(net "P1V8_STBY")
	)
	(segment
		(start 177.550064 -70.806564)
		(end 177.550064 -70.088252)
		(width 0.1778)
		(layer "F.Cu")
		(net "M_A_DQS_DN2")
	)
	(segment
		(start 107.290108 -44.927774)
		(end 107.64393 -45.281596)
		(width 0.1016)
		(layer "F.Cu")
		(net "M_A_DQS_DN2")
	)
	(segment
		(start 177.550064 -70.088252)
		(end 177.40249 -69.940678)
		(width 0.1778)
		(layer "F.Cu")
		(net "M_A_DQS_DN2")
	)
	(segment
		(start 177.40249 -66.936874)
		(end 177.667158 -66.672206)
		(width 0.1778)
		(layer "F.Cu")
		(net "M_A_DQS_DN2")
	)
	(segment
		(start 107.64393 -45.281596)
		(end 107.655868 -45.281596)
		(width 0.1016)
		(layer "F.Cu")
		(net "M_A_DQS_DN2")
	)
	(segment
		(start 177.40249 -69.940678)
		(end 177.40249 -66.936874)
		(width 0.1778)
		(layer "F.Cu")
		(net "M_A_DQS_DN2")
	)
	(via
		(at 107.655868 -45.281596)
		(size 0.4318)
		(drill 0.2032)
		(layers "F.Cu" "B.Cu")
		(net "M_A_DQS_DN2")
	)
	(via
		(at 177.667158 -66.672206)
		(size 0.4318)
		(drill 0.2032)
		(layers "F.Cu" "B.Cu")
		(net "M_A_DQS_DN2")
	)
	(segment
		(start 177.29327 -63.632334)
		(end 177.29327 -64.26327)
		(width 0.1778)
		(layer "B.Cu")
		(net "M_A_DQS_DN2")
	)
	(segment
		(start 177.550064 -63.37554)
		(end 177.29327 -63.632334)
		(width 0.1778)
		(layer "B.Cu")
		(net "M_A_DQS_DN2")
	)
	(segment
		(start 177.4952 -66.500248)
		(end 177.667158 -66.672206)
		(width 0.1778)
		(layer "B.Cu")
		(net "M_A_DQS_DN2")
	)
	(segment
		(start 177.29327 -64.26327)
		(end 177.4952 -64.4652)
		(width 0.1778)
		(layer "B.Cu")
		(net "M_A_DQS_DN2")
	)
	(segment
		(start 177.550064 -62.599824)
		(end 177.550064 -63.37554)
		(width 0.1778)
		(layer "B.Cu")
		(net "M_A_DQS_DN2")
	)
	(segment
		(start 177.4952 -64.4652)
		(end 177.4952 -66.500248)
		(width 0.1778)
		(layer "B.Cu")
		(net "M_A_DQS_DN2")
	)
	(segment
		(start 143.12392 -49.8094)
		(end 122.791728 -49.8094)
		(width 0.1524)
		(layer "In4.Cu")
		(net "M_A_DQS_DN2")
	)
	(segment
		(start 165.450774 -58.352436)
		(end 162.825938 -55.7276)
		(width 0.1524)
		(layer "In4.Cu")
		(net "M_A_DQS_DN2")
	)
	(segment
		(start 177.667158 -66.672206)
		(end 177.31359 -66.318638)
		(width 0.1524)
		(layer "In4.Cu")
		(net "M_A_DQS_DN2")
	)
	(segment
		(start 149.0472 -52.081176)
		(end 148.451824 -51.4858)
		(width 0.1524)
		(layer "In4.Cu")
		(net "M_A_DQS_DN2")
	)
	(segment
		(start 170.583352 -61.4172)
		(end 167.518588 -58.352436)
		(width 0.1524)
		(layer "In4.Cu")
		(net "M_A_DQS_DN2")
	)
	(segment
		(start 112.1537 -49.134522)
		(end 112.0267 -49.007522)
		(width 0.1524)
		(layer "In4.Cu")
		(net "M_A_DQS_DN2")
	)
	(segment
		(start 111.088678 -47.62881)
		(end 111.070898 -47.61103)
		(width 0.1016)
		(layer "In4.Cu")
		(net "M_A_DQS_DN2")
	)
	(segment
		(start 144.80032 -51.4858)
		(end 143.12392 -49.8094)
		(width 0.1524)
		(layer "In4.Cu")
		(net "M_A_DQS_DN2")
	)
	(segment
		(start 107.186984 -46.252384)
		(end 107.186984 -45.873416)
		(width 0.1016)
		(layer "In4.Cu")
		(net "M_A_DQS_DN2")
	)
	(segment
		(start 167.518588 -58.352436)
		(end 165.450774 -58.352436)
		(width 0.1524)
		(layer "In4.Cu")
		(net "M_A_DQS_DN2")
	)
	(segment
		(start 177.31359 -66.318638)
		(end 177.31359 -63.508128)
		(width 0.1524)
		(layer "In4.Cu")
		(net "M_A_DQS_DN2")
	)
	(segment
		(start 112.0267 -49.007522)
		(end 112.0267 -48.566832)
		(width 0.1524)
		(layer "In4.Cu")
		(net "M_A_DQS_DN2")
	)
	(segment
		(start 110.865666 -47.459138)
		(end 110.408466 -47.459138)
		(width 0.1016)
		(layer "In4.Cu")
		(net "M_A_DQS_DN2")
	)
	(segment
		(start 112.1537 -50.087276)
		(end 112.1537 -49.134522)
		(width 0.1524)
		(layer "In4.Cu")
		(net "M_A_DQS_DN2")
	)
	(segment
		(start 116.901976 -51.562)
		(end 113.628424 -51.562)
		(width 0.1524)
		(layer "In4.Cu")
		(net "M_A_DQS_DN2")
	)
	(segment
		(start 122.791728 -49.8094)
		(end 122.334528 -50.2666)
		(width 0.1524)
		(layer "In4.Cu")
		(net "M_A_DQS_DN2")
	)
	(segment
		(start 148.451824 -51.4858)
		(end 144.80032 -51.4858)
		(width 0.1524)
		(layer "In4.Cu")
		(net "M_A_DQS_DN2")
	)
	(segment
		(start 107.45216 -46.51756)
		(end 107.186984 -46.252384)
		(width 0.1016)
		(layer "In4.Cu")
		(net "M_A_DQS_DN2")
	)
	(segment
		(start 110.408466 -47.459138)
		(end 109.466888 -46.51756)
		(width 0.1016)
		(layer "In4.Cu")
		(net "M_A_DQS_DN2")
	)
	(segment
		(start 151.753824 -55.7276)
		(end 149.0472 -53.020976)
		(width 0.1524)
		(layer "In4.Cu")
		(net "M_A_DQS_DN2")
	)
	(segment
		(start 111.017558 -47.61103)
		(end 110.865666 -47.459138)
		(width 0.1016)
		(layer "In4.Cu")
		(net "M_A_DQS_DN2")
	)
	(segment
		(start 107.336336 -45.724064)
		(end 107.336336 -45.601128)
		(width 0.1016)
		(layer "In4.Cu")
		(net "M_A_DQS_DN2")
	)
	(segment
		(start 113.628424 -51.562)
		(end 112.1537 -50.087276)
		(width 0.1524)
		(layer "In4.Cu")
		(net "M_A_DQS_DN2")
	)
	(segment
		(start 177.31359 -63.508128)
		(end 175.222662 -61.4172)
		(width 0.1524)
		(layer "In4.Cu")
		(net "M_A_DQS_DN2")
	)
	(segment
		(start 112.0267 -48.566832)
		(end 111.088678 -47.62881)
		(width 0.1524)
		(layer "In4.Cu")
		(net "M_A_DQS_DN2")
	)
	(segment
		(start 118.197376 -50.2666)
		(end 116.901976 -51.562)
		(width 0.1524)
		(layer "In4.Cu")
		(net "M_A_DQS_DN2")
	)
	(segment
		(start 107.186984 -45.873416)
		(end 107.336336 -45.724064)
		(width 0.1016)
		(layer "In4.Cu")
		(net "M_A_DQS_DN2")
	)
	(segment
		(start 162.825938 -55.7276)
		(end 151.753824 -55.7276)
		(width 0.1524)
		(layer "In4.Cu")
		(net "M_A_DQS_DN2")
	)
	(segment
		(start 109.466888 -46.51756)
		(end 107.45216 -46.51756)
		(width 0.1016)
		(layer "In4.Cu")
		(net "M_A_DQS_DN2")
	)
	(segment
		(start 122.334528 -50.2666)
		(end 118.197376 -50.2666)
		(width 0.1524)
		(layer "In4.Cu")
		(net "M_A_DQS_DN2")
	)
	(segment
		(start 107.336336 -45.601128)
		(end 107.655868 -45.281596)
		(width 0.1016)
		(layer "In4.Cu")
		(net "M_A_DQS_DN2")
	)
	(segment
		(start 175.222662 -61.4172)
		(end 170.583352 -61.4172)
		(width 0.1524)
		(layer "In4.Cu")
		(net "M_A_DQS_DN2")
	)
	(segment
		(start 149.0472 -53.020976)
		(end 149.0472 -52.081176)
		(width 0.1524)
		(layer "In4.Cu")
		(net "M_A_DQS_DN2")
	)
	(segment
		(start 111.070898 -47.61103)
		(end 111.017558 -47.61103)
		(width 0.1016)
		(layer "In4.Cu")
		(net "M_A_DQS_DN2")
	)
	(via
		(at 85.6742 -22.352)
		(size 0.7112)
		(drill 0.3556)
		(layers "F.Cu" "B.Cu")
		(net "TPS74801_1V35_FB")
	)
	(segment
		(start 85.6488 -19.939)
		(end 85.207094 -19.497294)
		(width 0.254)
		(layer "B.Cu")
		(net "TPS74801_1V35_FB")
	)
	(segment
		(start 85.207094 -19.497294)
		(end 84.61375 -19.497294)
		(width 0.254)
		(layer "B.Cu")
		(net "TPS74801_1V35_FB")
	)
	(segment
		(start 85.6742 -21.463)
		(end 85.6742 -20.701)
		(width 0.254)
		(layer "B.Cu")
		(net "TPS74801_1V35_FB")
	)
	(segment
		(start 85.6742 -21.463)
		(end 85.6742 -22.352)
		(width 0.254)
		(layer "B.Cu")
		(net "TPS74801_1V35_FB")
	)
	(segment
		(start 85.6742 -19.9644)
		(end 85.6488 -19.939)
		(width 0.254)
		(layer "B.Cu")
		(net "TPS74801_1V35_FB")
	)
	(segment
		(start 85.6742 -20.701)
		(end 85.6742 -19.9644)
		(width 0.254)
		(layer "B.Cu")
		(net "TPS74801_1V35_FB")
	)
	(segment
		(start 188.650118 -62.59322)
		(end 188.650118 -64.079882)
		(width 0.1778)
		(layer "F.Cu")
		(net "M_A_DQ1")
	)
	(segment
		(start 105.301288 -42.141902)
		(end 105.301288 -42.121074)
		(width 0.1016)
		(layer "F.Cu")
		(net "M_A_DQ1")
	)
	(segment
		(start 188.650118 -64.079882)
		(end 188.35624 -64.37376)
		(width 0.1778)
		(layer "F.Cu")
		(net "M_A_DQ1")
	)
	(segment
		(start 105.301288 -42.121074)
		(end 105.766108 -41.656254)
		(width 0.1016)
		(layer "F.Cu")
		(net "M_A_DQ1")
	)
	(segment
		(start 188.35624 -64.37376)
		(end 188.35624 -64.77)
		(width 0.1778)
		(layer "F.Cu")
		(net "M_A_DQ1")
	)
	(via
		(at 105.301288 -42.141902)
		(size 0.4318)
		(drill 0.2032)
		(layers "F.Cu" "B.Cu")
		(net "M_A_DQ1")
	)
	(via
		(at 188.35624 -64.77)
		(size 0.4318)
		(drill 0.2032)
		(layers "F.Cu" "B.Cu")
		(net "M_A_DQ1")
	)
	(segment
		(start 188.350144 -62.599824)
		(end 188.350144 -64.763904)
		(width 0.1778)
		(layer "B.Cu")
		(net "M_A_DQ1")
	)
	(segment
		(start 188.350144 -64.763904)
		(end 188.35624 -64.77)
		(width 0.1778)
		(layer "B.Cu")
		(net "M_A_DQ1")
	)
	(segment
		(start 164.385244 -49.522634)
		(end 164.79901 -49.9364)
		(width 0.1524)
		(layer "In7.Cu")
		(net "M_A_DQ1")
	)
	(segment
		(start 106.48569 -41.458642)
		(end 106.48569 -40.551354)
		(width 0.1016)
		(layer "In7.Cu")
		(net "M_A_DQ1")
	)
	(segment
		(start 111.517176 -41.335198)
		(end 112.0648 -41.335198)
		(width 0.1016)
		(layer "In7.Cu")
		(net "M_A_DQ1")
	)
	(segment
		(start 168.406572 -52.353972)
		(end 168.621964 -52.353972)
		(width 0.1524)
		(layer "In7.Cu")
		(net "M_A_DQ1")
	)
	(segment
		(start 174.636938 -54.4068)
		(end 178.497738 -58.2676)
		(width 0.1524)
		(layer "In7.Cu")
		(net "M_A_DQ1")
	)
	(segment
		(start 188.468 -63.999872)
		(end 188.468 -64.65824)
		(width 0.1524)
		(layer "In7.Cu")
		(net "M_A_DQ1")
	)
	(segment
		(start 164.777674 -48.914812)
		(end 164.385244 -49.307242)
		(width 0.1524)
		(layer "In7.Cu")
		(net "M_A_DQ1")
	)
	(segment
		(start 163.73856 -48.87595)
		(end 163.953952 -48.87595)
		(width 0.1524)
		(layer "In7.Cu")
		(net "M_A_DQ1")
	)
	(segment
		(start 164.561774 -48.48352)
		(end 164.777674 -48.69942)
		(width 0.1524)
		(layer "In7.Cu")
		(net "M_A_DQ1")
	)
	(segment
		(start 167.0812 -49.9364)
		(end 168.52138 -51.37658)
		(width 0.1524)
		(layer "In7.Cu")
		(net "M_A_DQ1")
	)
	(segment
		(start 119.021098 -41.424098)
		(end 153.166318 -41.424098)
		(width 0.1524)
		(layer "In7.Cu")
		(net "M_A_DQ1")
	)
	(segment
		(start 184.8358 -61.444378)
		(end 185.887868 -62.142878)
		(width 0.1524)
		(layer "In7.Cu")
		(net "M_A_DQ1")
	)
	(segment
		(start 169.168064 -52.023264)
		(end 169.5958 -52.451)
		(width 0.1524)
		(layer "In7.Cu")
		(net "M_A_DQ1")
	)
	(segment
		(start 106.48569 -40.551354)
		(end 106.755946 -40.281098)
		(width 0.1016)
		(layer "In7.Cu")
		(net "M_A_DQ1")
	)
	(segment
		(start 110.89005 -40.708072)
		(end 111.517176 -41.335198)
		(width 0.1016)
		(layer "In7.Cu")
		(net "M_A_DQ1")
	)
	(segment
		(start 153.166318 -41.424098)
		(end 159.57042 -47.8282)
		(width 0.1524)
		(layer "In7.Cu")
		(net "M_A_DQ1")
	)
	(segment
		(start 110.89005 -40.519096)
		(end 110.89005 -40.708072)
		(width 0.1016)
		(layer "In7.Cu")
		(net "M_A_DQ1")
	)
	(segment
		(start 185.887868 -62.142878)
		(end 185.91784 -62.142878)
		(width 0.1524)
		(layer "In7.Cu")
		(net "M_A_DQ1")
	)
	(segment
		(start 118.4656 -40.8686)
		(end 119.021098 -41.424098)
		(width 0.1524)
		(layer "In7.Cu")
		(net "M_A_DQ1")
	)
	(segment
		(start 168.190672 -52.138072)
		(end 168.406572 -52.353972)
		(width 0.1524)
		(layer "In7.Cu")
		(net "M_A_DQ1")
	)
	(segment
		(start 110.652052 -40.281098)
		(end 110.89005 -40.519096)
		(width 0.1016)
		(layer "In7.Cu")
		(net "M_A_DQ1")
	)
	(segment
		(start 105.80243 -42.141902)
		(end 106.48569 -41.458642)
		(width 0.1016)
		(layer "In7.Cu")
		(net "M_A_DQ1")
	)
	(segment
		(start 185.91784 -62.142878)
		(end 188.276992 -63.808864)
		(width 0.1524)
		(layer "In7.Cu")
		(net "M_A_DQ1")
	)
	(segment
		(start 112.842802 -41.335198)
		(end 113.3094 -40.8686)
		(width 0.1524)
		(layer "In7.Cu")
		(net "M_A_DQ1")
	)
	(segment
		(start 168.952672 -52.023264)
		(end 169.168064 -52.023264)
		(width 0.1524)
		(layer "In7.Cu")
		(net "M_A_DQ1")
	)
	(segment
		(start 164.346382 -48.48352)
		(end 164.561774 -48.48352)
		(width 0.1524)
		(layer "In7.Cu")
		(net "M_A_DQ1")
	)
	(segment
		(start 169.5958 -52.451)
		(end 171.3738 -52.451)
		(width 0.1524)
		(layer "In7.Cu")
		(net "M_A_DQ1")
	)
	(segment
		(start 164.777674 -48.69942)
		(end 164.777674 -48.914812)
		(width 0.1524)
		(layer "In7.Cu")
		(net "M_A_DQ1")
	)
	(segment
		(start 178.497738 -58.2676)
		(end 179.5526 -58.2676)
		(width 0.1524)
		(layer "In7.Cu")
		(net "M_A_DQ1")
	)
	(segment
		(start 164.79901 -49.9364)
		(end 167.0812 -49.9364)
		(width 0.1524)
		(layer "In7.Cu")
		(net "M_A_DQ1")
	)
	(segment
		(start 179.5526 -58.2676)
		(end 182.729378 -61.444378)
		(width 0.1524)
		(layer "In7.Cu")
		(net "M_A_DQ1")
	)
	(segment
		(start 188.468 -64.65824)
		(end 188.35624 -64.77)
		(width 0.1524)
		(layer "In7.Cu")
		(net "M_A_DQ1")
	)
	(segment
		(start 113.3094 -40.8686)
		(end 118.4656 -40.8686)
		(width 0.1524)
		(layer "In7.Cu")
		(net "M_A_DQ1")
	)
	(segment
		(start 188.276992 -63.808864)
		(end 188.468 -63.999872)
		(width 0.1524)
		(layer "In7.Cu")
		(net "M_A_DQ1")
	)
	(segment
		(start 173.3296 -54.4068)
		(end 174.636938 -54.4068)
		(width 0.1524)
		(layer "In7.Cu")
		(net "M_A_DQ1")
	)
	(segment
		(start 162.69081 -47.8282)
		(end 163.73856 -48.87595)
		(width 0.1524)
		(layer "In7.Cu")
		(net "M_A_DQ1")
	)
	(segment
		(start 163.953952 -48.87595)
		(end 164.346382 -48.48352)
		(width 0.1524)
		(layer "In7.Cu")
		(net "M_A_DQ1")
	)
	(segment
		(start 182.729378 -61.444378)
		(end 184.8358 -61.444378)
		(width 0.1524)
		(layer "In7.Cu")
		(net "M_A_DQ1")
	)
	(segment
		(start 168.52138 -51.591972)
		(end 168.190672 -51.92268)
		(width 0.1524)
		(layer "In7.Cu")
		(net "M_A_DQ1")
	)
	(segment
		(start 105.301288 -42.141902)
		(end 105.80243 -42.141902)
		(width 0.1016)
		(layer "In7.Cu")
		(net "M_A_DQ1")
	)
	(segment
		(start 112.0648 -41.335198)
		(end 112.842802 -41.335198)
		(width 0.1524)
		(layer "In7.Cu")
		(net "M_A_DQ1")
	)
	(segment
		(start 168.190672 -51.92268)
		(end 168.190672 -52.138072)
		(width 0.1524)
		(layer "In7.Cu")
		(net "M_A_DQ1")
	)
	(segment
		(start 168.621964 -52.353972)
		(end 168.952672 -52.023264)
		(width 0.1524)
		(layer "In7.Cu")
		(net "M_A_DQ1")
	)
	(segment
		(start 168.52138 -51.37658)
		(end 168.52138 -51.591972)
		(width 0.1524)
		(layer "In7.Cu")
		(net "M_A_DQ1")
	)
	(segment
		(start 171.3738 -52.451)
		(end 173.3296 -54.4068)
		(width 0.1524)
		(layer "In7.Cu")
		(net "M_A_DQ1")
	)
	(segment
		(start 159.57042 -47.8282)
		(end 162.69081 -47.8282)
		(width 0.1524)
		(layer "In7.Cu")
		(net "M_A_DQ1")
	)
	(segment
		(start 164.385244 -49.307242)
		(end 164.385244 -49.522634)
		(width 0.1524)
		(layer "In7.Cu")
		(net "M_A_DQ1")
	)
	(segment
		(start 106.755946 -40.281098)
		(end 110.652052 -40.281098)
		(width 0.1016)
		(layer "In7.Cu")
		(net "M_A_DQ1")
	)
	(segment
		(start 20.3708 -20.828)
		(end 21.034248 -20.828)
		(width 0.254)
		(layer "F.Cu")
		(net "P1V0_VFB_R")
	)
	(segment
		(start 22.86 -23.114)
		(end 22.86 -22.97938)
		(width 0.254)
		(layer "F.Cu")
		(net "P1V0_VFB_R")
	)
	(segment
		(start 22.2504 -22.36978)
		(end 22.2504 -22.044152)
		(width 0.254)
		(layer "F.Cu")
		(net "P1V0_VFB_R")
	)
	(segment
		(start 22.2504 -22.044152)
		(end 21.820124 -21.613876)
		(width 0.254)
		(layer "F.Cu")
		(net "P1V0_VFB_R")
	)
	(segment
		(start 22.86 -22.97938)
		(end 22.2504 -22.36978)
		(width 0.254)
		(layer "F.Cu")
		(net "P1V0_VFB_R")
	)
	(segment
		(start 21.034248 -20.828)
		(end 21.820124 -21.613876)
		(width 0.254)
		(layer "F.Cu")
		(net "P1V0_VFB_R")
	)
	(via
		(at 21.820124 -21.613876)
		(size 0.7112)
		(drill 0.3556)
		(layers "F.Cu" "B.Cu")
		(net "P1V0_VFB_R")
	)
	(via
		(at 22.86 -23.114)
		(size 0.508)
		(drill 0.254)
		(layers "F.Cu" "B.Cu")
		(net "P1V0_VFB_R")
	)
	(segment
		(start 30.4292 -24.8412)
		(end 32.385 -24.8412)
		(width 0.254)
		(layer "B.Cu")
		(net "P1V0_VFB_R")
	)
	(segment
		(start 23.622 -22.352)
		(end 27.94 -22.352)
		(width 0.254)
		(layer "B.Cu")
		(net "P1V0_VFB_R")
	)
	(segment
		(start 27.94 -22.352)
		(end 30.4292 -24.8412)
		(width 0.254)
		(layer "B.Cu")
		(net "P1V0_VFB_R")
	)
	(segment
		(start 22.86 -23.114)
		(end 23.622 -22.352)
		(width 0.254)
		(layer "B.Cu")
		(net "P1V0_VFB_R")
	)
	(segment
		(start 180.1876 -69.446648)
		(end 180.1876 -69.2404)
		(width 0.1778)
		(layer "F.Cu")
		(net "M_A_DQ15")
	)
	(segment
		(start 107.671108 -42.941494)
		(end 107.733846 -42.941494)
		(width 0.1016)
		(layer "F.Cu")
		(net "M_A_DQ15")
	)
	(segment
		(start 180.550058 -70.806564)
		(end 180.550058 -69.809106)
		(width 0.1778)
		(layer "F.Cu")
		(net "M_A_DQ15")
	)
	(segment
		(start 107.733846 -42.941494)
		(end 108.03001 -43.237658)
		(width 0.1016)
		(layer "F.Cu")
		(net "M_A_DQ15")
	)
	(segment
		(start 108.048298 -43.237658)
		(end 108.0516 -43.24096)
		(width 0.1016)
		(layer "F.Cu")
		(net "M_A_DQ15")
	)
	(segment
		(start 108.03001 -43.237658)
		(end 108.048298 -43.237658)
		(width 0.1016)
		(layer "F.Cu")
		(net "M_A_DQ15")
	)
	(segment
		(start 180.550058 -69.809106)
		(end 180.1876 -69.446648)
		(width 0.1778)
		(layer "F.Cu")
		(net "M_A_DQ15")
	)
	(via
		(at 180.1876 -69.2404)
		(size 0.4318)
		(drill 0.2032)
		(layers "F.Cu" "B.Cu")
		(net "M_A_DQ15")
	)
	(via
		(at 108.0516 -43.24096)
		(size 0.4318)
		(drill 0.2032)
		(layers "F.Cu" "B.Cu")
		(net "M_A_DQ15")
	)
	(segment
		(start 179.650136 -70.79996)
		(end 179.650136 -69.886068)
		(width 0.1778)
		(layer "B.Cu")
		(net "M_A_DQ15")
	)
	(segment
		(start 180.1876 -69.348604)
		(end 180.1876 -69.2404)
		(width 0.1778)
		(layer "B.Cu")
		(net "M_A_DQ15")
	)
	(segment
		(start 179.650136 -69.886068)
		(end 180.1876 -69.348604)
		(width 0.1778)
		(layer "B.Cu")
		(net "M_A_DQ15")
	)
	(segment
		(start 170.466766 -55.149242)
		(end 164.606224 -49.2887)
		(width 0.1524)
		(layer "In4.Cu")
		(net "M_A_DQ15")
	)
	(segment
		(start 122.259852 -44.9326)
		(end 121.751852 -44.4246)
		(width 0.1524)
		(layer "In4.Cu")
		(net "M_A_DQ15")
	)
	(segment
		(start 114.0968 -43.688)
		(end 113.5888 -43.688)
		(width 0.1524)
		(layer "In4.Cu")
		(net "M_A_DQ15")
	)
	(segment
		(start 108.4453 -44.228512)
		(end 108.4453 -43.652948)
		(width 0.1016)
		(layer "In4.Cu")
		(net "M_A_DQ15")
	)
	(segment
		(start 157.252162 -49.2887)
		(end 156.4894 -48.525938)
		(width 0.1524)
		(layer "In4.Cu")
		(net "M_A_DQ15")
	)
	(segment
		(start 117.6528 -43.7134)
		(end 116.8908 -43.7134)
		(width 0.1524)
		(layer "In4.Cu")
		(net "M_A_DQ15")
	)
	(segment
		(start 153.59634 -46.27626)
		(end 153.01595 -46.85665)
		(width 0.1524)
		(layer "In4.Cu")
		(net "M_A_DQ15")
	)
	(segment
		(start 121.751852 -44.4246)
		(end 118.364 -44.4246)
		(width 0.1524)
		(layer "In4.Cu")
		(net "M_A_DQ15")
	)
	(segment
		(start 154.0002 -46.42866)
		(end 153.8478 -46.27626)
		(width 0.1524)
		(layer "In4.Cu")
		(net "M_A_DQ15")
	)
	(segment
		(start 154.7622 -46.27626)
		(end 154.6098 -46.42866)
		(width 0.1524)
		(layer "In4.Cu")
		(net "M_A_DQ15")
	)
	(segment
		(start 180.213 -65.278)
		(end 181.2036 -65.278)
		(width 0.1524)
		(layer "In4.Cu")
		(net "M_A_DQ15")
	)
	(segment
		(start 155.38323 -48.0822)
		(end 155.23083 -47.9298)
		(width 0.1524)
		(layer "In4.Cu")
		(net "M_A_DQ15")
	)
	(segment
		(start 113.3348 -43.942)
		(end 112.9792 -43.942)
		(width 0.1524)
		(layer "In4.Cu")
		(net "M_A_DQ15")
	)
	(segment
		(start 154.6098 -46.9392)
		(end 154.4574 -47.0916)
		(width 0.1524)
		(layer "In4.Cu")
		(net "M_A_DQ15")
	)
	(segment
		(start 112.903 -43.8658)
		(end 110.418626 -43.8658)
		(width 0.1016)
		(layer "In4.Cu")
		(net "M_A_DQ15")
	)
	(segment
		(start 153.01595 -46.85665)
		(end 152.50795 -46.85665)
		(width 0.1524)
		(layer "In4.Cu")
		(net "M_A_DQ15")
	)
	(segment
		(start 154.4574 -47.0916)
		(end 154.1526 -47.0916)
		(width 0.1524)
		(layer "In4.Cu")
		(net "M_A_DQ15")
	)
	(segment
		(start 108.557568 -44.34078)
		(end 108.4453 -44.228512)
		(width 0.1016)
		(layer "In4.Cu")
		(net "M_A_DQ15")
	)
	(segment
		(start 118.364 -44.4246)
		(end 117.6528 -43.7134)
		(width 0.1524)
		(layer "In4.Cu")
		(net "M_A_DQ15")
	)
	(segment
		(start 156.4894 -46.4312)
		(end 156.337 -46.2788)
		(width 0.1524)
		(layer "In4.Cu")
		(net "M_A_DQ15")
	)
	(segment
		(start 151.51735 -45.272198)
		(end 151.177752 -44.9326)
		(width 0.1524)
		(layer "In4.Cu")
		(net "M_A_DQ15")
	)
	(segment
		(start 155.8544 -47.9298)
		(end 155.702 -48.0822)
		(width 0.1524)
		(layer "In4.Cu")
		(net "M_A_DQ15")
	)
	(segment
		(start 116.6622 -43.942)
		(end 114.3508 -43.942)
		(width 0.1524)
		(layer "In4.Cu")
		(net "M_A_DQ15")
	)
	(segment
		(start 110.418626 -43.8658)
		(end 110.109 -44.175426)
		(width 0.1016)
		(layer "In4.Cu")
		(net "M_A_DQ15")
	)
	(segment
		(start 155.702 -48.0822)
		(end 155.38323 -48.0822)
		(width 0.1524)
		(layer "In4.Cu")
		(net "M_A_DQ15")
	)
	(segment
		(start 156.0068 -46.2788)
		(end 155.8544 -46.4312)
		(width 0.1524)
		(layer "In4.Cu")
		(net "M_A_DQ15")
	)
	(segment
		(start 152.50795 -46.85665)
		(end 151.51735 -45.86605)
		(width 0.1524)
		(layer "In4.Cu")
		(net "M_A_DQ15")
	)
	(segment
		(start 112.9792 -43.942)
		(end 112.903 -43.8658)
		(width 0.1016)
		(layer "In4.Cu")
		(net "M_A_DQ15")
	)
	(segment
		(start 154.6098 -46.42866)
		(end 154.6098 -46.9392)
		(width 0.1524)
		(layer "In4.Cu")
		(net "M_A_DQ15")
	)
	(segment
		(start 178.9176 -58.443876)
		(end 175.622966 -55.149242)
		(width 0.1524)
		(layer "In4.Cu")
		(net "M_A_DQ15")
	)
	(segment
		(start 116.8908 -43.7134)
		(end 116.6622 -43.942)
		(width 0.1524)
		(layer "In4.Cu")
		(net "M_A_DQ15")
	)
	(segment
		(start 113.5888 -43.688)
		(end 113.3348 -43.942)
		(width 0.1524)
		(layer "In4.Cu")
		(net "M_A_DQ15")
	)
	(segment
		(start 108.07192 -43.279568)
		(end 108.07192 -43.26128)
		(width 0.1016)
		(layer "In4.Cu")
		(net "M_A_DQ15")
	)
	(segment
		(start 178.9176 -59.9948)
		(end 178.9176 -58.443876)
		(width 0.1524)
		(layer "In4.Cu")
		(net "M_A_DQ15")
	)
	(segment
		(start 181.2036 -65.278)
		(end 181.356 -65.1256)
		(width 0.1524)
		(layer "In4.Cu")
		(net "M_A_DQ15")
	)
	(segment
		(start 155.8544 -46.4312)
		(end 155.8544 -47.9298)
		(width 0.1524)
		(layer "In4.Cu")
		(net "M_A_DQ15")
	)
	(segment
		(start 114.3508 -43.942)
		(end 114.0968 -43.688)
		(width 0.1524)
		(layer "In4.Cu")
		(net "M_A_DQ15")
	)
	(segment
		(start 181.356 -65.1256)
		(end 181.356 -62.4332)
		(width 0.1524)
		(layer "In4.Cu")
		(net "M_A_DQ15")
	)
	(segment
		(start 151.177752 -44.9326)
		(end 122.259852 -44.9326)
		(width 0.1524)
		(layer "In4.Cu")
		(net "M_A_DQ15")
	)
	(segment
		(start 154.1526 -47.0916)
		(end 154.0002 -46.9392)
		(width 0.1524)
		(layer "In4.Cu")
		(net "M_A_DQ15")
	)
	(segment
		(start 154.0002 -46.9392)
		(end 154.0002 -46.42866)
		(width 0.1524)
		(layer "In4.Cu")
		(net "M_A_DQ15")
	)
	(segment
		(start 155.07843 -46.27626)
		(end 154.7622 -46.27626)
		(width 0.1524)
		(layer "In4.Cu")
		(net "M_A_DQ15")
	)
	(segment
		(start 155.23083 -46.42866)
		(end 155.07843 -46.27626)
		(width 0.1524)
		(layer "In4.Cu")
		(net "M_A_DQ15")
	)
	(segment
		(start 181.356 -62.4332)
		(end 178.9176 -59.9948)
		(width 0.1524)
		(layer "In4.Cu")
		(net "M_A_DQ15")
	)
	(segment
		(start 164.606224 -49.2887)
		(end 157.252162 -49.2887)
		(width 0.1524)
		(layer "In4.Cu")
		(net "M_A_DQ15")
	)
	(segment
		(start 156.337 -46.2788)
		(end 156.0068 -46.2788)
		(width 0.1524)
		(layer "In4.Cu")
		(net "M_A_DQ15")
	)
	(segment
		(start 110.109 -44.175426)
		(end 109.587538 -44.175426)
		(width 0.1016)
		(layer "In4.Cu")
		(net "M_A_DQ15")
	)
	(segment
		(start 156.4894 -48.525938)
		(end 156.4894 -46.4312)
		(width 0.1524)
		(layer "In4.Cu")
		(net "M_A_DQ15")
	)
	(segment
		(start 180.0606 -69.1134)
		(end 180.0606 -65.4304)
		(width 0.1524)
		(layer "In4.Cu")
		(net "M_A_DQ15")
	)
	(segment
		(start 108.4453 -43.652948)
		(end 108.07192 -43.279568)
		(width 0.1016)
		(layer "In4.Cu")
		(net "M_A_DQ15")
	)
	(segment
		(start 151.51735 -45.86605)
		(end 151.51735 -45.272198)
		(width 0.1524)
		(layer "In4.Cu")
		(net "M_A_DQ15")
	)
	(segment
		(start 175.622966 -55.149242)
		(end 170.466766 -55.149242)
		(width 0.1524)
		(layer "In4.Cu")
		(net "M_A_DQ15")
	)
	(segment
		(start 155.23083 -47.9298)
		(end 155.23083 -46.42866)
		(width 0.1524)
		(layer "In4.Cu")
		(net "M_A_DQ15")
	)
	(segment
		(start 109.422184 -44.34078)
		(end 108.557568 -44.34078)
		(width 0.1016)
		(layer "In4.Cu")
		(net "M_A_DQ15")
	)
	(segment
		(start 153.8478 -46.27626)
		(end 153.59634 -46.27626)
		(width 0.1524)
		(layer "In4.Cu")
		(net "M_A_DQ15")
	)
	(segment
		(start 108.07192 -43.26128)
		(end 108.0516 -43.24096)
		(width 0.1016)
		(layer "In4.Cu")
		(net "M_A_DQ15")
	)
	(segment
		(start 180.1876 -69.2404)
		(end 180.0606 -69.1134)
		(width 0.1524)
		(layer "In4.Cu")
		(net "M_A_DQ15")
	)
	(segment
		(start 180.0606 -65.4304)
		(end 180.213 -65.278)
		(width 0.1524)
		(layer "In4.Cu")
		(net "M_A_DQ15")
	)
	(segment
		(start 109.587538 -44.175426)
		(end 109.422184 -44.34078)
		(width 0.1016)
		(layer "In4.Cu")
		(net "M_A_DQ15")
	)
	(segment
		(start 84.790788 -38.730174)
		(end 84.754974 -38.730174)
		(width 0.1143)
		(layer "F.Cu")
		(net "FLEX_CLK_SE1")
	)
	(segment
		(start 84.754974 -38.730174)
		(end 84.328 -38.3032)
		(width 0.1143)
		(layer "F.Cu")
		(net "FLEX_CLK_SE1")
	)
	(via
		(at 76.8858 -35.7124)
		(size 0.7112)
		(drill 0.3556)
		(layers "F.Cu" "B.Cu")
		(net "FLEX_CLK_SE1")
	)
	(via
		(at 84.328 -38.3032)
		(size 0.4318)
		(drill 0.2032)
		(layers "F.Cu" "B.Cu")
		(net "FLEX_CLK_SE1")
	)
	(segment
		(start 76.93025 -35.75685)
		(end 76.8858 -35.7124)
		(width 0.1143)
		(layer "B.Cu")
		(net "FLEX_CLK_SE1")
	)
	(segment
		(start 77.65034 -39.445184)
		(end 76.93025 -38.725094)
		(width 0.1143)
		(layer "B.Cu")
		(net "FLEX_CLK_SE1")
	)
	(segment
		(start 74.9046 -35.5092)
		(end 76.6826 -35.5092)
		(width 0.1143)
		(layer "B.Cu")
		(net "FLEX_CLK_SE1")
	)
	(segment
		(start 76.6826 -35.5092)
		(end 76.8858 -35.7124)
		(width 0.1143)
		(layer "B.Cu")
		(net "FLEX_CLK_SE1")
	)
	(segment
		(start 83.95335 -37.92855)
		(end 83.622388 -37.92855)
		(width 0.1016)
		(layer "B.Cu")
		(net "FLEX_CLK_SE1")
	)
	(segment
		(start 80.85074 -39.061644)
		(end 79.638906 -39.061644)
		(width 0.1143)
		(layer "B.Cu")
		(net "FLEX_CLK_SE1")
	)
	(segment
		(start 84.328 -38.3032)
		(end 83.95335 -37.92855)
		(width 0.1016)
		(layer "B.Cu")
		(net "FLEX_CLK_SE1")
	)
	(segment
		(start 76.93025 -38.725094)
		(end 76.93025 -35.75685)
		(width 0.1143)
		(layer "B.Cu")
		(net "FLEX_CLK_SE1")
	)
	(segment
		(start 82.445352 -38.301676)
		(end 82.427826 -38.28415)
		(width 0.1143)
		(layer "B.Cu")
		(net "FLEX_CLK_SE1")
	)
	(segment
		(start 82.427826 -38.28415)
		(end 81.628234 -38.28415)
		(width 0.1143)
		(layer "B.Cu")
		(net "FLEX_CLK_SE1")
	)
	(segment
		(start 79.255366 -39.445184)
		(end 77.65034 -39.445184)
		(width 0.1143)
		(layer "B.Cu")
		(net "FLEX_CLK_SE1")
	)
	(segment
		(start 83.249262 -38.301676)
		(end 82.445352 -38.301676)
		(width 0.1016)
		(layer "B.Cu")
		(net "FLEX_CLK_SE1")
	)
	(segment
		(start 83.622388 -37.92855)
		(end 83.249262 -38.301676)
		(width 0.1016)
		(layer "B.Cu")
		(net "FLEX_CLK_SE1")
	)
	(segment
		(start 74.4728 -36.703)
		(end 74.4728 -35.941)
		(width 0.1143)
		(layer "B.Cu")
		(net "FLEX_CLK_SE1")
	)
	(segment
		(start 79.638906 -39.061644)
		(end 79.255366 -39.445184)
		(width 0.1143)
		(layer "B.Cu")
		(net "FLEX_CLK_SE1")
	)
	(segment
		(start 74.4728 -35.941)
		(end 74.9046 -35.5092)
		(width 0.1143)
		(layer "B.Cu")
		(net "FLEX_CLK_SE1")
	)
	(segment
		(start 81.628234 -38.28415)
		(end 80.85074 -39.061644)
		(width 0.1143)
		(layer "B.Cu")
		(net "FLEX_CLK_SE1")
	)
	(segment
		(start 17.018 -21.8948)
		(end 16.3068 -22.606)
		(width 0.254)
		(layer "F.Cu")
		(net "P1V0_VFB")
	)
	(segment
		(start 17.272 -21.6408)
		(end 17.4752 -21.6408)
		(width 0.254)
		(layer "F.Cu")
		(net "P1V0_VFB")
	)
	(segment
		(start 16.292322 -22.606)
		(end 16.292322 -23.280878)
		(width 0.254)
		(layer "F.Cu")
		(net "P1V0_VFB")
	)
	(segment
		(start 16.3068 -22.606)
		(end 16.292322 -22.606)
		(width 0.254)
		(layer "F.Cu")
		(net "P1V0_VFB")
	)
	(segment
		(start 19.4818 -20.8534)
		(end 19.4818 -21.59)
		(width 0.254)
		(layer "F.Cu")
		(net "P1V0_VFB")
	)
	(segment
		(start 19.5072 -20.828)
		(end 19.4818 -20.8534)
		(width 0.254)
		(layer "F.Cu")
		(net "P1V0_VFB")
	)
	(segment
		(start 19.5072 -20.828)
		(end 18.288 -20.828)
		(width 0.254)
		(layer "F.Cu")
		(net "P1V0_VFB")
	)
	(segment
		(start 17.4752 -21.6408)
		(end 18.288 -20.828)
		(width 0.254)
		(layer "F.Cu")
		(net "P1V0_VFB")
	)
	(segment
		(start 17.018 -21.8948)
		(end 17.272 -21.6408)
		(width 0.254)
		(layer "F.Cu")
		(net "P1V0_VFB")
	)
	(via
		(at 18.288 -20.828)
		(size 0.7112)
		(drill 0.3556)
		(layers "F.Cu" "B.Cu")
		(net "P1V0_VFB")
	)
	(segment
		(start 103.693468 -46.894496)
		(end 103.434896 -46.894496)
		(width 0.1016)
		(layer "F.Cu")
		(net "M_A_CK_DP3")
	)
	(segment
		(start 154.450034 -62.59322)
		(end 154.450034 -63.757302)
		(width 0.2159)
		(layer "F.Cu")
		(net "M_A_CK_DP3")
	)
	(segment
		(start 154.1145 -64.9097)
		(end 154.1018 -64.9224)
		(width 0.2159)
		(layer "F.Cu")
		(net "M_A_CK_DP3")
	)
	(segment
		(start 154.450034 -63.757302)
		(end 154.1145 -64.092836)
		(width 0.2159)
		(layer "F.Cu")
		(net "M_A_CK_DP3")
	)
	(segment
		(start 154.1145 -64.092836)
		(end 154.1145 -64.9097)
		(width 0.2159)
		(layer "F.Cu")
		(net "M_A_CK_DP3")
	)
	(segment
		(start 103.434896 -46.894496)
		(end 103.325168 -46.784768)
		(width 0.1016)
		(layer "F.Cu")
		(net "M_A_CK_DP3")
	)
	(segment
		(start 103.325168 -46.784768)
		(end 103.325168 -46.497494)
		(width 0.1016)
		(layer "F.Cu")
		(net "M_A_CK_DP3")
	)
	(via
		(at 103.693468 -46.894496)
		(size 0.4318)
		(drill 0.2032)
		(layers "F.Cu" "B.Cu")
		(net "M_A_CK_DP3")
	)
	(via
		(at 154.1018 -64.9224)
		(size 0.4318)
		(drill 0.2032)
		(layers "F.Cu" "B.Cu")
		(net "M_A_CK_DP3")
	)
	(segment
		(start 106.422698 -52.451)
		(end 108.15193 -52.451)
		(width 0.1016)
		(layer "In7.Cu")
		(net "M_A_CK_DP3")
	)
	(segment
		(start 117.174264 -52.6415)
		(end 113.787936 -52.6415)
		(width 0.1905)
		(layer "In7.Cu")
		(net "M_A_CK_DP3")
	)
	(segment
		(start 154.3685 -62.7761)
		(end 155.1305 -62.7761)
		(width 0.1905)
		(layer "In7.Cu")
		(net "M_A_CK_DP3")
	)
	(segment
		(start 154.374342 -55.94604)
		(end 152.334468 -55.94604)
		(width 0.1905)
		(layer "In7.Cu")
		(net "M_A_CK_DP3")
	)
	(segment
		(start 109.34954 -52.7177)
		(end 108.961936 -52.330096)
		(width 0.1905)
		(layer "In7.Cu")
		(net "M_A_CK_DP3")
	)
	(segment
		(start 152.334468 -55.94604)
		(end 149.601428 -53.213)
		(width 0.1905)
		(layer "In7.Cu")
		(net "M_A_CK_DP3")
	)
	(segment
		(start 105.533698 -51.562)
		(end 106.422698 -52.451)
		(width 0.1016)
		(layer "In7.Cu")
		(net "M_A_CK_DP3")
	)
	(segment
		(start 108.15193 -52.451)
		(end 108.272834 -52.330096)
		(width 0.1016)
		(layer "In7.Cu")
		(net "M_A_CK_DP3")
	)
	(segment
		(start 155.1305 -62.7761)
		(end 155.6512 -62.2554)
		(width 0.1905)
		(layer "In7.Cu")
		(net "M_A_CK_DP3")
	)
	(segment
		(start 104.0384 -47.7266)
		(end 104.2924 -47.9806)
		(width 0.1016)
		(layer "In7.Cu")
		(net "M_A_CK_DP3")
	)
	(segment
		(start 154.066748 -64.887348)
		(end 154.066748 -63.077852)
		(width 0.1905)
		(layer "In7.Cu")
		(net "M_A_CK_DP3")
	)
	(segment
		(start 112.297464 -52.6415)
		(end 111.806736 -52.6415)
		(width 0.1905)
		(layer "In7.Cu")
		(net "M_A_CK_DP3")
	)
	(segment
		(start 154.1018 -64.9224)
		(end 154.066748 -64.887348)
		(width 0.1905)
		(layer "In7.Cu")
		(net "M_A_CK_DP3")
	)
	(segment
		(start 145.51025 -51.73345)
		(end 143.277336 -51.73345)
		(width 0.1905)
		(layer "In7.Cu")
		(net "M_A_CK_DP3")
	)
	(segment
		(start 113.787936 -52.6415)
		(end 113.483136 -52.3367)
		(width 0.1905)
		(layer "In7.Cu")
		(net "M_A_CK_DP3")
	)
	(segment
		(start 111.806736 -52.6415)
		(end 111.495332 -52.330096)
		(width 0.1905)
		(layer "In7.Cu")
		(net "M_A_CK_DP3")
	)
	(segment
		(start 149.601428 -53.213)
		(end 146.9898 -53.213)
		(width 0.1905)
		(layer "In7.Cu")
		(net "M_A_CK_DP3")
	)
	(segment
		(start 104.2924 -51.146964)
		(end 104.707436 -51.562)
		(width 0.1016)
		(layer "In7.Cu")
		(net "M_A_CK_DP3")
	)
	(segment
		(start 137.414 -51.6509)
		(end 136.594596 -51.6509)
		(width 0.1905)
		(layer "In7.Cu")
		(net "M_A_CK_DP3")
	)
	(segment
		(start 154.066748 -63.077852)
		(end 154.3685 -62.7761)
		(width 0.1905)
		(layer "In7.Cu")
		(net "M_A_CK_DP3")
	)
	(segment
		(start 113.483136 -52.3367)
		(end 112.602264 -52.3367)
		(width 0.1905)
		(layer "In7.Cu")
		(net "M_A_CK_DP3")
	)
	(segment
		(start 110.036864 -52.7177)
		(end 109.34954 -52.7177)
		(width 0.1905)
		(layer "In7.Cu")
		(net "M_A_CK_DP3")
	)
	(segment
		(start 103.6066 -47.7266)
		(end 104.0384 -47.7266)
		(width 0.1016)
		(layer "In7.Cu")
		(net "M_A_CK_DP3")
	)
	(segment
		(start 112.602264 -52.3367)
		(end 112.297464 -52.6415)
		(width 0.1905)
		(layer "In7.Cu")
		(net "M_A_CK_DP3")
	)
	(segment
		(start 136.594596 -51.6509)
		(end 136.022842 -51.079146)
		(width 0.1905)
		(layer "In7.Cu")
		(net "M_A_CK_DP3")
	)
	(segment
		(start 108.961936 -52.330096)
		(end 108.272834 -52.330096)
		(width 0.1905)
		(layer "In7.Cu")
		(net "M_A_CK_DP3")
	)
	(segment
		(start 155.6512 -62.2554)
		(end 155.6512 -57.222898)
		(width 0.1905)
		(layer "In7.Cu")
		(net "M_A_CK_DP3")
	)
	(segment
		(start 110.424468 -52.330096)
		(end 110.036864 -52.7177)
		(width 0.1905)
		(layer "In7.Cu")
		(net "M_A_CK_DP3")
	)
	(segment
		(start 142.623032 -51.079146)
		(end 137.985754 -51.079146)
		(width 0.1905)
		(layer "In7.Cu")
		(net "M_A_CK_DP3")
	)
	(segment
		(start 103.4796 -47.108364)
		(end 103.4796 -47.5996)
		(width 0.1016)
		(layer "In7.Cu")
		(net "M_A_CK_DP3")
	)
	(segment
		(start 104.2924 -47.9806)
		(end 104.2924 -51.146964)
		(width 0.1016)
		(layer "In7.Cu")
		(net "M_A_CK_DP3")
	)
	(segment
		(start 103.693468 -46.894496)
		(end 103.4796 -47.108364)
		(width 0.1016)
		(layer "In7.Cu")
		(net "M_A_CK_DP3")
	)
	(segment
		(start 118.736618 -51.079146)
		(end 117.174264 -52.6415)
		(width 0.1905)
		(layer "In7.Cu")
		(net "M_A_CK_DP3")
	)
	(segment
		(start 155.6512 -57.222898)
		(end 154.374342 -55.94604)
		(width 0.1905)
		(layer "In7.Cu")
		(net "M_A_CK_DP3")
	)
	(segment
		(start 111.495332 -52.330096)
		(end 110.424468 -52.330096)
		(width 0.1905)
		(layer "In7.Cu")
		(net "M_A_CK_DP3")
	)
	(segment
		(start 136.022842 -51.079146)
		(end 118.736618 -51.079146)
		(width 0.1905)
		(layer "In7.Cu")
		(net "M_A_CK_DP3")
	)
	(segment
		(start 143.277336 -51.73345)
		(end 142.623032 -51.079146)
		(width 0.1905)
		(layer "In7.Cu")
		(net "M_A_CK_DP3")
	)
	(segment
		(start 137.985754 -51.079146)
		(end 137.414 -51.6509)
		(width 0.1905)
		(layer "In7.Cu")
		(net "M_A_CK_DP3")
	)
	(segment
		(start 103.4796 -47.5996)
		(end 103.6066 -47.7266)
		(width 0.1016)
		(layer "In7.Cu")
		(net "M_A_CK_DP3")
	)
	(segment
		(start 104.707436 -51.562)
		(end 105.533698 -51.562)
		(width 0.1016)
		(layer "In7.Cu")
		(net "M_A_CK_DP3")
	)
	(segment
		(start 146.9898 -53.213)
		(end 145.51025 -51.73345)
		(width 0.1905)
		(layer "In7.Cu")
		(net "M_A_CK_DP3")
	)
	(segment
		(start 94.333568 -30.759654)
		(end 94.0054 -30.431486)
		(width 0.1397)
		(layer "F.Cu")
		(net "CLK_100M_CPU_HFHPLL_DP")
	)
	(segment
		(start 94.0054 -30.431486)
		(end 94.0054 -30.369002)
		(width 0.1397)
		(layer "F.Cu")
		(net "CLK_100M_CPU_HFHPLL_DP")
	)
	(via
		(at 94.0054 -30.369002)
		(size 0.4318)
		(drill 0.2032)
		(layers "F.Cu" "B.Cu")
		(net "CLK_100M_CPU_HFHPLL_DP")
	)
	(via
		(at 49.434242 -38.029642)
		(size 0.508)
		(drill 0.254)
		(layers "F.Cu" "B.Cu")
		(net "CLK_100M_CPU_HFHPLL_DP")
	)
	(segment
		(start 50.1777 -44.1833)
		(end 50.5333 -43.8277)
		(width 0.1397)
		(layer "B.Cu")
		(net "CLK_100M_CPU_HFHPLL_DP")
	)
	(segment
		(start 49.0601 -39.5351)
		(end 49.0601 -38.79596)
		(width 0.1397)
		(layer "B.Cu")
		(net "CLK_100M_CPU_HFHPLL_DP")
	)
	(segment
		(start 50.5333 -43.8277)
		(end 50.5333 -42.7355)
		(width 0.1397)
		(layer "B.Cu")
		(net "CLK_100M_CPU_HFHPLL_DP")
	)
	(segment
		(start 50.1777 -45.73016)
		(end 50.1777 -44.1833)
		(width 0.1397)
		(layer "B.Cu")
		(net "CLK_100M_CPU_HFHPLL_DP")
	)
	(segment
		(start 50.5333 -42.7355)
		(end 49.5427 -41.7449)
		(width 0.1397)
		(layer "B.Cu")
		(net "CLK_100M_CPU_HFHPLL_DP")
	)
	(segment
		(start 49.210468 -46.697392)
		(end 50.1777 -45.73016)
		(width 0.1397)
		(layer "B.Cu")
		(net "CLK_100M_CPU_HFHPLL_DP")
	)
	(segment
		(start 49.5427 -41.7449)
		(end 49.5427 -40.0177)
		(width 0.1397)
		(layer "B.Cu")
		(net "CLK_100M_CPU_HFHPLL_DP")
	)
	(segment
		(start 49.0601 -38.79596)
		(end 49.434242 -38.421818)
		(width 0.1397)
		(layer "B.Cu")
		(net "CLK_100M_CPU_HFHPLL_DP")
	)
	(segment
		(start 48.668178 -46.697392)
		(end 49.210468 -46.697392)
		(width 0.1397)
		(layer "B.Cu")
		(net "CLK_100M_CPU_HFHPLL_DP")
	)
	(segment
		(start 49.5427 -40.0177)
		(end 49.0601 -39.5351)
		(width 0.1397)
		(layer "B.Cu")
		(net "CLK_100M_CPU_HFHPLL_DP")
	)
	(segment
		(start 49.434242 -38.421818)
		(end 49.434242 -38.029642)
		(width 0.1397)
		(layer "B.Cu")
		(net "CLK_100M_CPU_HFHPLL_DP")
	)
	(segment
		(start 84.004658 -27.205686)
		(end 84.004658 -27.507438)
		(width 0.1143)
		(layer "In4.Cu")
		(net "CLK_100M_CPU_HFHPLL_DP")
	)
	(segment
		(start 68.017644 -26.25725)
		(end 69.09054 -26.25725)
		(width 0.1143)
		(layer "In4.Cu")
		(net "CLK_100M_CPU_HFHPLL_DP")
	)
	(segment
		(start 89.19845 -29.71165)
		(end 89.54135 -29.71165)
		(width 0.1143)
		(layer "In4.Cu")
		(net "CLK_100M_CPU_HFHPLL_DP")
	)
	(segment
		(start 83.46059 -26.96337)
		(end 83.762342 -26.96337)
		(width 0.1143)
		(layer "In4.Cu")
		(net "CLK_100M_CPU_HFHPLL_DP")
	)
	(segment
		(start 87.004144 -27.672284)
		(end 87.217504 -27.885644)
		(width 0.1143)
		(layer "In4.Cu")
		(net "CLK_100M_CPU_HFHPLL_DP")
	)
	(segment
		(start 56.882792 -31.6865)
		(end 60.5155 -31.6865)
		(width 0.1143)
		(layer "In4.Cu")
		(net "CLK_100M_CPU_HFHPLL_DP")
	)
	(segment
		(start 88.84412 -28.717494)
		(end 88.84412 -29.35732)
		(width 0.1143)
		(layer "In4.Cu")
		(net "CLK_100M_CPU_HFHPLL_DP")
	)
	(segment
		(start 66.204338 -28.070556)
		(end 68.017644 -26.25725)
		(width 0.1143)
		(layer "In4.Cu")
		(net "CLK_100M_CPU_HFHPLL_DP")
	)
	(segment
		(start 75.0697 -27.6479)
		(end 75.9968 -26.7208)
		(width 0.1143)
		(layer "In4.Cu")
		(net "CLK_100M_CPU_HFHPLL_DP")
	)
	(segment
		(start 83.762342 -26.96337)
		(end 84.004658 -27.205686)
		(width 0.1143)
		(layer "In4.Cu")
		(net "CLK_100M_CPU_HFHPLL_DP")
	)
	(segment
		(start 84.843112 -28.034996)
		(end 84.992464 -27.885644)
		(width 0.1143)
		(layer "In4.Cu")
		(net "CLK_100M_CPU_HFHPLL_DP")
	)
	(segment
		(start 84.992464 -27.885644)
		(end 85.335364 -27.885644)
		(width 0.1143)
		(layer "In4.Cu")
		(net "CLK_100M_CPU_HFHPLL_DP")
	)
	(segment
		(start 86.447884 -27.885644)
		(end 86.661244 -27.672284)
		(width 0.1143)
		(layer "In4.Cu")
		(net "CLK_100M_CPU_HFHPLL_DP")
	)
	(segment
		(start 92.80525 -29.71165)
		(end 93.507052 -30.413452)
		(width 0.1143)
		(layer "In4.Cu")
		(net "CLK_100M_CPU_HFHPLL_DP")
	)
	(segment
		(start 88.01227 -27.885644)
		(end 88.84412 -28.717494)
		(width 0.1143)
		(layer "In4.Cu")
		(net "CLK_100M_CPU_HFHPLL_DP")
	)
	(segment
		(start 54.9275 -33.641792)
		(end 56.882792 -31.6865)
		(width 0.1143)
		(layer "In4.Cu")
		(net "CLK_100M_CPU_HFHPLL_DP")
	)
	(segment
		(start 53.633116 -37.2491)
		(end 54.9275 -35.954716)
		(width 0.1143)
		(layer "In4.Cu")
		(net "CLK_100M_CPU_HFHPLL_DP")
	)
	(segment
		(start 50.624994 -37.2491)
		(end 53.633116 -37.2491)
		(width 0.1143)
		(layer "In4.Cu")
		(net "CLK_100M_CPU_HFHPLL_DP")
	)
	(segment
		(start 85.335364 -27.885644)
		(end 85.548724 -27.672284)
		(width 0.1143)
		(layer "In4.Cu")
		(net "CLK_100M_CPU_HFHPLL_DP")
	)
	(segment
		(start 93.96095 -30.413452)
		(end 94.0054 -30.369002)
		(width 0.1143)
		(layer "In4.Cu")
		(net "CLK_100M_CPU_HFHPLL_DP")
	)
	(segment
		(start 90.09761 -29.49829)
		(end 90.31097 -29.71165)
		(width 0.1143)
		(layer "In4.Cu")
		(net "CLK_100M_CPU_HFHPLL_DP")
	)
	(segment
		(start 49.434242 -38.029642)
		(end 49.844452 -38.029642)
		(width 0.1143)
		(layer "In4.Cu")
		(net "CLK_100M_CPU_HFHPLL_DP")
	)
	(segment
		(start 84.532216 -28.034996)
		(end 84.843112 -28.034996)
		(width 0.1143)
		(layer "In4.Cu")
		(net "CLK_100M_CPU_HFHPLL_DP")
	)
	(segment
		(start 85.548724 -27.672284)
		(end 85.891624 -27.672284)
		(width 0.1143)
		(layer "In4.Cu")
		(net "CLK_100M_CPU_HFHPLL_DP")
	)
	(segment
		(start 69.09054 -26.25725)
		(end 70.48119 -27.6479)
		(width 0.1143)
		(layer "In4.Cu")
		(net "CLK_100M_CPU_HFHPLL_DP")
	)
	(segment
		(start 49.844452 -38.029642)
		(end 50.624994 -37.2491)
		(width 0.1143)
		(layer "In4.Cu")
		(net "CLK_100M_CPU_HFHPLL_DP")
	)
	(segment
		(start 88.84412 -29.35732)
		(end 89.19845 -29.71165)
		(width 0.1143)
		(layer "In4.Cu")
		(net "CLK_100M_CPU_HFHPLL_DP")
	)
	(segment
		(start 93.507052 -30.413452)
		(end 93.96095 -30.413452)
		(width 0.1143)
		(layer "In4.Cu")
		(net "CLK_100M_CPU_HFHPLL_DP")
	)
	(segment
		(start 86.104984 -27.885644)
		(end 86.447884 -27.885644)
		(width 0.1143)
		(layer "In4.Cu")
		(net "CLK_100M_CPU_HFHPLL_DP")
	)
	(segment
		(start 86.661244 -27.672284)
		(end 87.004144 -27.672284)
		(width 0.1143)
		(layer "In4.Cu")
		(net "CLK_100M_CPU_HFHPLL_DP")
	)
	(segment
		(start 90.31097 -29.71165)
		(end 92.80525 -29.71165)
		(width 0.1143)
		(layer "In4.Cu")
		(net "CLK_100M_CPU_HFHPLL_DP")
	)
	(segment
		(start 85.891624 -27.672284)
		(end 86.104984 -27.885644)
		(width 0.1143)
		(layer "In4.Cu")
		(net "CLK_100M_CPU_HFHPLL_DP")
	)
	(segment
		(start 84.004658 -27.507438)
		(end 84.532216 -28.034996)
		(width 0.1143)
		(layer "In4.Cu")
		(net "CLK_100M_CPU_HFHPLL_DP")
	)
	(segment
		(start 60.5155 -31.6865)
		(end 64.131444 -28.070556)
		(width 0.1143)
		(layer "In4.Cu")
		(net "CLK_100M_CPU_HFHPLL_DP")
	)
	(segment
		(start 89.54135 -29.71165)
		(end 89.75471 -29.49829)
		(width 0.1143)
		(layer "In4.Cu")
		(net "CLK_100M_CPU_HFHPLL_DP")
	)
	(segment
		(start 70.48119 -27.6479)
		(end 75.0697 -27.6479)
		(width 0.1143)
		(layer "In4.Cu")
		(net "CLK_100M_CPU_HFHPLL_DP")
	)
	(segment
		(start 75.9968 -26.7208)
		(end 83.21802 -26.7208)
		(width 0.1143)
		(layer "In4.Cu")
		(net "CLK_100M_CPU_HFHPLL_DP")
	)
	(segment
		(start 89.75471 -29.49829)
		(end 90.09761 -29.49829)
		(width 0.1143)
		(layer "In4.Cu")
		(net "CLK_100M_CPU_HFHPLL_DP")
	)
	(segment
		(start 54.9275 -35.954716)
		(end 54.9275 -33.641792)
		(width 0.1143)
		(layer "In4.Cu")
		(net "CLK_100M_CPU_HFHPLL_DP")
	)
	(segment
		(start 87.217504 -27.885644)
		(end 88.01227 -27.885644)
		(width 0.1143)
		(layer "In4.Cu")
		(net "CLK_100M_CPU_HFHPLL_DP")
	)
	(segment
		(start 83.21802 -26.7208)
		(end 83.46059 -26.96337)
		(width 0.1143)
		(layer "In4.Cu")
		(net "CLK_100M_CPU_HFHPLL_DP")
	)
	(segment
		(start 64.131444 -28.070556)
		(end 66.204338 -28.070556)
		(width 0.1143)
		(layer "In4.Cu")
		(net "CLK_100M_CPU_HFHPLL_DP")
	)
	(via
		(at 6.477 -26.67)
		(size 0.7112)
		(drill 0.3556)
		(layers "F.Cu" "B.Cu")
		(net "P1V0_VIN")
	)
	(via
		(at 8.382 -26.67)
		(size 0.7112)
		(drill 0.4064)
		(layers "F.Cu" "B.Cu")
		(net "P1V0_VIN")
	)
	(via
		(at 9.525 -26.67)
		(size 0.7112)
		(drill 0.4064)
		(layers "F.Cu" "B.Cu")
		(net "P1V0_VIN")
	)
	(via
		(at 10.668 -26.67)
		(size 0.7112)
		(drill 0.4064)
		(layers "F.Cu" "B.Cu")
		(net "P1V0_VIN")
	)
	(segment
		(start 111.092488 -42.598594)
		(end 111.171482 -42.5196)
		(width 0.1016)
		(layer "F.Cu")
		(net "M_A_DQS_DP3")
	)
	(segment
		(start 171.997624 -66.407284)
		(end 171.732702 -66.672206)
		(width 0.1778)
		(layer "F.Cu")
		(net "M_A_DQS_DP3")
	)
	(segment
		(start 111.345726 -42.5196)
		(end 111.6076 -42.781474)
		(width 0.1016)
		(layer "F.Cu")
		(net "M_A_DQS_DP3")
	)
	(segment
		(start 171.85005 -63.33617)
		(end 171.997624 -63.483744)
		(width 0.1778)
		(layer "F.Cu")
		(net "M_A_DQS_DP3")
	)
	(segment
		(start 111.6076 -42.781474)
		(end 112.22482 -42.781474)
		(width 0.1016)
		(layer "F.Cu")
		(net "M_A_DQS_DP3")
	)
	(segment
		(start 116.4336 -44.831)
		(end 116.84 -44.4246)
		(width 0.1016)
		(layer "F.Cu")
		(net "M_A_DQS_DP3")
	)
	(segment
		(start 171.997624 -63.483744)
		(end 171.997624 -66.407284)
		(width 0.1778)
		(layer "F.Cu")
		(net "M_A_DQS_DP3")
	)
	(segment
		(start 112.22482 -42.781474)
		(end 114.274346 -44.831)
		(width 0.1016)
		(layer "F.Cu")
		(net "M_A_DQS_DP3")
	)
	(segment
		(start 114.274346 -44.831)
		(end 116.4336 -44.831)
		(width 0.1016)
		(layer "F.Cu")
		(net "M_A_DQS_DP3")
	)
	(segment
		(start 171.85005 -62.59322)
		(end 171.85005 -63.33617)
		(width 0.1778)
		(layer "F.Cu")
		(net "M_A_DQS_DP3")
	)
	(segment
		(start 111.171482 -42.5196)
		(end 111.345726 -42.5196)
		(width 0.1016)
		(layer "F.Cu")
		(net "M_A_DQS_DP3")
	)
	(via
		(at 171.732702 -66.672206)
		(size 0.4318)
		(drill 0.2032)
		(layers "F.Cu" "B.Cu")
		(net "M_A_DQS_DP3")
	)
	(via
		(at 116.84 -44.4246)
		(size 0.4318)
		(drill 0.2032)
		(layers "F.Cu" "B.Cu")
		(net "M_A_DQS_DP3")
	)
	(segment
		(start 171.997624 -66.937128)
		(end 171.732702 -66.672206)
		(width 0.1778)
		(layer "B.Cu")
		(net "M_A_DQS_DP3")
	)
	(segment
		(start 171.85005 -70.066154)
		(end 171.997624 -69.91858)
		(width 0.1778)
		(layer "B.Cu")
		(net "M_A_DQS_DP3")
	)
	(segment
		(start 171.997624 -69.91858)
		(end 171.997624 -66.937128)
		(width 0.1778)
		(layer "B.Cu")
		(net "M_A_DQS_DP3")
	)
	(segment
		(start 171.85005 -70.79996)
		(end 171.85005 -70.066154)
		(width 0.1778)
		(layer "B.Cu")
		(net "M_A_DQS_DP3")
	)
	(segment
		(start 161.29 -43.688)
		(end 164.619178 -47.017178)
		(width 0.1524)
		(layer "In2.Cu")
		(net "M_A_DQS_DP3")
	)
	(segment
		(start 164.619178 -50.73396)
		(end 172.7708 -58.885582)
		(width 0.1524)
		(layer "In2.Cu")
		(net "M_A_DQS_DP3")
	)
	(segment
		(start 157.0482 -45.073824)
		(end 157.0482 -43.8404)
		(width 0.1524)
		(layer "In2.Cu")
		(net "M_A_DQS_DP3")
	)
	(segment
		(start 158.9786 -43.688)
		(end 161.29 -43.688)
		(width 0.1524)
		(layer "In2.Cu")
		(net "M_A_DQS_DP3")
	)
	(segment
		(start 172.010324 -66.013076)
		(end 172.010324 -66.394584)
		(width 0.1524)
		(layer "In2.Cu")
		(net "M_A_DQS_DP3")
	)
	(segment
		(start 157.5054 -43.688)
		(end 157.6578 -43.8404)
		(width 0.1524)
		(layer "In2.Cu")
		(net "M_A_DQS_DP3")
	)
	(segment
		(start 158.8262 -45.073824)
		(end 158.8262 -43.8404)
		(width 0.1524)
		(layer "In2.Cu")
		(net "M_A_DQS_DP3")
	)
	(segment
		(start 155.7274 -43.688)
		(end 155.8798 -43.8404)
		(width 0.1524)
		(layer "In2.Cu")
		(net "M_A_DQS_DP3")
	)
	(segment
		(start 156.732224 -45.3898)
		(end 157.0482 -45.073824)
		(width 0.1524)
		(layer "In2.Cu")
		(net "M_A_DQS_DP3")
	)
	(segment
		(start 172.7708 -63.434976)
		(end 172.49902 -63.706756)
		(width 0.1524)
		(layer "In2.Cu")
		(net "M_A_DQS_DP3")
	)
	(segment
		(start 118.730268 -43.688)
		(end 118.654068 -43.7642)
		(width 0.1016)
		(layer "In2.Cu")
		(net "M_A_DQS_DP3")
	)
	(segment
		(start 157.2006 -43.688)
		(end 157.5054 -43.688)
		(width 0.1524)
		(layer "In2.Cu")
		(net "M_A_DQS_DP3")
	)
	(segment
		(start 157.973776 -45.3898)
		(end 158.510224 -45.3898)
		(width 0.1524)
		(layer "In2.Cu")
		(net "M_A_DQS_DP3")
	)
	(segment
		(start 158.8262 -43.8404)
		(end 158.9786 -43.688)
		(width 0.1524)
		(layer "In2.Cu")
		(net "M_A_DQS_DP3")
	)
	(segment
		(start 172.7708 -58.885582)
		(end 172.7708 -63.434976)
		(width 0.1524)
		(layer "In2.Cu")
		(net "M_A_DQS_DP3")
	)
	(segment
		(start 157.6578 -45.073824)
		(end 157.973776 -45.3898)
		(width 0.1524)
		(layer "In2.Cu")
		(net "M_A_DQS_DP3")
	)
	(segment
		(start 158.510224 -45.3898)
		(end 158.8262 -45.073824)
		(width 0.1524)
		(layer "In2.Cu")
		(net "M_A_DQS_DP3")
	)
	(segment
		(start 157.6578 -43.8404)
		(end 157.6578 -45.073824)
		(width 0.1524)
		(layer "In2.Cu")
		(net "M_A_DQS_DP3")
	)
	(segment
		(start 155.8798 -45.073824)
		(end 156.195776 -45.3898)
		(width 0.1524)
		(layer "In2.Cu")
		(net "M_A_DQS_DP3")
	)
	(segment
		(start 172.010324 -66.394584)
		(end 171.732702 -66.672206)
		(width 0.1524)
		(layer "In2.Cu")
		(net "M_A_DQS_DP3")
	)
	(segment
		(start 117.0686 -44.196)
		(end 116.84 -44.4246)
		(width 0.1016)
		(layer "In2.Cu")
		(net "M_A_DQS_DP3")
	)
	(segment
		(start 157.0482 -43.8404)
		(end 157.2006 -43.688)
		(width 0.1524)
		(layer "In2.Cu")
		(net "M_A_DQS_DP3")
	)
	(segment
		(start 118.1862 -44.196)
		(end 117.0686 -44.196)
		(width 0.1016)
		(layer "In2.Cu")
		(net "M_A_DQS_DP3")
	)
	(segment
		(start 164.619178 -47.017178)
		(end 164.619178 -50.73396)
		(width 0.1524)
		(layer "In2.Cu")
		(net "M_A_DQS_DP3")
	)
	(segment
		(start 172.49902 -65.52438)
		(end 172.010324 -66.013076)
		(width 0.1524)
		(layer "In2.Cu")
		(net "M_A_DQS_DP3")
	)
	(segment
		(start 118.730268 -43.688)
		(end 155.7274 -43.688)
		(width 0.1524)
		(layer "In2.Cu")
		(net "M_A_DQS_DP3")
	)
	(segment
		(start 156.195776 -45.3898)
		(end 156.732224 -45.3898)
		(width 0.1524)
		(layer "In2.Cu")
		(net "M_A_DQS_DP3")
	)
	(segment
		(start 155.8798 -43.8404)
		(end 155.8798 -45.073824)
		(width 0.1524)
		(layer "In2.Cu")
		(net "M_A_DQS_DP3")
	)
	(segment
		(start 118.654068 -43.7642)
		(end 118.618 -43.7642)
		(width 0.1016)
		(layer "In2.Cu")
		(net "M_A_DQS_DP3")
	)
	(segment
		(start 118.618 -43.7642)
		(end 118.1862 -44.196)
		(width 0.1016)
		(layer "In2.Cu")
		(net "M_A_DQS_DP3")
	)
	(segment
		(start 172.49902 -63.706756)
		(end 172.49902 -65.52438)
		(width 0.1524)
		(layer "In2.Cu")
		(net "M_A_DQS_DP3")
	)
	(via
		(at 20.447 -28.829)
		(size 0.508)
		(drill 0.254)
		(layers "F.Cu" "B.Cu")
		(net "P1V0_LX")
	)
	(via
		(at 20.066 -27.0256)
		(size 0.7112)
		(drill 0.3556)
		(layers "F.Cu" "B.Cu")
		(net "P1V0_LX")
	)
	(segment
		(start 20.066 -27.0256)
		(end 20.0152 -27.0764)
		(width 0.3048)
		(layer "B.Cu")
		(net "P1V0_LX")
	)
	(segment
		(start 20.0152 -28.3972)
		(end 20.447 -28.829)
		(width 0.3048)
		(layer "B.Cu")
		(net "P1V0_LX")
	)
	(segment
		(start 20.0152 -27.94)
		(end 20.0152 -28.3972)
		(width 0.3048)
		(layer "B.Cu")
		(net "P1V0_LX")
	)
	(segment
		(start 20.0152 -27.0764)
		(end 20.0152 -27.94)
		(width 0.3048)
		(layer "B.Cu")
		(net "P1V0_LX")
	)
	(segment
		(start 177.850038 -62.59322)
		(end 177.850038 -63.301118)
		(width 0.1778)
		(layer "F.Cu")
		(net "M_A_DQ17")
	)
	(segment
		(start 177.850038 -63.301118)
		(end 178.308 -63.75908)
		(width 0.1778)
		(layer "F.Cu")
		(net "M_A_DQ17")
	)
	(segment
		(start 107.290108 -45.628814)
		(end 107.605068 -45.943774)
		(width 0.1016)
		(layer "F.Cu")
		(net "M_A_DQ17")
	)
	(segment
		(start 107.605068 -45.943774)
		(end 107.605068 -46.068996)
		(width 0.1016)
		(layer "F.Cu")
		(net "M_A_DQ17")
	)
	(segment
		(start 178.308 -63.75908)
		(end 178.308 -64.693292)
		(width 0.1778)
		(layer "F.Cu")
		(net "M_A_DQ17")
	)
	(segment
		(start 178.308 -64.693292)
		(end 178.218846 -64.782446)
		(width 0.1778)
		(layer "F.Cu")
		(net "M_A_DQ17")
	)
	(via
		(at 178.218846 -64.782446)
		(size 0.4318)
		(drill 0.2032)
		(layers "F.Cu" "B.Cu")
		(net "M_A_DQ17")
	)
	(via
		(at 107.605068 -46.068996)
		(size 0.4318)
		(drill 0.2032)
		(layers "F.Cu" "B.Cu")
		(net "M_A_DQ17")
	)
	(segment
		(start 178.429412 -63.802006)
		(end 178.429412 -64.57188)
		(width 0.1778)
		(layer "B.Cu")
		(net "M_A_DQ17")
	)
	(segment
		(start 178.74996 -63.48095)
		(end 178.750214 -63.481204)
		(width 0.1778)
		(layer "B.Cu")
		(net "M_A_DQ17")
	)
	(segment
		(start 178.750214 -63.481204)
		(end 178.429412 -63.802006)
		(width 0.1778)
		(layer "B.Cu")
		(net "M_A_DQ17")
	)
	(segment
		(start 178.74996 -62.599824)
		(end 178.74996 -63.48095)
		(width 0.1778)
		(layer "B.Cu")
		(net "M_A_DQ17")
	)
	(segment
		(start 178.429412 -64.57188)
		(end 178.218846 -64.782446)
		(width 0.1778)
		(layer "B.Cu")
		(net "M_A_DQ17")
	)
	(segment
		(start 150.643336 -51.633882)
		(end 150.427944 -51.633882)
		(width 0.1524)
		(layer "In4.Cu")
		(net "M_A_DQ17")
	)
	(segment
		(start 170.927776 -60.1091)
		(end 168.002712 -57.184036)
		(width 0.1524)
		(layer "In4.Cu")
		(net "M_A_DQ17")
	)
	(segment
		(start 166.519098 -57.184036)
		(end 165.934898 -57.184036)
		(width 0.1524)
		(layer "In4.Cu")
		(net "M_A_DQ17")
	)
	(segment
		(start 165.16731 -56.201056)
		(end 165.985444 -55.382922)
		(width 0.1524)
		(layer "In4.Cu")
		(net "M_A_DQ17")
	)
	(segment
		(start 165.985444 -55.382922)
		(end 165.985444 -55.16753)
		(width 0.1524)
		(layer "In4.Cu")
		(net "M_A_DQ17")
	)
	(segment
		(start 151.055832 -51.437032)
		(end 150.84044 -51.437032)
		(width 0.1524)
		(layer "In4.Cu")
		(net "M_A_DQ17")
	)
	(segment
		(start 150.427944 -51.633882)
		(end 150.212044 -51.417982)
		(width 0.1524)
		(layer "In4.Cu")
		(net "M_A_DQ17")
	)
	(segment
		(start 151.271732 -51.86807)
		(end 151.271732 -51.652932)
		(width 0.1524)
		(layer "In4.Cu")
		(net "M_A_DQ17")
	)
	(segment
		(start 110.364016 -46.394878)
		(end 109.663738 -45.6946)
		(width 0.1016)
		(layer "In4.Cu")
		(net "M_A_DQ17")
	)
	(segment
		(start 165.985444 -55.16753)
		(end 165.769544 -54.95163)
		(width 0.1524)
		(layer "In4.Cu")
		(net "M_A_DQ17")
	)
	(segment
		(start 114.7064 -49.5554)
		(end 113.919 -48.768)
		(width 0.1524)
		(layer "In4.Cu")
		(net "M_A_DQ17")
	)
	(segment
		(start 122.307604 -48.641)
		(end 121.875804 -49.0728)
		(width 0.1524)
		(layer "In4.Cu")
		(net "M_A_DQ17")
	)
	(segment
		(start 109.0676 -45.6946)
		(end 108.693204 -46.068996)
		(width 0.1016)
		(layer "In4.Cu")
		(net "M_A_DQ17")
	)
	(segment
		(start 150.156672 -50.61077)
		(end 149.94128 -50.61077)
		(width 0.1524)
		(layer "In4.Cu")
		(net "M_A_DQ17")
	)
	(segment
		(start 121.875804 -49.0728)
		(end 118.237 -49.0728)
		(width 0.1524)
		(layer "In4.Cu")
		(net "M_A_DQ17")
	)
	(segment
		(start 167.433498 -57.184036)
		(end 167.281098 -57.031636)
		(width 0.1524)
		(layer "In4.Cu")
		(net "M_A_DQ17")
	)
	(segment
		(start 178.442112 -63.303912)
		(end 175.2473 -60.1091)
		(width 0.1524)
		(layer "In4.Cu")
		(net "M_A_DQ17")
	)
	(segment
		(start 165.934898 -57.184036)
		(end 165.16731 -56.416448)
		(width 0.1524)
		(layer "In4.Cu")
		(net "M_A_DQ17")
	)
	(segment
		(start 164.520626 -55.769764)
		(end 163.310062 -54.5592)
		(width 0.1524)
		(layer "In4.Cu")
		(net "M_A_DQ17")
	)
	(segment
		(start 145.284444 -50.3174)
		(end 143.608044 -48.641)
		(width 0.1524)
		(layer "In4.Cu")
		(net "M_A_DQ17")
	)
	(segment
		(start 165.769544 -54.95163)
		(end 165.554152 -54.95163)
		(width 0.1524)
		(layer "In4.Cu")
		(net "M_A_DQ17")
	)
	(segment
		(start 149.94128 -50.61077)
		(end 149.780752 -50.771298)
		(width 0.1524)
		(layer "In4.Cu")
		(net "M_A_DQ17")
	)
	(segment
		(start 150.212044 -51.417982)
		(end 150.212044 -51.20259)
		(width 0.1524)
		(layer "In4.Cu")
		(net "M_A_DQ17")
	)
	(segment
		(start 163.310062 -54.5592)
		(end 155.055062 -54.5592)
		(width 0.1524)
		(layer "In4.Cu")
		(net "M_A_DQ17")
	)
	(segment
		(start 110.836202 -46.228)
		(end 110.669324 -46.394878)
		(width 0.1016)
		(layer "In4.Cu")
		(net "M_A_DQ17")
	)
	(segment
		(start 154.547062 -54.0512)
		(end 152.845262 -54.0512)
		(width 0.1524)
		(layer "In4.Cu")
		(net "M_A_DQ17")
	)
	(segment
		(start 165.16731 -56.416448)
		(end 165.16731 -56.201056)
		(width 0.1524)
		(layer "In4.Cu")
		(net "M_A_DQ17")
	)
	(segment
		(start 113.6396 -48.4886)
		(end 113.6396 -48.3362)
		(width 0.1016)
		(layer "In4.Cu")
		(net "M_A_DQ17")
	)
	(segment
		(start 108.693204 -46.068996)
		(end 107.605068 -46.068996)
		(width 0.1016)
		(layer "In4.Cu")
		(net "M_A_DQ17")
	)
	(segment
		(start 167.281098 -57.031636)
		(end 167.281098 -56.4642)
		(width 0.1524)
		(layer "In4.Cu")
		(net "M_A_DQ17")
	)
	(segment
		(start 165.554152 -54.95163)
		(end 164.736018 -55.769764)
		(width 0.1524)
		(layer "In4.Cu")
		(net "M_A_DQ17")
	)
	(segment
		(start 150.212044 -51.20259)
		(end 150.372572 -51.042062)
		(width 0.1524)
		(layer "In4.Cu")
		(net "M_A_DQ17")
	)
	(segment
		(start 167.128698 -56.3118)
		(end 166.823898 -56.3118)
		(width 0.1524)
		(layer "In4.Cu")
		(net "M_A_DQ17")
	)
	(segment
		(start 155.055062 -54.5592)
		(end 154.547062 -54.0512)
		(width 0.1524)
		(layer "In4.Cu")
		(net "M_A_DQ17")
	)
	(segment
		(start 166.671498 -56.4642)
		(end 166.671498 -57.031636)
		(width 0.1524)
		(layer "In4.Cu")
		(net "M_A_DQ17")
	)
	(segment
		(start 113.919 -48.768)
		(end 113.6396 -48.4886)
		(width 0.1016)
		(layer "In4.Cu")
		(net "M_A_DQ17")
	)
	(segment
		(start 118.237 -49.0728)
		(end 117.7544 -49.5554)
		(width 0.1524)
		(layer "In4.Cu")
		(net "M_A_DQ17")
	)
	(segment
		(start 149.111462 -50.3174)
		(end 145.284444 -50.3174)
		(width 0.1524)
		(layer "In4.Cu")
		(net "M_A_DQ17")
	)
	(segment
		(start 151.074628 -52.065174)
		(end 151.271732 -51.86807)
		(width 0.1524)
		(layer "In4.Cu")
		(net "M_A_DQ17")
	)
	(segment
		(start 113.6396 -48.3362)
		(end 111.5314 -46.228)
		(width 0.1016)
		(layer "In4.Cu")
		(net "M_A_DQ17")
	)
	(segment
		(start 168.002712 -57.184036)
		(end 167.433498 -57.184036)
		(width 0.1524)
		(layer "In4.Cu")
		(net "M_A_DQ17")
	)
	(segment
		(start 166.823898 -56.3118)
		(end 166.671498 -56.4642)
		(width 0.1524)
		(layer "In4.Cu")
		(net "M_A_DQ17")
	)
	(segment
		(start 175.2473 -60.1091)
		(end 170.927776 -60.1091)
		(width 0.1524)
		(layer "In4.Cu")
		(net "M_A_DQ17")
	)
	(segment
		(start 149.56536 -50.771298)
		(end 149.111462 -50.3174)
		(width 0.1524)
		(layer "In4.Cu")
		(net "M_A_DQ17")
	)
	(segment
		(start 151.074628 -52.280566)
		(end 151.074628 -52.065174)
		(width 0.1524)
		(layer "In4.Cu")
		(net "M_A_DQ17")
	)
	(segment
		(start 117.7544 -49.5554)
		(end 114.7064 -49.5554)
		(width 0.1524)
		(layer "In4.Cu")
		(net "M_A_DQ17")
	)
	(segment
		(start 111.5314 -46.228)
		(end 110.836202 -46.228)
		(width 0.1016)
		(layer "In4.Cu")
		(net "M_A_DQ17")
	)
	(segment
		(start 143.608044 -48.641)
		(end 122.307604 -48.641)
		(width 0.1524)
		(layer "In4.Cu")
		(net "M_A_DQ17")
	)
	(segment
		(start 149.780752 -50.771298)
		(end 149.56536 -50.771298)
		(width 0.1524)
		(layer "In4.Cu")
		(net "M_A_DQ17")
	)
	(segment
		(start 110.669324 -46.394878)
		(end 110.364016 -46.394878)
		(width 0.1016)
		(layer "In4.Cu")
		(net "M_A_DQ17")
	)
	(segment
		(start 109.663738 -45.6946)
		(end 109.0676 -45.6946)
		(width 0.1016)
		(layer "In4.Cu")
		(net "M_A_DQ17")
	)
	(segment
		(start 152.845262 -54.0512)
		(end 151.074628 -52.280566)
		(width 0.1524)
		(layer "In4.Cu")
		(net "M_A_DQ17")
	)
	(segment
		(start 164.736018 -55.769764)
		(end 164.520626 -55.769764)
		(width 0.1524)
		(layer "In4.Cu")
		(net "M_A_DQ17")
	)
	(segment
		(start 178.218846 -64.782446)
		(end 178.442112 -64.55918)
		(width 0.1524)
		(layer "In4.Cu")
		(net "M_A_DQ17")
	)
	(segment
		(start 150.372572 -50.82667)
		(end 150.156672 -50.61077)
		(width 0.1524)
		(layer "In4.Cu")
		(net "M_A_DQ17")
	)
	(segment
		(start 151.271732 -51.652932)
		(end 151.055832 -51.437032)
		(width 0.1524)
		(layer "In4.Cu")
		(net "M_A_DQ17")
	)
	(segment
		(start 150.372572 -51.042062)
		(end 150.372572 -50.82667)
		(width 0.1524)
		(layer "In4.Cu")
		(net "M_A_DQ17")
	)
	(segment
		(start 150.84044 -51.437032)
		(end 150.643336 -51.633882)
		(width 0.1524)
		(layer "In4.Cu")
		(net "M_A_DQ17")
	)
	(segment
		(start 178.442112 -64.55918)
		(end 178.442112 -63.303912)
		(width 0.1524)
		(layer "In4.Cu")
		(net "M_A_DQ17")
	)
	(segment
		(start 167.281098 -56.4642)
		(end 167.128698 -56.3118)
		(width 0.1524)
		(layer "In4.Cu")
		(net "M_A_DQ17")
	)
	(segment
		(start 166.671498 -57.031636)
		(end 166.519098 -57.184036)
		(width 0.1524)
		(layer "In4.Cu")
		(net "M_A_DQ17")
	)
	(segment
		(start 17.3228 -23.3172)
		(end 17.3228 -23.241)
		(width 0.254)
		(layer "F.Cu")
		(net "P1V0_EN")
	)
	(segment
		(start 16.292322 -23.781004)
		(end 16.858996 -23.781004)
		(width 0.254)
		(layer "F.Cu")
		(net "P1V0_EN")
	)
	(segment
		(start 16.858996 -23.781004)
		(end 17.3228 -23.3172)
		(width 0.254)
		(layer "F.Cu")
		(net "P1V0_EN")
	)
	(via
		(at 17.3228 -23.241)
		(size 0.508)
		(drill 0.254)
		(layers "F.Cu" "B.Cu")
		(net "P1V0_EN")
	)
	(via
		(at 17.5514 -22.3012)
		(size 0.7112)
		(drill 0.3556)
		(layers "F.Cu" "B.Cu")
		(net "P1V0_EN")
	)
	(segment
		(start 17.3228 -22.5298)
		(end 17.3228 -23.241)
		(width 0.254)
		(layer "B.Cu")
		(net "P1V0_EN")
	)
	(segment
		(start 18.4912 -21.463)
		(end 18.4912 -22.352)
		(width 0.254)
		(layer "B.Cu")
		(net "P1V0_EN")
	)
	(segment
		(start 17.5514 -22.3012)
		(end 17.3228 -22.5298)
		(width 0.254)
		(layer "B.Cu")
		(net "P1V0_EN")
	)
	(segment
		(start 18.4404 -22.3012)
		(end 17.5514 -22.3012)
		(width 0.254)
		(layer "B.Cu")
		(net "P1V0_EN")
	)
	(segment
		(start 18.4912 -22.352)
		(end 18.4404 -22.3012)
		(width 0.254)
		(layer "B.Cu")
		(net "P1V0_EN")
	)
	(segment
		(start 114.358674 -44.6278)
		(end 112.098328 -42.367454)
		(width 0.1016)
		(layer "F.Cu")
		(net "M_A_DQS_DN3")
	)
	(segment
		(start 172.449998 -62.59322)
		(end 172.449998 -63.337694)
		(width 0.1778)
		(layer "F.Cu")
		(net "M_A_DQS_DN3")
	)
	(segment
		(start 114.8588 -44.6278)
		(end 114.358674 -44.6278)
		(width 0.1016)
		(layer "F.Cu")
		(net "M_A_DQS_DN3")
	)
	(segment
		(start 115.062 -44.4246)
		(end 114.8588 -44.6278)
		(width 0.1016)
		(layer "F.Cu")
		(net "M_A_DQS_DN3")
	)
	(segment
		(start 172.302424 -63.485268)
		(end 172.302424 -66.407538)
		(width 0.1778)
		(layer "F.Cu")
		(net "M_A_DQS_DN3")
	)
	(segment
		(start 172.449998 -63.337694)
		(end 172.302424 -63.485268)
		(width 0.1778)
		(layer "F.Cu")
		(net "M_A_DQS_DN3")
	)
	(segment
		(start 172.302424 -66.407538)
		(end 172.567092 -66.672206)
		(width 0.1778)
		(layer "F.Cu")
		(net "M_A_DQS_DN3")
	)
	(via
		(at 172.567092 -66.672206)
		(size 0.4318)
		(drill 0.2032)
		(layers "F.Cu" "B.Cu")
		(net "M_A_DQS_DN3")
	)
	(via
		(at 115.062 -44.4246)
		(size 0.4318)
		(drill 0.2032)
		(layers "F.Cu" "B.Cu")
		(net "M_A_DQS_DN3")
	)
	(segment
		(start 172.449998 -70.025006)
		(end 172.302424 -69.877432)
		(width 0.1778)
		(layer "B.Cu")
		(net "M_A_DQS_DN3")
	)
	(segment
		(start 172.302424 -66.936874)
		(end 172.567092 -66.672206)
		(width 0.1778)
		(layer "B.Cu")
		(net "M_A_DQS_DN3")
	)
	(segment
		(start 172.302424 -69.877432)
		(end 172.302424 -66.936874)
		(width 0.1778)
		(layer "B.Cu")
		(net "M_A_DQS_DN3")
	)
	(segment
		(start 172.449998 -70.79996)
		(end 172.449998 -70.025006)
		(width 0.1778)
		(layer "B.Cu")
		(net "M_A_DQS_DN3")
	)
	(segment
		(start 118.101872 -43.9928)
		(end 115.4938 -43.9928)
		(width 0.1016)
		(layer "In2.Cu")
		(net "M_A_DQS_DN3")
	)
	(segment
		(start 162.874706 -44.70146)
		(end 162.551364 -44.378118)
		(width 0.1524)
		(layer "In2.Cu")
		(net "M_A_DQS_DN3")
	)
	(segment
		(start 162.551364 -44.378118)
		(end 162.375342 -44.378118)
		(width 0.1524)
		(layer "In2.Cu")
		(net "M_A_DQS_DN3")
	)
	(segment
		(start 155.843224 -43.4086)
		(end 118.686326 -43.4086)
		(width 0.1524)
		(layer "In2.Cu")
		(net "M_A_DQS_DN3")
	)
	(segment
		(start 163.697158 -45.699934)
		(end 163.697158 -45.523912)
		(width 0.1524)
		(layer "In2.Cu")
		(net "M_A_DQS_DN3")
	)
	(segment
		(start 158.0896 -45.1104)
		(end 157.9372 -44.958)
		(width 0.1524)
		(layer "In2.Cu")
		(net "M_A_DQS_DN3")
	)
	(segment
		(start 164.898578 -46.901354)
		(end 164.519864 -46.52264)
		(width 0.1524)
		(layer "In2.Cu")
		(net "M_A_DQS_DN3")
	)
	(segment
		(start 170.49496 -56.038496)
		(end 170.318938 -56.038496)
		(width 0.1524)
		(layer "In2.Cu")
		(net "M_A_DQS_DN3")
	)
	(segment
		(start 170.318938 -56.038496)
		(end 169.99585 -55.715408)
		(width 0.1524)
		(layer "In2.Cu")
		(net "M_A_DQS_DN3")
	)
	(segment
		(start 173.0502 -58.769758)
		(end 170.818302 -56.53786)
		(width 0.1524)
		(layer "In2.Cu")
		(net "M_A_DQS_DN3")
	)
	(segment
		(start 158.862776 -43.4086)
		(end 158.5468 -43.724576)
		(width 0.1524)
		(layer "In2.Cu")
		(net "M_A_DQS_DN3")
	)
	(segment
		(start 164.196522 -46.023276)
		(end 164.0205 -46.023276)
		(width 0.1524)
		(layer "In2.Cu")
		(net "M_A_DQS_DN3")
	)
	(segment
		(start 157.9372 -43.724576)
		(end 157.621224 -43.4086)
		(width 0.1524)
		(layer "In2.Cu")
		(net "M_A_DQS_DN3")
	)
	(segment
		(start 169.173144 -54.892702)
		(end 169.173144 -54.71668)
		(width 0.1524)
		(layer "In2.Cu")
		(net "M_A_DQS_DN3")
	)
	(segment
		(start 158.5468 -44.958)
		(end 158.3944 -45.1104)
		(width 0.1524)
		(layer "In2.Cu")
		(net "M_A_DQS_DN3")
	)
	(segment
		(start 161.405824 -43.4086)
		(end 158.862776 -43.4086)
		(width 0.1524)
		(layer "In2.Cu")
		(net "M_A_DQS_DN3")
	)
	(segment
		(start 118.501668 -43.593258)
		(end 118.501668 -43.593004)
		(width 0.1016)
		(layer "In2.Cu")
		(net "M_A_DQS_DN3")
	)
	(segment
		(start 156.1592 -44.958)
		(end 156.1592 -43.724576)
		(width 0.1524)
		(layer "In2.Cu")
		(net "M_A_DQS_DN3")
	)
	(segment
		(start 156.6164 -45.1104)
		(end 156.3116 -45.1104)
		(width 0.1524)
		(layer "In2.Cu")
		(net "M_A_DQS_DN3")
	)
	(segment
		(start 163.373816 -45.20057)
		(end 163.197794 -45.20057)
		(width 0.1524)
		(layer "In2.Cu")
		(net "M_A_DQS_DN3")
	)
	(segment
		(start 164.519864 -46.346618)
		(end 164.196522 -46.023276)
		(width 0.1524)
		(layer "In2.Cu")
		(net "M_A_DQS_DN3")
	)
	(segment
		(start 172.289724 -66.1289)
		(end 172.77842 -65.640204)
		(width 0.1524)
		(layer "In2.Cu")
		(net "M_A_DQS_DN3")
	)
	(segment
		(start 164.519864 -46.52264)
		(end 164.519864 -46.346618)
		(width 0.1524)
		(layer "In2.Cu")
		(net "M_A_DQS_DN3")
	)
	(segment
		(start 162.375342 -44.378118)
		(end 161.405824 -43.4086)
		(width 0.1524)
		(layer "In2.Cu")
		(net "M_A_DQS_DN3")
	)
	(segment
		(start 172.567092 -66.672206)
		(end 172.289724 -66.394838)
		(width 0.1524)
		(layer "In2.Cu")
		(net "M_A_DQS_DN3")
	)
	(segment
		(start 173.0502 -63.5508)
		(end 173.0502 -58.769758)
		(width 0.1524)
		(layer "In2.Cu")
		(net "M_A_DQS_DN3")
	)
	(segment
		(start 169.99585 -55.715408)
		(end 169.99585 -55.539386)
		(width 0.1524)
		(layer "In2.Cu")
		(net "M_A_DQS_DN3")
	)
	(segment
		(start 169.496486 -55.216044)
		(end 169.173144 -54.892702)
		(width 0.1524)
		(layer "In2.Cu")
		(net "M_A_DQS_DN3")
	)
	(segment
		(start 158.5468 -43.724576)
		(end 158.5468 -44.958)
		(width 0.1524)
		(layer "In2.Cu")
		(net "M_A_DQS_DN3")
	)
	(segment
		(start 156.7688 -43.724576)
		(end 156.7688 -44.958)
		(width 0.1524)
		(layer "In2.Cu")
		(net "M_A_DQS_DN3")
	)
	(segment
		(start 172.289724 -66.394838)
		(end 172.289724 -66.1289)
		(width 0.1524)
		(layer "In2.Cu")
		(net "M_A_DQS_DN3")
	)
	(segment
		(start 164.898578 -50.618136)
		(end 164.898578 -46.901354)
		(width 0.1524)
		(layer "In2.Cu")
		(net "M_A_DQS_DN3")
	)
	(segment
		(start 156.7688 -44.958)
		(end 156.6164 -45.1104)
		(width 0.1524)
		(layer "In2.Cu")
		(net "M_A_DQS_DN3")
	)
	(segment
		(start 164.0205 -46.023276)
		(end 163.697158 -45.699934)
		(width 0.1524)
		(layer "In2.Cu")
		(net "M_A_DQS_DN3")
	)
	(segment
		(start 157.9372 -44.958)
		(end 157.9372 -43.724576)
		(width 0.1524)
		(layer "In2.Cu")
		(net "M_A_DQS_DN3")
	)
	(segment
		(start 157.621224 -43.4086)
		(end 157.084776 -43.4086)
		(width 0.1524)
		(layer "In2.Cu")
		(net "M_A_DQS_DN3")
	)
	(segment
		(start 115.4938 -43.9928)
		(end 115.062 -44.4246)
		(width 0.1016)
		(layer "In2.Cu")
		(net "M_A_DQS_DN3")
	)
	(segment
		(start 170.818302 -56.53786)
		(end 170.818302 -56.361838)
		(width 0.1524)
		(layer "In2.Cu")
		(net "M_A_DQS_DN3")
	)
	(segment
		(start 162.874706 -44.877482)
		(end 162.874706 -44.70146)
		(width 0.1524)
		(layer "In2.Cu")
		(net "M_A_DQS_DN3")
	)
	(segment
		(start 168.67378 -54.393338)
		(end 164.898578 -50.618136)
		(width 0.1524)
		(layer "In2.Cu")
		(net "M_A_DQS_DN3")
	)
	(segment
		(start 169.672508 -55.216044)
		(end 169.496486 -55.216044)
		(width 0.1524)
		(layer "In2.Cu")
		(net "M_A_DQS_DN3")
	)
	(segment
		(start 156.1592 -43.724576)
		(end 155.843224 -43.4086)
		(width 0.1524)
		(layer "In2.Cu")
		(net "M_A_DQS_DN3")
	)
	(segment
		(start 169.99585 -55.539386)
		(end 169.672508 -55.216044)
		(width 0.1524)
		(layer "In2.Cu")
		(net "M_A_DQS_DN3")
	)
	(segment
		(start 163.197794 -45.20057)
		(end 162.874706 -44.877482)
		(width 0.1524)
		(layer "In2.Cu")
		(net "M_A_DQS_DN3")
	)
	(segment
		(start 156.3116 -45.1104)
		(end 156.1592 -44.958)
		(width 0.1524)
		(layer "In2.Cu")
		(net "M_A_DQS_DN3")
	)
	(segment
		(start 170.818302 -56.361838)
		(end 170.49496 -56.038496)
		(width 0.1524)
		(layer "In2.Cu")
		(net "M_A_DQS_DN3")
	)
	(segment
		(start 172.77842 -63.82258)
		(end 173.0502 -63.5508)
		(width 0.1524)
		(layer "In2.Cu")
		(net "M_A_DQS_DN3")
	)
	(segment
		(start 118.686326 -43.4086)
		(end 118.501668 -43.593258)
		(width 0.1016)
		(layer "In2.Cu")
		(net "M_A_DQS_DN3")
	)
	(segment
		(start 157.084776 -43.4086)
		(end 156.7688 -43.724576)
		(width 0.1524)
		(layer "In2.Cu")
		(net "M_A_DQS_DN3")
	)
	(segment
		(start 163.697158 -45.523912)
		(end 163.373816 -45.20057)
		(width 0.1524)
		(layer "In2.Cu")
		(net "M_A_DQS_DN3")
	)
	(segment
		(start 172.77842 -65.640204)
		(end 172.77842 -63.82258)
		(width 0.1524)
		(layer "In2.Cu")
		(net "M_A_DQS_DN3")
	)
	(segment
		(start 168.849802 -54.393338)
		(end 168.67378 -54.393338)
		(width 0.1524)
		(layer "In2.Cu")
		(net "M_A_DQS_DN3")
	)
	(segment
		(start 169.173144 -54.71668)
		(end 168.849802 -54.393338)
		(width 0.1524)
		(layer "In2.Cu")
		(net "M_A_DQS_DN3")
	)
	(segment
		(start 118.501668 -43.593004)
		(end 118.101872 -43.9928)
		(width 0.1016)
		(layer "In2.Cu")
		(net "M_A_DQS_DN3")
	)
	(segment
		(start 158.3944 -45.1104)
		(end 158.0896 -45.1104)
		(width 0.1524)
		(layer "In2.Cu")
		(net "M_A_DQS_DN3")
	)
	(segment
		(start 9.975342 -23.781004)
		(end 9.942068 -23.74773)
		(width 0.254)
		(layer "F.Cu")
		(net "P1V0_TRIP")
	)
	(segment
		(start 8.485378 -22.506432)
		(end 8.559546 -22.5806)
		(width 0.254)
		(layer "F.Cu")
		(net "P1V0_TRIP")
	)
	(segment
		(start 9.7536 -23.559262)
		(end 9.942068 -23.74773)
		(width 0.254)
		(layer "F.Cu")
		(net "P1V0_TRIP")
	)
	(segment
		(start 11.647678 -23.781004)
		(end 9.975342 -23.781004)
		(width 0.254)
		(layer "F.Cu")
		(net "P1V0_TRIP")
	)
	(segment
		(start 8.559546 -22.5806)
		(end 9.0678 -22.5806)
		(width 0.254)
		(layer "F.Cu")
		(net "P1V0_TRIP")
	)
	(segment
		(start 9.0678 -22.5806)
		(end 9.7536 -23.2664)
		(width 0.254)
		(layer "F.Cu")
		(net "P1V0_TRIP")
	)
	(segment
		(start 7.9502 -22.225)
		(end 8.201152 -22.225)
		(width 0.254)
		(layer "F.Cu")
		(net "P1V0_TRIP")
	)
	(segment
		(start 9.7536 -23.2664)
		(end 9.7536 -23.559262)
		(width 0.254)
		(layer "F.Cu")
		(net "P1V0_TRIP")
	)
	(segment
		(start 8.201152 -22.225)
		(end 8.485378 -22.506432)
		(width 0.254)
		(layer "F.Cu")
		(net "P1V0_TRIP")
	)
	(via
		(at 9.942068 -23.74773)
		(size 0.7112)
		(drill 0.3556)
		(layers "F.Cu" "B.Cu")
		(net "P1V0_TRIP")
	)
	(segment
		(start 96.63684 -45.0723)
		(end 96.63684 -45.179742)
		(width 0.1016)
		(layer "F.Cu")
		(net "M_A_DQ32")
	)
	(segment
		(start 147.850098 -62.59322)
		(end 147.850098 -63.814706)
		(width 0.1778)
		(layer "F.Cu")
		(net "M_A_DQ32")
	)
	(segment
		(start 96.63684 -45.179742)
		(end 96.081088 -45.735494)
		(width 0.1016)
		(layer "F.Cu")
		(net "M_A_DQ32")
	)
	(segment
		(start 147.850098 -63.814706)
		(end 147.8788 -63.843408)
		(width 0.1778)
		(layer "F.Cu")
		(net "M_A_DQ32")
	)
	(segment
		(start 96.65716 -45.05198)
		(end 96.63684 -45.0723)
		(width 0.1016)
		(layer "F.Cu")
		(net "M_A_DQ32")
	)
	(segment
		(start 147.8788 -63.843408)
		(end 147.8788 -64.060324)
		(width 0.1778)
		(layer "F.Cu")
		(net "M_A_DQ32")
	)
	(via
		(at 147.8788 -64.060324)
		(size 0.4318)
		(drill 0.2032)
		(layers "F.Cu" "B.Cu")
		(net "M_A_DQ32")
	)
	(via
		(at 96.65716 -45.05198)
		(size 0.4318)
		(drill 0.2032)
		(layers "F.Cu" "B.Cu")
		(net "M_A_DQ32")
	)
	(segment
		(start 147.8788 -64.0588)
		(end 147.8788 -64.060324)
		(width 0.1778)
		(layer "B.Cu")
		(net "M_A_DQ32")
	)
	(segment
		(start 148.150072 -62.599824)
		(end 148.150072 -63.787528)
		(width 0.1778)
		(layer "B.Cu")
		(net "M_A_DQ32")
	)
	(segment
		(start 148.150072 -63.787528)
		(end 147.8788 -64.0588)
		(width 0.1778)
		(layer "B.Cu")
		(net "M_A_DQ32")
	)
	(segment
		(start 137.273792 -54.8386)
		(end 137.121392 -54.6862)
		(width 0.1524)
		(layer "In4.Cu")
		(net "M_A_DQ32")
	)
	(segment
		(start 137.883392 -54.8386)
		(end 137.883392 -54.98973)
		(width 0.1524)
		(layer "In4.Cu")
		(net "M_A_DQ32")
	)
	(segment
		(start 100.099368 -48.511968)
		(end 100.099368 -47.494444)
		(width 0.1016)
		(layer "In4.Cu")
		(net "M_A_DQ32")
	)
	(segment
		(start 108.3818 -54.91099)
		(end 108.3818 -54.04739)
		(width 0.1524)
		(layer "In4.Cu")
		(net "M_A_DQ32")
	)
	(segment
		(start 121.918222 -55.1942)
		(end 121.613422 -55.1942)
		(width 0.1524)
		(layer "In4.Cu")
		(net "M_A_DQ32")
	)
	(segment
		(start 147.8788 -60.833)
		(end 147.166076 -60.120276)
		(width 0.1524)
		(layer "In4.Cu")
		(net "M_A_DQ32")
	)
	(segment
		(start 135.927592 -55.14213)
		(end 135.471662 -54.6862)
		(width 0.1524)
		(layer "In4.Cu")
		(net "M_A_DQ32")
	)
	(segment
		(start 138.645392 -55.14213)
		(end 138.492992 -54.98973)
		(width 0.1524)
		(layer "In4.Cu")
		(net "M_A_DQ32")
	)
	(segment
		(start 102.63251 -51.138836)
		(end 101.73843 -50.244756)
		(width 0.1524)
		(layer "In4.Cu")
		(net "M_A_DQ32")
	)
	(segment
		(start 146.734784 -59.473592)
		(end 146.519392 -59.473592)
		(width 0.1524)
		(layer "In4.Cu")
		(net "M_A_DQ32")
	)
	(segment
		(start 124.051822 -55.1942)
		(end 123.747022 -54.8894)
		(width 0.1524)
		(layer "In4.Cu")
		(net "M_A_DQ32")
	)
	(segment
		(start 147.204684 -59.219084)
		(end 146.989292 -59.219084)
		(width 0.1524)
		(layer "In4.Cu")
		(net "M_A_DQ32")
	)
	(segment
		(start 125.621542 -55.1942)
		(end 125.469142 -55.0418)
		(width 0.1524)
		(layer "In4.Cu")
		(net "M_A_DQ32")
	)
	(segment
		(start 136.664192 -54.8386)
		(end 136.664192 -54.98973)
		(width 0.1524)
		(layer "In4.Cu")
		(net "M_A_DQ32")
	)
	(segment
		(start 124.859542 -55.0418)
		(end 124.707142 -55.1942)
		(width 0.1524)
		(layer "In4.Cu")
		(net "M_A_DQ32")
	)
	(segment
		(start 130.4798 -55.1942)
		(end 127.381 -55.1942)
		(width 0.1524)
		(layer "In4.Cu")
		(net "M_A_DQ32")
	)
	(segment
		(start 124.707142 -55.1942)
		(end 124.051822 -55.1942)
		(width 0.1524)
		(layer "In4.Cu")
		(net "M_A_DQ32")
	)
	(segment
		(start 132.701538 -54.6862)
		(end 132.193538 -55.1942)
		(width 0.1524)
		(layer "In4.Cu")
		(net "M_A_DQ32")
	)
	(segment
		(start 122.832622 -55.1942)
		(end 122.527822 -54.8894)
		(width 0.1524)
		(layer "In4.Cu")
		(net "M_A_DQ32")
	)
	(segment
		(start 137.426192 -55.14213)
		(end 137.273792 -54.98973)
		(width 0.1524)
		(layer "In4.Cu")
		(net "M_A_DQ32")
	)
	(segment
		(start 143.8656 -56.1086)
		(end 142.884906 -56.1086)
		(width 0.1524)
		(layer "In4.Cu")
		(net "M_A_DQ32")
	)
	(segment
		(start 98.5012 -45.6184)
		(end 97.9678 -46.1518)
		(width 0.1016)
		(layer "In4.Cu")
		(net "M_A_DQ32")
	)
	(segment
		(start 144.794224 -57.748424)
		(end 144.0942 -57.0484)
		(width 0.1524)
		(layer "In4.Cu")
		(net "M_A_DQ32")
	)
	(segment
		(start 123.442222 -54.8894)
		(end 123.137422 -55.1942)
		(width 0.1524)
		(layer "In4.Cu")
		(net "M_A_DQ32")
	)
	(segment
		(start 104.021636 -51.138836)
		(end 102.63251 -51.138836)
		(width 0.1524)
		(layer "In4.Cu")
		(net "M_A_DQ32")
	)
	(segment
		(start 136.816592 -54.6862)
		(end 136.664192 -54.8386)
		(width 0.1524)
		(layer "In4.Cu")
		(net "M_A_DQ32")
	)
	(segment
		(start 99.351846 -45.8216)
		(end 99.351846 -45.757846)
		(width 0.1016)
		(layer "In4.Cu")
		(net "M_A_DQ32")
	)
	(segment
		(start 100.099368 -47.494444)
		(end 99.872038 -47.267114)
		(width 0.1016)
		(layer "In4.Cu")
		(net "M_A_DQ32")
	)
	(segment
		(start 145.672048 -58.595768)
		(end 145.456148 -58.379868)
		(width 0.1524)
		(layer "In4.Cu")
		(net "M_A_DQ32")
	)
	(segment
		(start 136.664192 -54.98973)
		(end 136.511792 -55.14213)
		(width 0.1524)
		(layer "In4.Cu")
		(net "M_A_DQ32")
	)
	(segment
		(start 122.527822 -54.8894)
		(end 122.223022 -54.8894)
		(width 0.1524)
		(layer "In4.Cu")
		(net "M_A_DQ32")
	)
	(segment
		(start 145.720816 -57.899808)
		(end 145.720816 -57.68594)
		(width 0.1524)
		(layer "In4.Cu")
		(net "M_A_DQ32")
	)
	(segment
		(start 138.492992 -54.8386)
		(end 138.340592 -54.6862)
		(width 0.1524)
		(layer "In4.Cu")
		(net "M_A_DQ32")
	)
	(segment
		(start 126.1618 -55.1942)
		(end 125.621542 -55.1942)
		(width 0.1524)
		(layer "In4.Cu")
		(net "M_A_DQ32")
	)
	(segment
		(start 125.316742 -54.4322)
		(end 125.011942 -54.4322)
		(width 0.1524)
		(layer "In4.Cu")
		(net "M_A_DQ32")
	)
	(segment
		(start 145.88744 -58.595768)
		(end 145.672048 -58.595768)
		(width 0.1524)
		(layer "In4.Cu")
		(net "M_A_DQ32")
	)
	(segment
		(start 100.387912 -48.800512)
		(end 100.099368 -48.511968)
		(width 0.1016)
		(layer "In4.Cu")
		(net "M_A_DQ32")
	)
	(segment
		(start 146.303492 -59.257692)
		(end 146.303492 -59.0423)
		(width 0.1524)
		(layer "In4.Cu")
		(net "M_A_DQ32")
	)
	(segment
		(start 99.872038 -47.267114)
		(end 99.600258 -47.267114)
		(width 0.1016)
		(layer "In4.Cu")
		(net "M_A_DQ32")
	)
	(segment
		(start 137.883392 -54.98973)
		(end 137.730992 -55.14213)
		(width 0.1524)
		(layer "In4.Cu")
		(net "M_A_DQ32")
	)
	(segment
		(start 147.420584 -59.650376)
		(end 147.420584 -59.434984)
		(width 0.1524)
		(layer "In4.Cu")
		(net "M_A_DQ32")
	)
	(segment
		(start 125.469142 -54.5846)
		(end 125.316742 -54.4322)
		(width 0.1524)
		(layer "In4.Cu")
		(net "M_A_DQ32")
	)
	(segment
		(start 96.57334 -46.1518)
		(end 96.4565 -46.03496)
		(width 0.1016)
		(layer "In4.Cu")
		(net "M_A_DQ32")
	)
	(segment
		(start 126.619 -54.737)
		(end 126.1618 -55.1942)
		(width 0.1524)
		(layer "In4.Cu")
		(net "M_A_DQ32")
	)
	(segment
		(start 137.121392 -54.6862)
		(end 136.816592 -54.6862)
		(width 0.1524)
		(layer "In4.Cu")
		(net "M_A_DQ32")
	)
	(segment
		(start 137.273792 -54.98973)
		(end 137.273792 -54.8386)
		(width 0.1524)
		(layer "In4.Cu")
		(net "M_A_DQ32")
	)
	(segment
		(start 138.492992 -54.98973)
		(end 138.492992 -54.8386)
		(width 0.1524)
		(layer "In4.Cu")
		(net "M_A_DQ32")
	)
	(segment
		(start 131.318 -54.864)
		(end 130.81 -54.864)
		(width 0.1524)
		(layer "In4.Cu")
		(net "M_A_DQ32")
	)
	(segment
		(start 107.24261 -52.9082)
		(end 106.577638 -52.9082)
		(width 0.1524)
		(layer "In4.Cu")
		(net "M_A_DQ32")
	)
	(segment
		(start 146.3548 -58.3438)
		(end 146.139408 -58.3438)
		(width 0.1524)
		(layer "In4.Cu")
		(net "M_A_DQ32")
	)
	(segment
		(start 101.73843 -50.244756)
		(end 101.346 -49.852326)
		(width 0.1016)
		(layer "In4.Cu")
		(net "M_A_DQ32")
	)
	(segment
		(start 130.81 -54.864)
		(end 130.4798 -55.1942)
		(width 0.1524)
		(layer "In4.Cu")
		(net "M_A_DQ32")
	)
	(segment
		(start 145.009616 -57.748424)
		(end 144.794224 -57.748424)
		(width 0.1524)
		(layer "In4.Cu")
		(net "M_A_DQ32")
	)
	(segment
		(start 137.730992 -55.14213)
		(end 137.426192 -55.14213)
		(width 0.1524)
		(layer "In4.Cu")
		(net "M_A_DQ32")
	)
	(segment
		(start 146.5707 -58.5597)
		(end 146.3548 -58.3438)
		(width 0.1524)
		(layer "In4.Cu")
		(net "M_A_DQ32")
	)
	(segment
		(start 120.699022 -55.1942)
		(end 120.394222 -55.1942)
		(width 0.1524)
		(layer "In4.Cu")
		(net "M_A_DQ32")
	)
	(segment
		(start 145.456148 -58.379868)
		(end 145.456148 -58.164476)
		(width 0.1524)
		(layer "In4.Cu")
		(net "M_A_DQ32")
	)
	(segment
		(start 101.346 -49.852326)
		(end 101.346 -49.618646)
		(width 0.1016)
		(layer "In4.Cu")
		(net "M_A_DQ32")
	)
	(segment
		(start 144.0942 -56.3372)
		(end 143.8656 -56.1086)
		(width 0.1524)
		(layer "In4.Cu")
		(net "M_A_DQ32")
	)
	(segment
		(start 145.503392 -57.468516)
		(end 145.289524 -57.468516)
		(width 0.1524)
		(layer "In4.Cu")
		(net "M_A_DQ32")
	)
	(segment
		(start 119.479822 -55.1942)
		(end 108.66501 -55.1942)
		(width 0.1524)
		(layer "In4.Cu")
		(net "M_A_DQ32")
	)
	(segment
		(start 101.346 -49.618646)
		(end 100.527866 -48.800512)
		(width 0.1016)
		(layer "In4.Cu")
		(net "M_A_DQ32")
	)
	(segment
		(start 124.859542 -54.5846)
		(end 124.859542 -55.0418)
		(width 0.1524)
		(layer "In4.Cu")
		(net "M_A_DQ32")
	)
	(segment
		(start 146.139408 -58.3438)
		(end 145.88744 -58.595768)
		(width 0.1524)
		(layer "In4.Cu")
		(net "M_A_DQ32")
	)
	(segment
		(start 146.303492 -59.0423)
		(end 146.5707 -58.775092)
		(width 0.1524)
		(layer "In4.Cu")
		(net "M_A_DQ32")
	)
	(segment
		(start 142.884906 -56.1086)
		(end 141.918436 -55.14213)
		(width 0.1524)
		(layer "In4.Cu")
		(net "M_A_DQ32")
	)
	(segment
		(start 108.66501 -55.1942)
		(end 108.3818 -54.91099)
		(width 0.1524)
		(layer "In4.Cu")
		(net "M_A_DQ32")
	)
	(segment
		(start 121.003822 -54.8894)
		(end 120.699022 -55.1942)
		(width 0.1524)
		(layer "In4.Cu")
		(net "M_A_DQ32")
	)
	(segment
		(start 136.511792 -55.14213)
		(end 135.927592 -55.14213)
		(width 0.1524)
		(layer "In4.Cu")
		(net "M_A_DQ32")
	)
	(segment
		(start 123.747022 -54.8894)
		(end 123.442222 -54.8894)
		(width 0.1524)
		(layer "In4.Cu")
		(net "M_A_DQ32")
	)
	(segment
		(start 147.166076 -59.904884)
		(end 147.420584 -59.650376)
		(width 0.1524)
		(layer "In4.Cu")
		(net "M_A_DQ32")
	)
	(segment
		(start 99.600258 -47.267114)
		(end 99.216972 -46.883828)
		(width 0.1016)
		(layer "In4.Cu")
		(net "M_A_DQ32")
	)
	(segment
		(start 123.137422 -55.1942)
		(end 122.832622 -55.1942)
		(width 0.1524)
		(layer "In4.Cu")
		(net "M_A_DQ32")
	)
	(segment
		(start 99.2124 -45.6184)
		(end 98.5012 -45.6184)
		(width 0.1016)
		(layer "In4.Cu")
		(net "M_A_DQ32")
	)
	(segment
		(start 105.916984 -52.247546)
		(end 105.130346 -52.247546)
		(width 0.1524)
		(layer "In4.Cu")
		(net "M_A_DQ32")
	)
	(segment
		(start 131.6482 -55.1942)
		(end 131.318 -54.864)
		(width 0.1524)
		(layer "In4.Cu")
		(net "M_A_DQ32")
	)
	(segment
		(start 122.223022 -54.8894)
		(end 121.918222 -55.1942)
		(width 0.1524)
		(layer "In4.Cu")
		(net "M_A_DQ32")
	)
	(segment
		(start 125.011942 -54.4322)
		(end 124.859542 -54.5846)
		(width 0.1524)
		(layer "In4.Cu")
		(net "M_A_DQ32")
	)
	(segment
		(start 146.989292 -59.219084)
		(end 146.734784 -59.473592)
		(width 0.1524)
		(layer "In4.Cu")
		(net "M_A_DQ32")
	)
	(segment
		(start 138.035792 -54.6862)
		(end 137.883392 -54.8386)
		(width 0.1524)
		(layer "In4.Cu")
		(net "M_A_DQ32")
	)
	(segment
		(start 119.784622 -54.8894)
		(end 119.479822 -55.1942)
		(width 0.1524)
		(layer "In4.Cu")
		(net "M_A_DQ32")
	)
	(segment
		(start 135.471662 -54.6862)
		(end 132.701538 -54.6862)
		(width 0.1524)
		(layer "In4.Cu")
		(net "M_A_DQ32")
	)
	(segment
		(start 120.394222 -55.1942)
		(end 120.089422 -54.8894)
		(width 0.1524)
		(layer "In4.Cu")
		(net "M_A_DQ32")
	)
	(segment
		(start 96.4565 -45.25264)
		(end 96.65716 -45.05198)
		(width 0.1016)
		(layer "In4.Cu")
		(net "M_A_DQ32")
	)
	(segment
		(start 146.5707 -58.775092)
		(end 146.5707 -58.5597)
		(width 0.1524)
		(layer "In4.Cu")
		(net "M_A_DQ32")
	)
	(segment
		(start 145.720816 -57.68594)
		(end 145.503392 -57.468516)
		(width 0.1524)
		(layer "In4.Cu")
		(net "M_A_DQ32")
	)
	(segment
		(start 127.381 -55.1942)
		(end 126.9238 -54.737)
		(width 0.1524)
		(layer "In4.Cu")
		(net "M_A_DQ32")
	)
	(segment
		(start 99.0854 -46.566074)
		(end 99.0854 -46.4058)
		(width 0.1016)
		(layer "In4.Cu")
		(net "M_A_DQ32")
	)
	(segment
		(start 126.9238 -54.737)
		(end 126.619 -54.737)
		(width 0.1524)
		(layer "In4.Cu")
		(net "M_A_DQ32")
	)
	(segment
		(start 99.351846 -45.757846)
		(end 99.2124 -45.6184)
		(width 0.1016)
		(layer "In4.Cu")
		(net "M_A_DQ32")
	)
	(segment
		(start 108.3818 -54.04739)
		(end 107.24261 -52.9082)
		(width 0.1524)
		(layer "In4.Cu")
		(net "M_A_DQ32")
	)
	(segment
		(start 100.527866 -48.800512)
		(end 100.387912 -48.800512)
		(width 0.1016)
		(layer "In4.Cu")
		(net "M_A_DQ32")
	)
	(segment
		(start 141.918436 -55.14213)
		(end 138.645392 -55.14213)
		(width 0.1524)
		(layer "In4.Cu")
		(net "M_A_DQ32")
	)
	(segment
		(start 121.308622 -54.8894)
		(end 121.003822 -54.8894)
		(width 0.1524)
		(layer "In4.Cu")
		(net "M_A_DQ32")
	)
	(segment
		(start 121.613422 -55.1942)
		(end 121.308622 -54.8894)
		(width 0.1524)
		(layer "In4.Cu")
		(net "M_A_DQ32")
	)
	(segment
		(start 147.420584 -59.434984)
		(end 147.204684 -59.219084)
		(width 0.1524)
		(layer "In4.Cu")
		(net "M_A_DQ32")
	)
	(segment
		(start 132.193538 -55.1942)
		(end 131.6482 -55.1942)
		(width 0.1524)
		(layer "In4.Cu")
		(net "M_A_DQ32")
	)
	(segment
		(start 145.289524 -57.468516)
		(end 145.009616 -57.748424)
		(width 0.1524)
		(layer "In4.Cu")
		(net "M_A_DQ32")
	)
	(segment
		(start 105.130346 -52.247546)
		(end 104.021636 -51.138836)
		(width 0.1524)
		(layer "In4.Cu")
		(net "M_A_DQ32")
	)
	(segment
		(start 147.8788 -64.060324)
		(end 147.8788 -60.833)
		(width 0.1524)
		(layer "In4.Cu")
		(net "M_A_DQ32")
	)
	(segment
		(start 144.0942 -57.0484)
		(end 144.0942 -56.3372)
		(width 0.1524)
		(layer "In4.Cu")
		(net "M_A_DQ32")
	)
	(segment
		(start 99.256596 -46.04385)
		(end 99.26193 -46.038262)
		(width 0.1016)
		(layer "In4.Cu")
		(net "M_A_DQ32")
	)
	(segment
		(start 96.4565 -46.03496)
		(end 96.4565 -45.25264)
		(width 0.1016)
		(layer "In4.Cu")
		(net "M_A_DQ32")
	)
	(segment
		(start 106.577638 -52.9082)
		(end 105.916984 -52.247546)
		(width 0.1524)
		(layer "In4.Cu")
		(net "M_A_DQ32")
	)
	(segment
		(start 145.456148 -58.164476)
		(end 145.720816 -57.899808)
		(width 0.1524)
		(layer "In4.Cu")
		(net "M_A_DQ32")
	)
	(segment
		(start 125.469142 -55.0418)
		(end 125.469142 -54.5846)
		(width 0.1524)
		(layer "In4.Cu")
		(net "M_A_DQ32")
	)
	(segment
		(start 99.220274 -46.080172)
		(end 99.256596 -46.04385)
		(width 0.1016)
		(layer "In4.Cu")
		(net "M_A_DQ32")
	)
	(segment
		(start 120.089422 -54.8894)
		(end 119.784622 -54.8894)
		(width 0.1524)
		(layer "In4.Cu")
		(net "M_A_DQ32")
	)
	(segment
		(start 97.9678 -46.1518)
		(end 96.57334 -46.1518)
		(width 0.1016)
		(layer "In4.Cu")
		(net "M_A_DQ32")
	)
	(segment
		(start 138.340592 -54.6862)
		(end 138.035792 -54.6862)
		(width 0.1524)
		(layer "In4.Cu")
		(net "M_A_DQ32")
	)
	(segment
		(start 146.519392 -59.473592)
		(end 146.303492 -59.257692)
		(width 0.1524)
		(layer "In4.Cu")
		(net "M_A_DQ32")
	)
	(segment
		(start 147.166076 -60.120276)
		(end 147.166076 -59.904884)
		(width 0.1524)
		(layer "In4.Cu")
		(net "M_A_DQ32")
	)
	(arc
		(start 99.0854 -46.4058)
		(mid 99.120454 -46.229574)
		(end 99.220274 -46.080172)
		(width 0.1016)
		(layer "In4.Cu")
		(net "M_A_DQ32")
	)
	(arc
		(start 99.216972 -46.883828)
		(mid 99.11956 -46.738041)
		(end 99.0854 -46.566074)
		(width 0.1016)
		(layer "In4.Cu")
		(net "M_A_DQ32")
	)
	(arc
		(start 99.26193 -46.038262)
		(mid 99.328433 -45.938872)
		(end 99.351846 -45.8216)
		(width 0.1016)
		(layer "In4.Cu")
		(net "M_A_DQ32")
	)
	(segment
		(start 8.8392 -21.9202)
		(end 8.8646 -21.9202)
		(width 0.254)
		(layer "F.Cu")
		(net "P1V0_RF")
	)
	(segment
		(start 10.809478 -23.280878)
		(end 10.4648 -22.9362)
		(width 0.254)
		(layer "F.Cu")
		(net "P1V0_RF")
	)
	(segment
		(start 10.213848 -22.9362)
		(end 10.4648 -22.9362)
		(width 0.254)
		(layer "F.Cu")
		(net "P1V0_RF")
	)
	(segment
		(start 8.8646 -21.9202)
		(end 9.197848 -21.9202)
		(width 0.254)
		(layer "F.Cu")
		(net "P1V0_RF")
	)
	(segment
		(start 8.382 -21.463)
		(end 8.8392 -21.9202)
		(width 0.254)
		(layer "F.Cu")
		(net "P1V0_RF")
	)
	(segment
		(start 9.197848 -21.9202)
		(end 10.213848 -22.9362)
		(width 0.254)
		(layer "F.Cu")
		(net "P1V0_RF")
	)
	(segment
		(start 11.647678 -23.280878)
		(end 10.809478 -23.280878)
		(width 0.254)
		(layer "F.Cu")
		(net "P1V0_RF")
	)
	(segment
		(start 7.9502 -21.463)
		(end 8.382 -21.463)
		(width 0.254)
		(layer "F.Cu")
		(net "P1V0_RF")
	)
	(via
		(at 10.4648 -22.9362)
		(size 0.508)
		(drill 0.254)
		(layers "F.Cu" "B.Cu")
		(net "P1V0_RF")
	)
	(via
		(at 8.8646 -21.9202)
		(size 0.7112)
		(drill 0.3556)
		(layers "F.Cu" "B.Cu")
		(net "P1V0_RF")
	)
	(segment
		(start 10.4648 -22.9362)
		(end 10.3632 -23.0378)
		(width 0.254)
		(layer "B.Cu")
		(net "P1V0_RF")
	)
	(segment
		(start 10.3632 -23.0378)
		(end 9.017 -23.0378)
		(width 0.254)
		(layer "B.Cu")
		(net "P1V0_RF")
	)
	(segment
		(start 112.428528 -43.68927)
		(end 112.18926 -43.450002)
		(width 0.1016)
		(layer "F.Cu")
		(net "M_A_DQ31")
	)
	(segment
		(start 111.44885 -43.450002)
		(end 111.135922 -43.137074)
		(width 0.1016)
		(layer "F.Cu")
		(net "M_A_DQ31")
	)
	(segment
		(start 170.1038 -69.1388)
		(end 170.1038 -68.8086)
		(width 0.1778)
		(layer "F.Cu")
		(net "M_A_DQ31")
	)
	(segment
		(start 111.135922 -43.137074)
		(end 110.645448 -43.137074)
		(width 0.1016)
		(layer "F.Cu")
		(net "M_A_DQ31")
	)
	(segment
		(start 170.950128 -69.985128)
		(end 170.1038 -69.1388)
		(width 0.1778)
		(layer "F.Cu")
		(net "M_A_DQ31")
	)
	(segment
		(start 119.9388 -45.6946)
		(end 114.0968 -45.6946)
		(width 0.1016)
		(layer "F.Cu")
		(net "M_A_DQ31")
	)
	(segment
		(start 112.428528 -44.026328)
		(end 112.428528 -43.68927)
		(width 0.1016)
		(layer "F.Cu")
		(net "M_A_DQ31")
	)
	(segment
		(start 112.18926 -43.450002)
		(end 111.44885 -43.450002)
		(width 0.1016)
		(layer "F.Cu")
		(net "M_A_DQ31")
	)
	(segment
		(start 120.3706 -45.2628)
		(end 119.9388 -45.6946)
		(width 0.1016)
		(layer "F.Cu")
		(net "M_A_DQ31")
	)
	(segment
		(start 114.0968 -45.6946)
		(end 112.428528 -44.026328)
		(width 0.1016)
		(layer "F.Cu")
		(net "M_A_DQ31")
	)
	(segment
		(start 170.950128 -70.806564)
		(end 170.950128 -69.985128)
		(width 0.1778)
		(layer "F.Cu")
		(net "M_A_DQ31")
	)
	(via
		(at 170.1038 -68.8086)
		(size 0.4318)
		(drill 0.2032)
		(layers "F.Cu" "B.Cu")
		(net "M_A_DQ31")
	)
	(via
		(at 120.3706 -45.2628)
		(size 0.4318)
		(drill 0.2032)
		(layers "F.Cu" "B.Cu")
		(net "M_A_DQ31")
	)
	(segment
		(start 170.434 -69.436234)
		(end 170.434 -69.1134)
		(width 0.1778)
		(layer "B.Cu")
		(net "M_A_DQ31")
	)
	(segment
		(start 170.1292 -68.8086)
		(end 170.1038 -68.8086)
		(width 0.1778)
		(layer "B.Cu")
		(net "M_A_DQ31")
	)
	(segment
		(start 170.434 -69.1134)
		(end 170.1292 -68.8086)
		(width 0.1778)
		(layer "B.Cu")
		(net "M_A_DQ31")
	)
	(segment
		(start 170.049952 -70.79996)
		(end 170.050206 -70.799706)
		(width 0.1778)
		(layer "B.Cu")
		(net "M_A_DQ31")
	)
	(segment
		(start 170.050206 -69.820028)
		(end 170.434 -69.436234)
		(width 0.1778)
		(layer "B.Cu")
		(net "M_A_DQ31")
	)
	(segment
		(start 170.050206 -70.799706)
		(end 170.050206 -69.820028)
		(width 0.1778)
		(layer "B.Cu")
		(net "M_A_DQ31")
	)
	(segment
		(start 156.623004 -46.6598)
		(end 156.927804 -46.6598)
		(width 0.1524)
		(layer "In2.Cu")
		(net "M_A_DQ31")
	)
	(segment
		(start 158.451804 -47.2313)
		(end 158.756604 -47.2313)
		(width 0.1524)
		(layer "In2.Cu")
		(net "M_A_DQ31")
	)
	(segment
		(start 160.890204 -47.2313)
		(end 161.555176 -47.2313)
		(width 0.1524)
		(layer "In2.Cu")
		(net "M_A_DQ31")
	)
	(segment
		(start 155.708604 -46.6598)
		(end 155.861004 -46.8122)
		(width 0.1524)
		(layer "In2.Cu")
		(net "M_A_DQ31")
	)
	(segment
		(start 170.5864 -68.6816)
		(end 170.434 -68.834)
		(width 0.1524)
		(layer "In2.Cu")
		(net "M_A_DQ31")
	)
	(segment
		(start 160.585404 -46.6598)
		(end 160.737804 -46.8122)
		(width 0.1524)
		(layer "In2.Cu")
		(net "M_A_DQ31")
	)
	(segment
		(start 170.5864 -68.3514)
		(end 170.5864 -68.6816)
		(width 0.1524)
		(layer "In2.Cu")
		(net "M_A_DQ31")
	)
	(segment
		(start 157.232604 -47.2313)
		(end 157.537404 -47.2313)
		(width 0.1524)
		(layer "In2.Cu")
		(net "M_A_DQ31")
	)
	(segment
		(start 169.7736 -68.0466)
		(end 169.926 -68.199)
		(width 0.1524)
		(layer "In2.Cu")
		(net "M_A_DQ31")
	)
	(segment
		(start 170.434 -67.101466)
		(end 170.5864 -67.253866)
		(width 0.1524)
		(layer "In2.Cu")
		(net "M_A_DQ31")
	)
	(segment
		(start 171.27982 -61.60516)
		(end 171.77766 -62.103)
		(width 0.1524)
		(layer "In2.Cu")
		(net "M_A_DQ31")
	)
	(segment
		(start 156.013404 -47.2313)
		(end 156.318204 -47.2313)
		(width 0.1524)
		(layer "In2.Cu")
		(net "M_A_DQ31")
	)
	(segment
		(start 163.450778 -49.126902)
		(end 163.450778 -51.218084)
		(width 0.1524)
		(layer "In2.Cu")
		(net "M_A_DQ31")
	)
	(segment
		(start 171.27982 -59.047126)
		(end 171.27982 -61.60516)
		(width 0.1524)
		(layer "In2.Cu")
		(net "M_A_DQ31")
	)
	(segment
		(start 159.518604 -47.0789)
		(end 159.671004 -47.2313)
		(width 0.1524)
		(layer "In2.Cu")
		(net "M_A_DQ31")
	)
	(segment
		(start 120.3706 -45.2628)
		(end 120.777 -44.8564)
		(width 0.1016)
		(layer "In2.Cu")
		(net "M_A_DQ31")
	)
	(segment
		(start 160.128204 -47.0789)
		(end 160.128204 -46.8122)
		(width 0.1524)
		(layer "In2.Cu")
		(net "M_A_DQ31")
	)
	(segment
		(start 170.5864 -67.253866)
		(end 170.5864 -67.558666)
		(width 0.1524)
		(layer "In2.Cu")
		(net "M_A_DQ31")
	)
	(segment
		(start 159.518604 -46.8122)
		(end 159.518604 -47.0789)
		(width 0.1524)
		(layer "In2.Cu")
		(net "M_A_DQ31")
	)
	(segment
		(start 157.842204 -46.6598)
		(end 158.147004 -46.6598)
		(width 0.1524)
		(layer "In2.Cu")
		(net "M_A_DQ31")
	)
	(segment
		(start 154.4447 -47.2313)
		(end 155.099004 -47.2313)
		(width 0.1524)
		(layer "In2.Cu")
		(net "M_A_DQ31")
	)
	(segment
		(start 171.77766 -65.01638)
		(end 170.302174 -66.491866)
		(width 0.1524)
		(layer "In2.Cu")
		(net "M_A_DQ31")
	)
	(segment
		(start 169.926 -68.199)
		(end 170.434 -68.199)
		(width 0.1524)
		(layer "In2.Cu")
		(net "M_A_DQ31")
	)
	(segment
		(start 157.689804 -47.0789)
		(end 157.689804 -46.8122)
		(width 0.1524)
		(layer "In2.Cu")
		(net "M_A_DQ31")
	)
	(segment
		(start 162.052 -47.728124)
		(end 162.052 -48.1838)
		(width 0.1524)
		(layer "In2.Cu")
		(net "M_A_DQ31")
	)
	(segment
		(start 159.366204 -46.6598)
		(end 159.518604 -46.8122)
		(width 0.1524)
		(layer "In2.Cu")
		(net "M_A_DQ31")
	)
	(segment
		(start 156.470604 -46.8122)
		(end 156.623004 -46.6598)
		(width 0.1524)
		(layer "In2.Cu")
		(net "M_A_DQ31")
	)
	(segment
		(start 171.77766 -62.103)
		(end 171.77766 -65.01638)
		(width 0.1524)
		(layer "In2.Cu")
		(net "M_A_DQ31")
	)
	(segment
		(start 155.861004 -47.0789)
		(end 156.013404 -47.2313)
		(width 0.1524)
		(layer "In2.Cu")
		(net "M_A_DQ31")
	)
	(segment
		(start 155.861004 -46.8122)
		(end 155.861004 -47.0789)
		(width 0.1524)
		(layer "In2.Cu")
		(net "M_A_DQ31")
	)
	(segment
		(start 158.909004 -47.0789)
		(end 158.909004 -46.8122)
		(width 0.1524)
		(layer "In2.Cu")
		(net "M_A_DQ31")
	)
	(segment
		(start 160.737804 -47.0789)
		(end 160.890204 -47.2313)
		(width 0.1524)
		(layer "In2.Cu")
		(net "M_A_DQ31")
	)
	(segment
		(start 169.7736 -66.949066)
		(end 169.926 -67.101466)
		(width 0.1524)
		(layer "In2.Cu")
		(net "M_A_DQ31")
	)
	(segment
		(start 156.470604 -47.0789)
		(end 156.470604 -46.8122)
		(width 0.1524)
		(layer "In2.Cu")
		(net "M_A_DQ31")
	)
	(segment
		(start 158.299404 -47.0789)
		(end 158.451804 -47.2313)
		(width 0.1524)
		(layer "In2.Cu")
		(net "M_A_DQ31")
	)
	(segment
		(start 160.128204 -46.8122)
		(end 160.280604 -46.6598)
		(width 0.1524)
		(layer "In2.Cu")
		(net "M_A_DQ31")
	)
	(segment
		(start 155.099004 -47.2313)
		(end 155.251404 -47.0789)
		(width 0.1524)
		(layer "In2.Cu")
		(net "M_A_DQ31")
	)
	(segment
		(start 170.434 -68.199)
		(end 170.5864 -68.3514)
		(width 0.1524)
		(layer "In2.Cu")
		(net "M_A_DQ31")
	)
	(segment
		(start 170.434 -68.834)
		(end 170.1292 -68.834)
		(width 0.1524)
		(layer "In2.Cu")
		(net "M_A_DQ31")
	)
	(segment
		(start 162.052 -48.1838)
		(end 162.2044 -48.3362)
		(width 0.1524)
		(layer "In2.Cu")
		(net "M_A_DQ31")
	)
	(segment
		(start 158.147004 -46.6598)
		(end 158.299404 -46.8122)
		(width 0.1524)
		(layer "In2.Cu")
		(net "M_A_DQ31")
	)
	(segment
		(start 120.777 -44.8564)
		(end 152.0698 -44.8564)
		(width 0.1524)
		(layer "In2.Cu")
		(net "M_A_DQ31")
	)
	(segment
		(start 170.302174 -66.491866)
		(end 169.926 -66.491866)
		(width 0.1524)
		(layer "In2.Cu")
		(net "M_A_DQ31")
	)
	(segment
		(start 158.909004 -46.8122)
		(end 159.061404 -46.6598)
		(width 0.1524)
		(layer "In2.Cu")
		(net "M_A_DQ31")
	)
	(segment
		(start 158.756604 -47.2313)
		(end 158.909004 -47.0789)
		(width 0.1524)
		(layer "In2.Cu")
		(net "M_A_DQ31")
	)
	(segment
		(start 162.660076 -48.3362)
		(end 163.450778 -49.126902)
		(width 0.1524)
		(layer "In2.Cu")
		(net "M_A_DQ31")
	)
	(segment
		(start 161.555176 -47.2313)
		(end 162.052 -47.728124)
		(width 0.1524)
		(layer "In2.Cu")
		(net "M_A_DQ31")
	)
	(segment
		(start 156.927804 -46.6598)
		(end 157.080204 -46.8122)
		(width 0.1524)
		(layer "In2.Cu")
		(net "M_A_DQ31")
	)
	(segment
		(start 163.450778 -51.218084)
		(end 171.27982 -59.047126)
		(width 0.1524)
		(layer "In2.Cu")
		(net "M_A_DQ31")
	)
	(segment
		(start 158.299404 -46.8122)
		(end 158.299404 -47.0789)
		(width 0.1524)
		(layer "In2.Cu")
		(net "M_A_DQ31")
	)
	(segment
		(start 160.737804 -46.8122)
		(end 160.737804 -47.0789)
		(width 0.1524)
		(layer "In2.Cu")
		(net "M_A_DQ31")
	)
	(segment
		(start 159.671004 -47.2313)
		(end 159.975804 -47.2313)
		(width 0.1524)
		(layer "In2.Cu")
		(net "M_A_DQ31")
	)
	(segment
		(start 170.434 -67.711066)
		(end 169.926 -67.711066)
		(width 0.1524)
		(layer "In2.Cu")
		(net "M_A_DQ31")
	)
	(segment
		(start 152.0698 -44.8564)
		(end 154.4447 -47.2313)
		(width 0.1524)
		(layer "In2.Cu")
		(net "M_A_DQ31")
	)
	(segment
		(start 169.926 -67.101466)
		(end 170.434 -67.101466)
		(width 0.1524)
		(layer "In2.Cu")
		(net "M_A_DQ31")
	)
	(segment
		(start 157.080204 -46.8122)
		(end 157.080204 -47.0789)
		(width 0.1524)
		(layer "In2.Cu")
		(net "M_A_DQ31")
	)
	(segment
		(start 169.7736 -67.863466)
		(end 169.7736 -68.0466)
		(width 0.1524)
		(layer "In2.Cu")
		(net "M_A_DQ31")
	)
	(segment
		(start 170.5864 -67.558666)
		(end 170.434 -67.711066)
		(width 0.1524)
		(layer "In2.Cu")
		(net "M_A_DQ31")
	)
	(segment
		(start 155.251404 -47.0789)
		(end 155.251404 -46.8122)
		(width 0.1524)
		(layer "In2.Cu")
		(net "M_A_DQ31")
	)
	(segment
		(start 169.926 -66.491866)
		(end 169.7736 -66.644266)
		(width 0.1524)
		(layer "In2.Cu")
		(net "M_A_DQ31")
	)
	(segment
		(start 155.251404 -46.8122)
		(end 155.403804 -46.6598)
		(width 0.1524)
		(layer "In2.Cu")
		(net "M_A_DQ31")
	)
	(segment
		(start 157.080204 -47.0789)
		(end 157.232604 -47.2313)
		(width 0.1524)
		(layer "In2.Cu")
		(net "M_A_DQ31")
	)
	(segment
		(start 157.537404 -47.2313)
		(end 157.689804 -47.0789)
		(width 0.1524)
		(layer "In2.Cu")
		(net "M_A_DQ31")
	)
	(segment
		(start 155.403804 -46.6598)
		(end 155.708604 -46.6598)
		(width 0.1524)
		(layer "In2.Cu")
		(net "M_A_DQ31")
	)
	(segment
		(start 156.318204 -47.2313)
		(end 156.470604 -47.0789)
		(width 0.1524)
		(layer "In2.Cu")
		(net "M_A_DQ31")
	)
	(segment
		(start 159.061404 -46.6598)
		(end 159.366204 -46.6598)
		(width 0.1524)
		(layer "In2.Cu")
		(net "M_A_DQ31")
	)
	(segment
		(start 160.280604 -46.6598)
		(end 160.585404 -46.6598)
		(width 0.1524)
		(layer "In2.Cu")
		(net "M_A_DQ31")
	)
	(segment
		(start 159.975804 -47.2313)
		(end 160.128204 -47.0789)
		(width 0.1524)
		(layer "In2.Cu")
		(net "M_A_DQ31")
	)
	(segment
		(start 170.1292 -68.834)
		(end 170.1038 -68.8086)
		(width 0.1524)
		(layer "In2.Cu")
		(net "M_A_DQ31")
	)
	(segment
		(start 157.689804 -46.8122)
		(end 157.842204 -46.6598)
		(width 0.1524)
		(layer "In2.Cu")
		(net "M_A_DQ31")
	)
	(segment
		(start 162.2044 -48.3362)
		(end 162.660076 -48.3362)
		(width 0.1524)
		(layer "In2.Cu")
		(net "M_A_DQ31")
	)
	(segment
		(start 169.926 -67.711066)
		(end 169.7736 -67.863466)
		(width 0.1524)
		(layer "In2.Cu")
		(net "M_A_DQ31")
	)
	(segment
		(start 169.7736 -66.644266)
		(end 169.7736 -66.949066)
		(width 0.1524)
		(layer "In2.Cu")
		(net "M_A_DQ31")
	)
	(segment
		(start 20.3962 -21.59)
		(end 20.680172 -21.59)
		(width 0.254)
		(layer "F.Cu")
		(net "P1V0_SW_R")
	)
	(segment
		(start 20.680172 -21.59)
		(end 21.8694 -22.779228)
		(width 0.254)
		(layer "F.Cu")
		(net "P1V0_SW_R")
	)
	(segment
		(start 21.8694 -22.779228)
		(end 21.8694 -24.8158)
		(width 0.254)
		(layer "F.Cu")
		(net "P1V0_SW_R")
	)
	(via
		(at 21.6408 -26.289)
		(size 0.7112)
		(drill 0.3556)
		(layers "F.Cu" "B.Cu")
		(net "P1V0_SW_R")
	)
	(via
		(at 21.8694 -24.8158)
		(size 0.508)
		(drill 0.254)
		(layers "F.Cu" "B.Cu")
		(net "P1V0_SW_R")
	)
	(segment
		(start 21.6408 -25.0444)
		(end 21.6408 -26.289)
		(width 0.254)
		(layer "B.Cu")
		(net "P1V0_SW_R")
	)
	(segment
		(start 21.8694 -24.8158)
		(end 21.6408 -25.0444)
		(width 0.254)
		(layer "B.Cu")
		(net "P1V0_SW_R")
	)
	(segment
		(start 21.6408 -27.94)
		(end 21.6408 -26.289)
		(width 0.254)
		(layer "B.Cu")
		(net "P1V0_SW_R")
	)
	(segment
		(start 20.8788 -27.94)
		(end 21.6408 -27.94)
		(width 0.254)
		(layer "B.Cu")
		(net "P1V0_SW_R")
	)
	(segment
		(start 107.273598 -43.32605)
		(end 107.27182 -43.324272)
		(width 0.1016)
		(layer "F.Cu")
		(net "M_A_DQ11")
	)
	(segment
		(start 107.27182 -43.304206)
		(end 106.909108 -42.941494)
		(width 0.1016)
		(layer "F.Cu")
		(net "M_A_DQ11")
	)
	(segment
		(start 107.27182 -43.324272)
		(end 107.27182 -43.304206)
		(width 0.1016)
		(layer "F.Cu")
		(net "M_A_DQ11")
	)
	(segment
		(start 179.650136 -62.59322)
		(end 179.650136 -63.374016)
		(width 0.1778)
		(layer "F.Cu")
		(net "M_A_DQ11")
	)
	(segment
		(start 179.650136 -63.374016)
		(end 180.13426 -63.85814)
		(width 0.1778)
		(layer "F.Cu")
		(net "M_A_DQ11")
	)
	(segment
		(start 180.13426 -63.85814)
		(end 180.13426 -64.41694)
		(width 0.1778)
		(layer "F.Cu")
		(net "M_A_DQ11")
	)
	(segment
		(start 180.13426 -64.41694)
		(end 179.7812 -64.77)
		(width 0.1778)
		(layer "F.Cu")
		(net "M_A_DQ11")
	)
	(via
		(at 107.273598 -43.32605)
		(size 0.4318)
		(drill 0.2032)
		(layers "F.Cu" "B.Cu")
		(net "M_A_DQ11")
	)
	(via
		(at 179.7812 -64.77)
		(size 0.4318)
		(drill 0.2032)
		(layers "F.Cu" "B.Cu")
		(net "M_A_DQ11")
	)
	(segment
		(start 180.550058 -63.373762)
		(end 180.13426 -63.78956)
		(width 0.1778)
		(layer "B.Cu")
		(net "M_A_DQ11")
	)
	(segment
		(start 179.8066 -64.77)
		(end 179.7812 -64.77)
		(width 0.1778)
		(layer "B.Cu")
		(net "M_A_DQ11")
	)
	(segment
		(start 180.550058 -62.599824)
		(end 180.550058 -63.373762)
		(width 0.1778)
		(layer "B.Cu")
		(net "M_A_DQ11")
	)
	(segment
		(start 180.13426 -63.78956)
		(end 180.13426 -64.44234)
		(width 0.1778)
		(layer "B.Cu")
		(net "M_A_DQ11")
	)
	(segment
		(start 180.13426 -64.44234)
		(end 179.8066 -64.77)
		(width 0.1778)
		(layer "B.Cu")
		(net "M_A_DQ11")
	)
	(segment
		(start 110.713774 -44.7294)
		(end 112.0648 -44.7294)
		(width 0.1016)
		(layer "In4.Cu")
		(net "M_A_DQ11")
	)
	(segment
		(start 132.188458 -46.101)
		(end 121.826782 -46.101)
		(width 0.1524)
		(layer "In4.Cu")
		(net "M_A_DQ11")
	)
	(segment
		(start 117.9322 -46.6344)
		(end 117.6274 -46.9392)
		(width 0.1524)
		(layer "In4.Cu")
		(net "M_A_DQ11")
	)
	(segment
		(start 115.588288 -45.6184)
		(end 115.283488 -45.6184)
		(width 0.1524)
		(layer "In4.Cu")
		(net "M_A_DQ11")
	)
	(segment
		(start 171.7548 -57.9501)
		(end 171.7548 -57.5056)
		(width 0.1524)
		(layer "In4.Cu")
		(net "M_A_DQ11")
	)
	(segment
		(start 154.677618 -51.1556)
		(end 151.516588 -47.99457)
		(width 0.1524)
		(layer "In4.Cu")
		(net "M_A_DQ11")
	)
	(segment
		(start 121.293382 -46.6344)
		(end 117.9322 -46.6344)
		(width 0.1524)
		(layer "In4.Cu")
		(net "M_A_DQ11")
	)
	(segment
		(start 116.502688 -45.593)
		(end 116.350288 -45.7454)
		(width 0.1524)
		(layer "In4.Cu")
		(net "M_A_DQ11")
	)
	(segment
		(start 169.982642 -56.317642)
		(end 164.1221 -50.4571)
		(width 0.1524)
		(layer "In4.Cu")
		(net "M_A_DQ11")
	)
	(segment
		(start 164.1221 -50.4571)
		(end 163.7284 -50.4571)
		(width 0.1524)
		(layer "In4.Cu")
		(net "M_A_DQ11")
	)
	(segment
		(start 149.01545 -47.03445)
		(end 149.01545 -46.368716)
		(width 0.1524)
		(layer "In4.Cu")
		(net "M_A_DQ11")
	)
	(segment
		(start 121.826782 -46.101)
		(end 121.293382 -46.6344)
		(width 0.1524)
		(layer "In4.Cu")
		(net "M_A_DQ11")
	)
	(segment
		(start 132.950458 -46.482)
		(end 132.798058 -46.6344)
		(width 0.1524)
		(layer "In4.Cu")
		(net "M_A_DQ11")
	)
	(segment
		(start 174.0408 -57.3532)
		(end 173.736 -57.3532)
		(width 0.1524)
		(layer "In4.Cu")
		(net "M_A_DQ11")
	)
	(segment
		(start 151.516588 -47.517812)
		(end 151.223726 -47.22495)
		(width 0.1524)
		(layer "In4.Cu")
		(net "M_A_DQ11")
	)
	(segment
		(start 171.6024 -57.3532)
		(end 171.0182 -57.3532)
		(width 0.1524)
		(layer "In4.Cu")
		(net "M_A_DQ11")
	)
	(segment
		(start 171.7548 -57.5056)
		(end 171.6024 -57.3532)
		(width 0.1524)
		(layer "In4.Cu")
		(net "M_A_DQ11")
	)
	(segment
		(start 110.5662 -44.581826)
		(end 110.713774 -44.7294)
		(width 0.1016)
		(layer "In4.Cu")
		(net "M_A_DQ11")
	)
	(segment
		(start 149.01545 -46.368716)
		(end 148.747734 -46.101)
		(width 0.1524)
		(layer "In4.Cu")
		(net "M_A_DQ11")
	)
	(segment
		(start 115.740688 -46.8376)
		(end 115.740688 -45.7708)
		(width 0.1524)
		(layer "In4.Cu")
		(net "M_A_DQ11")
	)
	(segment
		(start 132.340858 -46.2534)
		(end 132.188458 -46.101)
		(width 0.1524)
		(layer "In4.Cu")
		(net "M_A_DQ11")
	)
	(segment
		(start 174.1932 -57.5056)
		(end 174.0408 -57.3532)
		(width 0.1524)
		(layer "In4.Cu")
		(net "M_A_DQ11")
	)
	(segment
		(start 115.131088 -46.482)
		(end 114.978688 -46.6344)
		(width 0.1524)
		(layer "In4.Cu")
		(net "M_A_DQ11")
	)
	(segment
		(start 116.959888 -46.754288)
		(end 116.959888 -45.7454)
		(width 0.1524)
		(layer "In4.Cu")
		(net "M_A_DQ11")
	)
	(segment
		(start 176.6824 -57.8866)
		(end 175.9712 -57.8866)
		(width 0.1524)
		(layer "In4.Cu")
		(net "M_A_DQ11")
	)
	(segment
		(start 174.879 -58.1025)
		(end 174.3456 -58.1025)
		(width 0.1524)
		(layer "In4.Cu")
		(net "M_A_DQ11")
	)
	(segment
		(start 173.5836 -57.5056)
		(end 173.5836 -57.9501)
		(width 0.1524)
		(layer "In4.Cu")
		(net "M_A_DQ11")
	)
	(segment
		(start 115.283488 -45.6184)
		(end 115.131088 -45.7708)
		(width 0.1524)
		(layer "In4.Cu")
		(net "M_A_DQ11")
	)
	(segment
		(start 173.5836 -57.9501)
		(end 173.4312 -58.1025)
		(width 0.1524)
		(layer "In4.Cu")
		(net "M_A_DQ11")
	)
	(segment
		(start 170.738546 -56.317642)
		(end 169.982642 -56.317642)
		(width 0.1524)
		(layer "In4.Cu")
		(net "M_A_DQ11")
	)
	(segment
		(start 180.14696 -63.4619)
		(end 180.076856 -63.391796)
		(width 0.1524)
		(layer "In4.Cu")
		(net "M_A_DQ11")
	)
	(segment
		(start 132.798058 -46.6344)
		(end 132.493258 -46.6344)
		(width 0.1524)
		(layer "In4.Cu")
		(net "M_A_DQ11")
	)
	(segment
		(start 157.2006 -50.9778)
		(end 157.0228 -51.1556)
		(width 0.1524)
		(layer "In4.Cu")
		(net "M_A_DQ11")
	)
	(segment
		(start 162.5981 -50.4571)
		(end 162.264852 -50.4571)
		(width 0.1524)
		(layer "In4.Cu")
		(net "M_A_DQ11")
	)
	(segment
		(start 116.197888 -46.99)
		(end 115.893088 -46.99)
		(width 0.1524)
		(layer "In4.Cu")
		(net "M_A_DQ11")
	)
	(segment
		(start 175.241966 -56.8198)
		(end 175.0314 -57.030366)
		(width 0.1524)
		(layer "In4.Cu")
		(net "M_A_DQ11")
	)
	(segment
		(start 175.8188 -57.7342)
		(end 175.8188 -57.023)
		(width 0.1524)
		(layer "In4.Cu")
		(net "M_A_DQ11")
	)
	(segment
		(start 115.893088 -46.99)
		(end 115.740688 -46.8376)
		(width 0.1524)
		(layer "In4.Cu")
		(net "M_A_DQ11")
	)
	(segment
		(start 132.493258 -46.6344)
		(end 132.340858 -46.482)
		(width 0.1524)
		(layer "In4.Cu")
		(net "M_A_DQ11")
	)
	(segment
		(start 175.0314 -57.9501)
		(end 174.879 -58.1025)
		(width 0.1524)
		(layer "In4.Cu")
		(net "M_A_DQ11")
	)
	(segment
		(start 158.425134 -51.1556)
		(end 157.8102 -51.1556)
		(width 0.1524)
		(layer "In4.Cu")
		(net "M_A_DQ11")
	)
	(segment
		(start 173.4312 -58.1025)
		(end 173.1264 -58.1025)
		(width 0.1524)
		(layer "In4.Cu")
		(net "M_A_DQ11")
	)
	(segment
		(start 162.9918 -50.8508)
		(end 162.5981 -50.4571)
		(width 0.1524)
		(layer "In4.Cu")
		(net "M_A_DQ11")
	)
	(segment
		(start 163.7284 -50.4571)
		(end 163.3347 -50.8508)
		(width 0.1524)
		(layer "In4.Cu")
		(net "M_A_DQ11")
	)
	(segment
		(start 170.8658 -56.9722)
		(end 170.986704 -56.851296)
		(width 0.1524)
		(layer "In4.Cu")
		(net "M_A_DQ11")
	)
	(segment
		(start 151.223726 -47.22495)
		(end 149.20595 -47.22495)
		(width 0.1524)
		(layer "In4.Cu")
		(net "M_A_DQ11")
	)
	(segment
		(start 177.7492 -58.9534)
		(end 176.6824 -57.8866)
		(width 0.1524)
		(layer "In4.Cu")
		(net "M_A_DQ11")
	)
	(segment
		(start 115.740688 -45.7708)
		(end 115.588288 -45.6184)
		(width 0.1524)
		(layer "In4.Cu")
		(net "M_A_DQ11")
	)
	(segment
		(start 149.20595 -47.22495)
		(end 149.01545 -47.03445)
		(width 0.1524)
		(layer "In4.Cu")
		(net "M_A_DQ11")
	)
	(segment
		(start 173.736 -57.3532)
		(end 173.5836 -57.5056)
		(width 0.1524)
		(layer "In4.Cu")
		(net "M_A_DQ11")
	)
	(segment
		(start 148.747734 -46.101)
		(end 133.102858 -46.101)
		(width 0.1524)
		(layer "In4.Cu")
		(net "M_A_DQ11")
	)
	(segment
		(start 117.1448 -46.9392)
		(end 116.959888 -46.754288)
		(width 0.1524)
		(layer "In4.Cu")
		(net "M_A_DQ11")
	)
	(segment
		(start 175.0314 -57.030366)
		(end 175.0314 -57.9501)
		(width 0.1524)
		(layer "In4.Cu")
		(net "M_A_DQ11")
	)
	(segment
		(start 172.3644 -57.5056)
		(end 172.3644 -57.9501)
		(width 0.1524)
		(layer "In4.Cu")
		(net "M_A_DQ11")
	)
	(segment
		(start 112.0648 -44.7294)
		(end 113.9698 -46.6344)
		(width 0.1016)
		(layer "In4.Cu")
		(net "M_A_DQ11")
	)
	(segment
		(start 133.102858 -46.101)
		(end 132.950458 -46.2534)
		(width 0.1524)
		(layer "In4.Cu")
		(net "M_A_DQ11")
	)
	(segment
		(start 151.516588 -47.99457)
		(end 151.516588 -47.517812)
		(width 0.1524)
		(layer "In4.Cu")
		(net "M_A_DQ11")
	)
	(segment
		(start 172.974 -57.9501)
		(end 172.974 -57.5056)
		(width 0.1524)
		(layer "In4.Cu")
		(net "M_A_DQ11")
	)
	(segment
		(start 171.9072 -58.1025)
		(end 171.7548 -57.9501)
		(width 0.1524)
		(layer "In4.Cu")
		(net "M_A_DQ11")
	)
	(segment
		(start 175.8188 -57.023)
		(end 175.6156 -56.8198)
		(width 0.1524)
		(layer "In4.Cu")
		(net "M_A_DQ11")
	)
	(segment
		(start 180.076856 -63.391796)
		(end 180.076856 -62.678056)
		(width 0.1524)
		(layer "In4.Cu")
		(net "M_A_DQ11")
	)
	(segment
		(start 157.6324 -50.9778)
		(end 157.2006 -50.9778)
		(width 0.1524)
		(layer "In4.Cu")
		(net "M_A_DQ11")
	)
	(segment
		(start 157.8102 -51.1556)
		(end 157.6324 -50.9778)
		(width 0.1524)
		(layer "In4.Cu")
		(net "M_A_DQ11")
	)
	(segment
		(start 132.340858 -46.482)
		(end 132.340858 -46.2534)
		(width 0.1524)
		(layer "In4.Cu")
		(net "M_A_DQ11")
	)
	(segment
		(start 116.807488 -45.593)
		(end 116.502688 -45.593)
		(width 0.1524)
		(layer "In4.Cu")
		(net "M_A_DQ11")
	)
	(segment
		(start 172.212 -58.1025)
		(end 171.9072 -58.1025)
		(width 0.1524)
		(layer "In4.Cu")
		(net "M_A_DQ11")
	)
	(segment
		(start 108.313474 -44.74718)
		(end 109.59084 -44.74718)
		(width 0.1016)
		(layer "In4.Cu")
		(net "M_A_DQ11")
	)
	(segment
		(start 180.076856 -62.678056)
		(end 177.7492 -60.3504)
		(width 0.1524)
		(layer "In4.Cu")
		(net "M_A_DQ11")
	)
	(segment
		(start 155.7528 -50.9524)
		(end 155.5496 -51.1556)
		(width 0.1524)
		(layer "In4.Cu")
		(net "M_A_DQ11")
	)
	(segment
		(start 161.871152 -50.8508)
		(end 158.729934 -50.8508)
		(width 0.1524)
		(layer "In4.Cu")
		(net "M_A_DQ11")
	)
	(segment
		(start 180.14696 -64.42964)
		(end 180.14696 -63.4619)
		(width 0.1524)
		(layer "In4.Cu")
		(net "M_A_DQ11")
	)
	(segment
		(start 115.131088 -45.7708)
		(end 115.131088 -46.482)
		(width 0.1524)
		(layer "In4.Cu")
		(net "M_A_DQ11")
	)
	(segment
		(start 170.986704 -56.5658)
		(end 170.738546 -56.317642)
		(width 0.1524)
		(layer "In4.Cu")
		(net "M_A_DQ11")
	)
	(segment
		(start 157.0228 -51.1556)
		(end 156.5148 -51.1556)
		(width 0.1524)
		(layer "In4.Cu")
		(net "M_A_DQ11")
	)
	(segment
		(start 175.6156 -56.8198)
		(end 175.241966 -56.8198)
		(width 0.1524)
		(layer "In4.Cu")
		(net "M_A_DQ11")
	)
	(segment
		(start 172.974 -57.5056)
		(end 172.8216 -57.3532)
		(width 0.1524)
		(layer "In4.Cu")
		(net "M_A_DQ11")
	)
	(segment
		(start 179.7812 -64.77)
		(end 179.8066 -64.77)
		(width 0.1524)
		(layer "In4.Cu")
		(net "M_A_DQ11")
	)
	(segment
		(start 158.729934 -50.8508)
		(end 158.425134 -51.1556)
		(width 0.1524)
		(layer "In4.Cu")
		(net "M_A_DQ11")
	)
	(segment
		(start 174.1932 -57.9501)
		(end 174.1932 -57.5056)
		(width 0.1524)
		(layer "In4.Cu")
		(net "M_A_DQ11")
	)
	(segment
		(start 170.8658 -57.2008)
		(end 170.8658 -56.9722)
		(width 0.1524)
		(layer "In4.Cu")
		(net "M_A_DQ11")
	)
	(segment
		(start 156.5148 -51.1556)
		(end 156.3116 -50.9524)
		(width 0.1524)
		(layer "In4.Cu")
		(net "M_A_DQ11")
	)
	(segment
		(start 171.0182 -57.3532)
		(end 170.8658 -57.2008)
		(width 0.1524)
		(layer "In4.Cu")
		(net "M_A_DQ11")
	)
	(segment
		(start 175.9712 -57.8866)
		(end 175.8188 -57.7342)
		(width 0.1524)
		(layer "In4.Cu")
		(net "M_A_DQ11")
	)
	(segment
		(start 113.9698 -46.6344)
		(end 114.3762 -46.6344)
		(width 0.1016)
		(layer "In4.Cu")
		(net "M_A_DQ11")
	)
	(segment
		(start 156.3116 -50.9524)
		(end 155.7528 -50.9524)
		(width 0.1524)
		(layer "In4.Cu")
		(net "M_A_DQ11")
	)
	(segment
		(start 170.986704 -56.851296)
		(end 170.986704 -56.5658)
		(width 0.1524)
		(layer "In4.Cu")
		(net "M_A_DQ11")
	)
	(segment
		(start 107.27182 -43.327828)
		(end 107.27182 -43.705526)
		(width 0.1016)
		(layer "In4.Cu")
		(net "M_A_DQ11")
	)
	(segment
		(start 155.5496 -51.1556)
		(end 154.677618 -51.1556)
		(width 0.1524)
		(layer "In4.Cu")
		(net "M_A_DQ11")
	)
	(segment
		(start 172.5168 -57.3532)
		(end 172.3644 -57.5056)
		(width 0.1524)
		(layer "In4.Cu")
		(net "M_A_DQ11")
	)
	(segment
		(start 116.350288 -46.8376)
		(end 116.197888 -46.99)
		(width 0.1524)
		(layer "In4.Cu")
		(net "M_A_DQ11")
	)
	(segment
		(start 107.273598 -43.32605)
		(end 107.27182 -43.327828)
		(width 0.1016)
		(layer "In4.Cu")
		(net "M_A_DQ11")
	)
	(segment
		(start 109.756194 -44.581826)
		(end 110.5662 -44.581826)
		(width 0.1016)
		(layer "In4.Cu")
		(net "M_A_DQ11")
	)
	(segment
		(start 163.3347 -50.8508)
		(end 162.9918 -50.8508)
		(width 0.1524)
		(layer "In4.Cu")
		(net "M_A_DQ11")
	)
	(segment
		(start 162.264852 -50.4571)
		(end 161.871152 -50.8508)
		(width 0.1524)
		(layer "In4.Cu")
		(net "M_A_DQ11")
	)
	(segment
		(start 109.59084 -44.74718)
		(end 109.756194 -44.581826)
		(width 0.1016)
		(layer "In4.Cu")
		(net "M_A_DQ11")
	)
	(segment
		(start 179.8066 -64.77)
		(end 180.14696 -64.42964)
		(width 0.1524)
		(layer "In4.Cu")
		(net "M_A_DQ11")
	)
	(segment
		(start 117.6274 -46.9392)
		(end 117.1448 -46.9392)
		(width 0.1524)
		(layer "In4.Cu")
		(net "M_A_DQ11")
	)
	(segment
		(start 173.1264 -58.1025)
		(end 172.974 -57.9501)
		(width 0.1524)
		(layer "In4.Cu")
		(net "M_A_DQ11")
	)
	(segment
		(start 114.978688 -46.6344)
		(end 114.3762 -46.6344)
		(width 0.1524)
		(layer "In4.Cu")
		(net "M_A_DQ11")
	)
	(segment
		(start 177.7492 -60.3504)
		(end 177.7492 -58.9534)
		(width 0.1524)
		(layer "In4.Cu")
		(net "M_A_DQ11")
	)
	(segment
		(start 174.3456 -58.1025)
		(end 174.1932 -57.9501)
		(width 0.1524)
		(layer "In4.Cu")
		(net "M_A_DQ11")
	)
	(segment
		(start 172.3644 -57.9501)
		(end 172.212 -58.1025)
		(width 0.1524)
		(layer "In4.Cu")
		(net "M_A_DQ11")
	)
	(segment
		(start 116.959888 -45.7454)
		(end 116.807488 -45.593)
		(width 0.1524)
		(layer "In4.Cu")
		(net "M_A_DQ11")
	)
	(segment
		(start 132.950458 -46.2534)
		(end 132.950458 -46.482)
		(width 0.1524)
		(layer "In4.Cu")
		(net "M_A_DQ11")
	)
	(segment
		(start 116.350288 -45.7454)
		(end 116.350288 -46.8376)
		(width 0.1524)
		(layer "In4.Cu")
		(net "M_A_DQ11")
	)
	(segment
		(start 107.27182 -43.705526)
		(end 108.313474 -44.74718)
		(width 0.1016)
		(layer "In4.Cu")
		(net "M_A_DQ11")
	)
	(segment
		(start 172.8216 -57.3532)
		(end 172.5168 -57.3532)
		(width 0.1524)
		(layer "In4.Cu")
		(net "M_A_DQ11")
	)
	(segment
		(start 11.647678 -24.280876)
		(end 10.872724 -24.280876)
		(width 0.254)
		(layer "F.Cu")
		(net "P1V0_MODE")
	)
	(segment
		(start 10.872724 -24.280876)
		(end 10.7696 -24.384)
		(width 0.254)
		(layer "F.Cu")
		(net "P1V0_MODE")
	)
	(segment
		(start 10.7696 -24.384)
		(end 10.668 -24.384)
		(width 0.254)
		(layer "F.Cu")
		(net "P1V0_MODE")
	)
	(via
		(at 10.668 -24.384)
		(size 0.508)
		(drill 0.254)
		(layers "F.Cu" "B.Cu")
		(net "P1V0_MODE")
	)
	(via
		(at 7.239 -23.749)
		(size 0.7112)
		(drill 0.3556)
		(layers "F.Cu" "B.Cu")
		(net "P1V0_MODE")
	)
	(segment
		(start 8.255 -23.241)
		(end 8.255 -23.0378)
		(width 0.254)
		(layer "B.Cu")
		(net "P1V0_MODE")
	)
	(segment
		(start 8.0772 -24.384)
		(end 7.874 -24.384)
		(width 0.254)
		(layer "B.Cu")
		(net "P1V0_MODE")
	)
	(segment
		(start 7.9502 -23.0378)
		(end 8.255 -23.0378)
		(width 0.254)
		(layer "B.Cu")
		(net "P1V0_MODE")
	)
	(segment
		(start 10.668 -24.384)
		(end 9.906 -23.622)
		(width 0.254)
		(layer "B.Cu")
		(net "P1V0_MODE")
	)
	(segment
		(start 9.906 -23.622)
		(end 8.636 -23.622)
		(width 0.254)
		(layer "B.Cu")
		(net "P1V0_MODE")
	)
	(segment
		(start 7.874 -24.384)
		(end 7.239 -23.749)
		(width 0.254)
		(layer "B.Cu")
		(net "P1V0_MODE")
	)
	(segment
		(start 8.636 -23.622)
		(end 8.255 -23.241)
		(width 0.254)
		(layer "B.Cu")
		(net "P1V0_MODE")
	)
	(segment
		(start 7.239 -23.749)
		(end 7.9502 -23.0378)
		(width 0.254)
		(layer "B.Cu")
		(net "P1V0_MODE")
	)
	(segment
		(start 108.814108 -44.927774)
		(end 109.118654 -44.927774)
		(width 0.1016)
		(layer "F.Cu")
		(net "M_A_DQ20")
	)
	(segment
		(start 109.118654 -44.927774)
		(end 109.30636 -45.11548)
		(width 0.1016)
		(layer "F.Cu")
		(net "M_A_DQ20")
	)
	(segment
		(start 179.350162 -69.80301)
		(end 178.886358 -69.339206)
		(width 0.1778)
		(layer "F.Cu")
		(net "M_A_DQ20")
	)
	(segment
		(start 179.350162 -70.806564)
		(end 179.350162 -69.80301)
		(width 0.1778)
		(layer "F.Cu")
		(net "M_A_DQ20")
	)
	(via
		(at 109.30636 -45.11548)
		(size 0.4318)
		(drill 0.2032)
		(layers "F.Cu" "B.Cu")
		(net "M_A_DQ20")
	)
	(via
		(at 178.886358 -69.339206)
		(size 0.4318)
		(drill 0.2032)
		(layers "F.Cu" "B.Cu")
		(net "M_A_DQ20")
	)
	(segment
		(start 178.886104 -69.583554)
		(end 178.886104 -69.33946)
		(width 0.1778)
		(layer "B.Cu")
		(net "M_A_DQ20")
	)
	(segment
		(start 178.886104 -69.33946)
		(end 178.886358 -69.339206)
		(width 0.1778)
		(layer "B.Cu")
		(net "M_A_DQ20")
	)
	(segment
		(start 178.449986 -70.79996)
		(end 178.449986 -70.019672)
		(width 0.1778)
		(layer "B.Cu")
		(net "M_A_DQ20")
	)
	(segment
		(start 178.449986 -70.019672)
		(end 178.886104 -69.583554)
		(width 0.1778)
		(layer "B.Cu")
		(net "M_A_DQ20")
	)
	(segment
		(start 110.511082 -45.331634)
		(end 110.095538 -45.331634)
		(width 0.1016)
		(layer "In4.Cu")
		(net "M_A_DQ20")
	)
	(segment
		(start 178.8414 -69.294248)
		(end 178.8414 -67.6783)
		(width 0.1524)
		(layer "In4.Cu")
		(net "M_A_DQ20")
	)
	(segment
		(start 179.038758 -67.480942)
		(end 179.4002 -67.480942)
		(width 0.1524)
		(layer "In4.Cu")
		(net "M_A_DQ20")
	)
	(segment
		(start 147.545552 -49.149)
		(end 147.393152 -48.9966)
		(width 0.1524)
		(layer "In4.Cu")
		(net "M_A_DQ20")
	)
	(segment
		(start 179.28336 -65.14592)
		(end 179.28336 -62.64656)
		(width 0.1524)
		(layer "In4.Cu")
		(net "M_A_DQ20")
	)
	(segment
		(start 125.9078 -47.4726)
		(end 125.3744 -46.9392)
		(width 0.1524)
		(layer "In4.Cu")
		(net "M_A_DQ20")
	)
	(segment
		(start 147.240752 -48.6918)
		(end 146.935952 -48.6918)
		(width 0.1524)
		(layer "In4.Cu")
		(net "M_A_DQ20")
	)
	(segment
		(start 146.935952 -48.6918)
		(end 146.783552 -48.8442)
		(width 0.1524)
		(layer "In4.Cu")
		(net "M_A_DQ20")
	)
	(segment
		(start 176.9364 -60.2996)
		(end 176.9364 -59.7154)
		(width 0.1524)
		(layer "In4.Cu")
		(net "M_A_DQ20")
	)
	(segment
		(start 178.886358 -69.339206)
		(end 178.8414 -69.294248)
		(width 0.1524)
		(layer "In4.Cu")
		(net "M_A_DQ20")
	)
	(segment
		(start 111.845344 -45.177202)
		(end 110.665514 -45.177202)
		(width 0.1016)
		(layer "In4.Cu")
		(net "M_A_DQ20")
	)
	(segment
		(start 114.980974 -47.5742)
		(end 114.242342 -47.5742)
		(width 0.1016)
		(layer "In4.Cu")
		(net "M_A_DQ20")
	)
	(segment
		(start 179.5526 -67.023742)
		(end 179.4002 -66.871342)
		(width 0.1524)
		(layer "In4.Cu")
		(net "M_A_DQ20")
	)
	(segment
		(start 178.8414 -67.6783)
		(end 179.038758 -67.480942)
		(width 0.1524)
		(layer "In4.Cu")
		(net "M_A_DQ20")
	)
	(segment
		(start 175.5775 -58.9407)
		(end 171.4119 -58.9407)
		(width 0.1524)
		(layer "In4.Cu")
		(net "M_A_DQ20")
	)
	(segment
		(start 176.53 -59.309)
		(end 175.9458 -59.309)
		(width 0.1524)
		(layer "In4.Cu")
		(net "M_A_DQ20")
	)
	(segment
		(start 114.242342 -47.5742)
		(end 111.845344 -45.177202)
		(width 0.1016)
		(layer "In4.Cu")
		(net "M_A_DQ20")
	)
	(segment
		(start 121.539 -47.5742)
		(end 114.980974 -47.5742)
		(width 0.1524)
		(layer "In4.Cu")
		(net "M_A_DQ20")
	)
	(segment
		(start 175.9458 -59.309)
		(end 175.5775 -58.9407)
		(width 0.1524)
		(layer "In4.Cu")
		(net "M_A_DQ20")
	)
	(segment
		(start 147.393152 -48.8442)
		(end 147.240752 -48.6918)
		(width 0.1524)
		(layer "In4.Cu")
		(net "M_A_DQ20")
	)
	(segment
		(start 179.038758 -66.871342)
		(end 178.886358 -66.718942)
		(width 0.1524)
		(layer "In4.Cu")
		(net "M_A_DQ20")
	)
	(segment
		(start 179.28336 -62.64656)
		(end 176.9364 -60.2996)
		(width 0.1524)
		(layer "In4.Cu")
		(net "M_A_DQ20")
	)
	(segment
		(start 179.3748 -66.167)
		(end 179.5272 -66.0146)
		(width 0.1524)
		(layer "In4.Cu")
		(net "M_A_DQ20")
	)
	(segment
		(start 147.393152 -48.9966)
		(end 147.393152 -48.8442)
		(width 0.1524)
		(layer "In4.Cu")
		(net "M_A_DQ20")
	)
	(segment
		(start 165.862 -53.3908)
		(end 155.7274 -53.3908)
		(width 0.1524)
		(layer "In4.Cu")
		(net "M_A_DQ20")
	)
	(segment
		(start 155.7274 -53.3908)
		(end 151.4856 -49.149)
		(width 0.1524)
		(layer "In4.Cu")
		(net "M_A_DQ20")
	)
	(segment
		(start 145.768568 -49.149)
		(end 144.092168 -47.4726)
		(width 0.1524)
		(layer "In4.Cu")
		(net "M_A_DQ20")
	)
	(segment
		(start 179.5272 -66.0146)
		(end 179.5272 -65.38976)
		(width 0.1524)
		(layer "In4.Cu")
		(net "M_A_DQ20")
	)
	(segment
		(start 176.9364 -59.7154)
		(end 176.53 -59.309)
		(width 0.1524)
		(layer "In4.Cu")
		(net "M_A_DQ20")
	)
	(segment
		(start 146.783552 -48.9966)
		(end 146.631152 -49.149)
		(width 0.1524)
		(layer "In4.Cu")
		(net "M_A_DQ20")
	)
	(segment
		(start 179.5272 -65.38976)
		(end 179.28336 -65.14592)
		(width 0.1524)
		(layer "In4.Cu")
		(net "M_A_DQ20")
	)
	(segment
		(start 110.095538 -45.331634)
		(end 109.879384 -45.11548)
		(width 0.1016)
		(layer "In4.Cu")
		(net "M_A_DQ20")
	)
	(segment
		(start 179.07 -66.167)
		(end 179.3748 -66.167)
		(width 0.1524)
		(layer "In4.Cu")
		(net "M_A_DQ20")
	)
	(segment
		(start 109.879384 -45.11548)
		(end 109.30636 -45.11548)
		(width 0.1016)
		(layer "In4.Cu")
		(net "M_A_DQ20")
	)
	(segment
		(start 179.4002 -67.480942)
		(end 179.5526 -67.328542)
		(width 0.1524)
		(layer "In4.Cu")
		(net "M_A_DQ20")
	)
	(segment
		(start 179.4002 -66.871342)
		(end 179.038758 -66.871342)
		(width 0.1524)
		(layer "In4.Cu")
		(net "M_A_DQ20")
	)
	(segment
		(start 146.783552 -48.8442)
		(end 146.783552 -48.9966)
		(width 0.1524)
		(layer "In4.Cu")
		(net "M_A_DQ20")
	)
	(segment
		(start 146.631152 -49.149)
		(end 145.768568 -49.149)
		(width 0.1524)
		(layer "In4.Cu")
		(net "M_A_DQ20")
	)
	(segment
		(start 144.092168 -47.4726)
		(end 125.9078 -47.4726)
		(width 0.1524)
		(layer "In4.Cu")
		(net "M_A_DQ20")
	)
	(segment
		(start 179.5526 -67.328542)
		(end 179.5526 -67.023742)
		(width 0.1524)
		(layer "In4.Cu")
		(net "M_A_DQ20")
	)
	(segment
		(start 178.886358 -66.350642)
		(end 179.07 -66.167)
		(width 0.1524)
		(layer "In4.Cu")
		(net "M_A_DQ20")
	)
	(segment
		(start 178.886358 -66.718942)
		(end 178.886358 -66.350642)
		(width 0.1524)
		(layer "In4.Cu")
		(net "M_A_DQ20")
	)
	(segment
		(start 125.3744 -46.9392)
		(end 122.174 -46.9392)
		(width 0.1524)
		(layer "In4.Cu")
		(net "M_A_DQ20")
	)
	(segment
		(start 151.4856 -49.149)
		(end 147.545552 -49.149)
		(width 0.1524)
		(layer "In4.Cu")
		(net "M_A_DQ20")
	)
	(segment
		(start 122.174 -46.9392)
		(end 121.539 -47.5742)
		(width 0.1524)
		(layer "In4.Cu")
		(net "M_A_DQ20")
	)
	(segment
		(start 110.665514 -45.177202)
		(end 110.511082 -45.331634)
		(width 0.1016)
		(layer "In4.Cu")
		(net "M_A_DQ20")
	)
	(segment
		(start 171.4119 -58.9407)
		(end 165.862 -53.3908)
		(width 0.1524)
		(layer "In4.Cu")
		(net "M_A_DQ20")
	)
	(segment
		(start 62.3062 -22.479)
		(end 60.1218 -22.479)
		(width 0.254)
		(layer "F.Cu")
		(net "PWRGD_P1V0_PG")
	)
	(via
		(at 60.1218 -22.479)
		(size 0.508)
		(drill 0.254)
		(layers "F.Cu" "B.Cu")
		(net "PWRGD_P1V0_PG")
	)
	(via
		(at 33.923732 -23.311866)
		(size 0.508)
		(drill 0.254)
		(layers "F.Cu" "B.Cu")
		(net "PWRGD_P1V0_PG")
	)
	(via
		(at 27.178 -19.05)
		(size 0.7112)
		(drill 0.3556)
		(layers "F.Cu" "B.Cu")
		(net "PWRGD_P1V0_PG")
	)
	(segment
		(start 31.709106 -22.4282)
		(end 33.323276 -22.4282)
		(width 0.254)
		(layer "B.Cu")
		(net "PWRGD_P1V0_PG")
	)
	(segment
		(start 28.431744 -19.05)
		(end 30.096714 -20.71497)
		(width 0.254)
		(layer "B.Cu")
		(net "PWRGD_P1V0_PG")
	)
	(segment
		(start 33.923732 -23.028656)
		(end 33.923732 -23.311866)
		(width 0.254)
		(layer "B.Cu")
		(net "PWRGD_P1V0_PG")
	)
	(segment
		(start 33.323276 -22.4282)
		(end 33.923732 -23.028656)
		(width 0.254)
		(layer "B.Cu")
		(net "PWRGD_P1V0_PG")
	)
	(segment
		(start 27.178 -19.05)
		(end 26.307796 -19.920204)
		(width 0.254)
		(layer "B.Cu")
		(net "PWRGD_P1V0_PG")
	)
	(segment
		(start 27.178 -19.05)
		(end 28.431744 -19.05)
		(width 0.254)
		(layer "B.Cu")
		(net "PWRGD_P1V0_PG")
	)
	(segment
		(start 30.096714 -20.815808)
		(end 31.709106 -22.4282)
		(width 0.254)
		(layer "B.Cu")
		(net "PWRGD_P1V0_PG")
	)
	(segment
		(start 30.096714 -20.71497)
		(end 30.096714 -20.815808)
		(width 0.254)
		(layer "B.Cu")
		(net "PWRGD_P1V0_PG")
	)
	(segment
		(start 26.307796 -19.920204)
		(end 17.874996 -19.920204)
		(width 0.254)
		(layer "B.Cu")
		(net "PWRGD_P1V0_PG")
	)
	(segment
		(start 17.874996 -19.920204)
		(end 16.383 -21.4122)
		(width 0.254)
		(layer "B.Cu")
		(net "PWRGD_P1V0_PG")
	)
	(segment
		(start 48.133 -20.574)
		(end 48.8442 -19.8628)
		(width 0.254)
		(layer "In4.Cu")
		(net "PWRGD_P1V0_PG")
	)
	(segment
		(start 34.72688 -21.9837)
		(end 40.344852 -21.9837)
		(width 0.254)
		(layer "In4.Cu")
		(net "PWRGD_P1V0_PG")
	)
	(segment
		(start 33.9344 -22.77618)
		(end 34.72688 -21.9837)
		(width 0.254)
		(layer "In4.Cu")
		(net "PWRGD_P1V0_PG")
	)
	(segment
		(start 60.095384 -22.452584)
		(end 60.1218 -22.479)
		(width 0.254)
		(layer "In4.Cu")
		(net "PWRGD_P1V0_PG")
	)
	(segment
		(start 33.9344 -23.301198)
		(end 33.9344 -22.77618)
		(width 0.254)
		(layer "In4.Cu")
		(net "PWRGD_P1V0_PG")
	)
	(segment
		(start 48.8442 -19.8628)
		(end 50.4952 -19.8628)
		(width 0.254)
		(layer "In4.Cu")
		(net "PWRGD_P1V0_PG")
	)
	(segment
		(start 50.4952 -19.8628)
		(end 53.4416 -22.8092)
		(width 0.254)
		(layer "In4.Cu")
		(net "PWRGD_P1V0_PG")
	)
	(segment
		(start 45.3898 -20.574)
		(end 48.133 -20.574)
		(width 0.254)
		(layer "In4.Cu")
		(net "PWRGD_P1V0_PG")
	)
	(segment
		(start 53.4416 -22.8092)
		(end 54.6608 -22.8092)
		(width 0.254)
		(layer "In4.Cu")
		(net "PWRGD_P1V0_PG")
	)
	(segment
		(start 41.475152 -20.8534)
		(end 45.1104 -20.8534)
		(width 0.254)
		(layer "In4.Cu")
		(net "PWRGD_P1V0_PG")
	)
	(segment
		(start 54.6608 -22.8092)
		(end 55.017416 -22.452584)
		(width 0.254)
		(layer "In4.Cu")
		(net "PWRGD_P1V0_PG")
	)
	(segment
		(start 33.923732 -23.311866)
		(end 33.9344 -23.301198)
		(width 0.254)
		(layer "In4.Cu")
		(net "PWRGD_P1V0_PG")
	)
	(segment
		(start 40.344852 -21.9837)
		(end 41.475152 -20.8534)
		(width 0.254)
		(layer "In4.Cu")
		(net "PWRGD_P1V0_PG")
	)
	(segment
		(start 45.1104 -20.8534)
		(end 45.3898 -20.574)
		(width 0.254)
		(layer "In4.Cu")
		(net "PWRGD_P1V0_PG")
	)
	(segment
		(start 55.017416 -22.452584)
		(end 60.095384 -22.452584)
		(width 0.254)
		(layer "In4.Cu")
		(net "PWRGD_P1V0_PG")
	)
	(segment
		(start 136.29767 -69.906134)
		(end 136.29767 -66.937128)
		(width 0.1778)
		(layer "F.Cu")
		(net "M_A_DQS_DP6")
	)
	(segment
		(start 99.5934 -54.2798)
		(end 99.2886 -53.975)
		(width 0.1016)
		(layer "F.Cu")
		(net "M_A_DQS_DP6")
	)
	(segment
		(start 99.2886 -53.043328)
		(end 99.388168 -52.94376)
		(width 0.1016)
		(layer "F.Cu")
		(net "M_A_DQS_DP6")
	)
	(segment
		(start 99.2886 -53.975)
		(end 99.2886 -53.043328)
		(width 0.1016)
		(layer "F.Cu")
		(net "M_A_DQS_DP6")
	)
	(segment
		(start 99.388168 -52.108354)
		(end 99.489768 -52.006754)
		(width 0.1016)
		(layer "F.Cu")
		(net "M_A_DQS_DP6")
	)
	(segment
		(start 99.388168 -52.94376)
		(end 99.388168 -52.108354)
		(width 0.1016)
		(layer "F.Cu")
		(net "M_A_DQS_DP6")
	)
	(segment
		(start 136.150096 -70.053708)
		(end 136.29767 -69.906134)
		(width 0.1778)
		(layer "F.Cu")
		(net "M_A_DQS_DP6")
	)
	(segment
		(start 136.150096 -70.806564)
		(end 136.150096 -70.053708)
		(width 0.1778)
		(layer "F.Cu")
		(net "M_A_DQS_DP6")
	)
	(segment
		(start 136.29767 -66.937128)
		(end 136.032748 -66.672206)
		(width 0.1778)
		(layer "F.Cu")
		(net "M_A_DQS_DP6")
	)
	(via
		(at 136.032748 -66.672206)
		(size 0.4318)
		(drill 0.2032)
		(layers "F.Cu" "B.Cu")
		(net "M_A_DQS_DP6")
	)
	(via
		(at 99.5934 -54.2798)
		(size 0.4318)
		(drill 0.2032)
		(layers "F.Cu" "B.Cu")
		(net "M_A_DQS_DP6")
	)
	(segment
		(start 136.150096 -63.392304)
		(end 136.346692 -63.5889)
		(width 0.1778)
		(layer "B.Cu")
		(net "M_A_DQS_DP6")
	)
	(segment
		(start 136.346692 -63.5889)
		(end 136.346692 -66.358262)
		(width 0.1778)
		(layer "B.Cu")
		(net "M_A_DQS_DP6")
	)
	(segment
		(start 136.346692 -66.358262)
		(end 136.032748 -66.672206)
		(width 0.1778)
		(layer "B.Cu")
		(net "M_A_DQS_DP6")
	)
	(segment
		(start 136.150096 -62.599824)
		(end 136.150096 -63.392304)
		(width 0.1778)
		(layer "B.Cu")
		(net "M_A_DQS_DP6")
	)
	(segment
		(start 100.296726 -59.225434)
		(end 100.296726 -59.049412)
		(width 0.1524)
		(layer "In4.Cu")
		(net "M_A_DQS_DP6")
	)
	(segment
		(start 99.5299 -58.282586)
		(end 99.5299 -56.8579)
		(width 0.1524)
		(layer "In4.Cu")
		(net "M_A_DQS_DP6")
	)
	(segment
		(start 106.130344 -64.8716)
		(end 106.005884 -64.99606)
		(width 0.1524)
		(layer "In4.Cu")
		(net "M_A_DQS_DP6")
	)
	(segment
		(start 125.036326 -62.68466)
		(end 124.579126 -62.68466)
		(width 0.1524)
		(layer "In4.Cu")
		(net "M_A_DQS_DP6")
	)
	(segment
		(start 103.620824 -64.036448)
		(end 103.620824 -63.535052)
		(width 0.1524)
		(layer "In4.Cu")
		(net "M_A_DQS_DP6")
	)
	(segment
		(start 101.44252 -60.371228)
		(end 101.119432 -60.04814)
		(width 0.1524)
		(layer "In4.Cu")
		(net "M_A_DQS_DP6")
	)
	(segment
		(start 101.618542 -60.371228)
		(end 101.44252 -60.371228)
		(width 0.1524)
		(layer "In4.Cu")
		(net "M_A_DQS_DP6")
	)
	(segment
		(start 102.265226 -61.193934)
		(end 101.941884 -60.870592)
		(width 0.1524)
		(layer "In4.Cu")
		(net "M_A_DQS_DP6")
	)
	(segment
		(start 124.454666 -62.5602)
		(end 123.852178 -62.5602)
		(width 0.1524)
		(layer "In4.Cu")
		(net "M_A_DQS_DP6")
	)
	(segment
		(start 124.579126 -62.68466)
		(end 124.454666 -62.5602)
		(width 0.1524)
		(layer "In4.Cu")
		(net "M_A_DQS_DP6")
	)
	(segment
		(start 135.4074 -62.5602)
		(end 125.160786 -62.5602)
		(width 0.1524)
		(layer "In4.Cu")
		(net "M_A_DQS_DP6")
	)
	(segment
		(start 101.941884 -60.870592)
		(end 101.941884 -60.69457)
		(width 0.1524)
		(layer "In4.Cu")
		(net "M_A_DQS_DP6")
	)
	(segment
		(start 103.336598 -62.089284)
		(end 102.441248 -61.193934)
		(width 0.1524)
		(layer "In4.Cu")
		(net "M_A_DQS_DP6")
	)
	(segment
		(start 101.941884 -60.69457)
		(end 101.618542 -60.371228)
		(width 0.1524)
		(layer "In4.Cu")
		(net "M_A_DQS_DP6")
	)
	(segment
		(start 103.620824 -62.371732)
		(end 103.338376 -62.089284)
		(width 0.1524)
		(layer "In4.Cu")
		(net "M_A_DQS_DP6")
	)
	(segment
		(start 121.982738 -62.5602)
		(end 121.525538 -62.5602)
		(width 0.1524)
		(layer "In4.Cu")
		(net "M_A_DQS_DP6")
	)
	(segment
		(start 122.564398 -62.68466)
		(end 122.107198 -62.68466)
		(width 0.1524)
		(layer "In4.Cu")
		(net "M_A_DQS_DP6")
	)
	(segment
		(start 106.712004 -64.99606)
		(end 106.587544 -64.8716)
		(width 0.1524)
		(layer "In4.Cu")
		(net "M_A_DQS_DP6")
	)
	(segment
		(start 136.6774 -65.644776)
		(end 136.6774 -63.8302)
		(width 0.1524)
		(layer "In4.Cu")
		(net "M_A_DQS_DP6")
	)
	(segment
		(start 122.107198 -62.68466)
		(end 121.982738 -62.5602)
		(width 0.1524)
		(layer "In4.Cu")
		(net "M_A_DQS_DP6")
	)
	(segment
		(start 106.005884 -64.99606)
		(end 105.548684 -64.99606)
		(width 0.1524)
		(layer "In4.Cu")
		(net "M_A_DQS_DP6")
	)
	(segment
		(start 122.688858 -62.5602)
		(end 122.564398 -62.68466)
		(width 0.1524)
		(layer "In4.Cu")
		(net "M_A_DQS_DP6")
	)
	(segment
		(start 123.727718 -62.68466)
		(end 123.270518 -62.68466)
		(width 0.1524)
		(layer "In4.Cu")
		(net "M_A_DQS_DP6")
	)
	(segment
		(start 136.032748 -66.672206)
		(end 136.3218 -66.383154)
		(width 0.1524)
		(layer "In4.Cu")
		(net "M_A_DQS_DP6")
	)
	(segment
		(start 106.587544 -64.8716)
		(end 106.130344 -64.8716)
		(width 0.1524)
		(layer "In4.Cu")
		(net "M_A_DQS_DP6")
	)
	(segment
		(start 123.146058 -62.5602)
		(end 122.688858 -62.5602)
		(width 0.1524)
		(layer "In4.Cu")
		(net "M_A_DQS_DP6")
	)
	(segment
		(start 99.5299 -56.8579)
		(end 99.0854 -56.4134)
		(width 0.1016)
		(layer "In4.Cu")
		(net "M_A_DQS_DP6")
	)
	(segment
		(start 107.169204 -64.99606)
		(end 106.712004 -64.99606)
		(width 0.1524)
		(layer "In4.Cu")
		(net "M_A_DQS_DP6")
	)
	(segment
		(start 105.424224 -64.8716)
		(end 104.455976 -64.8716)
		(width 0.1524)
		(layer "In4.Cu")
		(net "M_A_DQS_DP6")
	)
	(segment
		(start 105.548684 -64.99606)
		(end 105.424224 -64.8716)
		(width 0.1524)
		(layer "In4.Cu")
		(net "M_A_DQS_DP6")
	)
	(segment
		(start 103.620824 -62.828932)
		(end 103.620824 -62.371732)
		(width 0.1524)
		(layer "In4.Cu")
		(net "M_A_DQS_DP6")
	)
	(segment
		(start 101.119432 -60.04814)
		(end 101.119432 -59.872118)
		(width 0.1524)
		(layer "In4.Cu")
		(net "M_A_DQS_DP6")
	)
	(segment
		(start 109.1946 -66.167)
		(end 107.8992 -64.8716)
		(width 0.1524)
		(layer "In4.Cu")
		(net "M_A_DQS_DP6")
	)
	(segment
		(start 107.8992 -64.8716)
		(end 107.293664 -64.8716)
		(width 0.1524)
		(layer "In4.Cu")
		(net "M_A_DQS_DP6")
	)
	(segment
		(start 103.620824 -63.535052)
		(end 103.496364 -63.410592)
		(width 0.1524)
		(layer "In4.Cu")
		(net "M_A_DQS_DP6")
	)
	(segment
		(start 125.160786 -62.5602)
		(end 125.036326 -62.68466)
		(width 0.1524)
		(layer "In4.Cu")
		(net "M_A_DQS_DP6")
	)
	(segment
		(start 123.852178 -62.5602)
		(end 123.727718 -62.68466)
		(width 0.1524)
		(layer "In4.Cu")
		(net "M_A_DQS_DP6")
	)
	(segment
		(start 102.441248 -61.193934)
		(end 102.265226 -61.193934)
		(width 0.1524)
		(layer "In4.Cu")
		(net "M_A_DQS_DP6")
	)
	(segment
		(start 103.496364 -62.953392)
		(end 103.620824 -62.828932)
		(width 0.1524)
		(layer "In4.Cu")
		(net "M_A_DQS_DP6")
	)
	(segment
		(start 117.918738 -66.167)
		(end 109.1946 -66.167)
		(width 0.1524)
		(layer "In4.Cu")
		(net "M_A_DQS_DP6")
	)
	(segment
		(start 100.79609 -59.548776)
		(end 100.620068 -59.548776)
		(width 0.1524)
		(layer "In4.Cu")
		(net "M_A_DQS_DP6")
	)
	(segment
		(start 103.496364 -63.410592)
		(end 103.496364 -62.953392)
		(width 0.1524)
		(layer "In4.Cu")
		(net "M_A_DQS_DP6")
	)
	(segment
		(start 100.620068 -59.548776)
		(end 100.296726 -59.225434)
		(width 0.1524)
		(layer "In4.Cu")
		(net "M_A_DQS_DP6")
	)
	(segment
		(start 100.296726 -59.049412)
		(end 99.5299 -58.282586)
		(width 0.1524)
		(layer "In4.Cu")
		(net "M_A_DQS_DP6")
	)
	(segment
		(start 136.3218 -66.000376)
		(end 136.6774 -65.644776)
		(width 0.1524)
		(layer "In4.Cu")
		(net "M_A_DQS_DP6")
	)
	(segment
		(start 136.6774 -63.8302)
		(end 135.4074 -62.5602)
		(width 0.1524)
		(layer "In4.Cu")
		(net "M_A_DQS_DP6")
	)
	(segment
		(start 123.270518 -62.68466)
		(end 123.146058 -62.5602)
		(width 0.1524)
		(layer "In4.Cu")
		(net "M_A_DQS_DP6")
	)
	(segment
		(start 101.119432 -59.872118)
		(end 100.79609 -59.548776)
		(width 0.1524)
		(layer "In4.Cu")
		(net "M_A_DQS_DP6")
	)
	(segment
		(start 121.525538 -62.5602)
		(end 117.918738 -66.167)
		(width 0.1524)
		(layer "In4.Cu")
		(net "M_A_DQS_DP6")
	)
	(segment
		(start 107.293664 -64.8716)
		(end 107.169204 -64.99606)
		(width 0.1524)
		(layer "In4.Cu")
		(net "M_A_DQS_DP6")
	)
	(segment
		(start 136.3218 -66.383154)
		(end 136.3218 -66.000376)
		(width 0.1524)
		(layer "In4.Cu")
		(net "M_A_DQS_DP6")
	)
	(segment
		(start 104.455976 -64.8716)
		(end 103.620824 -64.036448)
		(width 0.1524)
		(layer "In4.Cu")
		(net "M_A_DQS_DP6")
	)
	(segment
		(start 99.0854 -56.4134)
		(end 99.0854 -54.7878)
		(width 0.1016)
		(layer "In4.Cu")
		(net "M_A_DQS_DP6")
	)
	(segment
		(start 103.338376 -62.089284)
		(end 103.336598 -62.089284)
		(width 0.1524)
		(layer "In4.Cu")
		(net "M_A_DQS_DP6")
	)
	(segment
		(start 99.0854 -54.7878)
		(end 99.5934 -54.2798)
		(width 0.1016)
		(layer "In4.Cu")
		(net "M_A_DQS_DP6")
	)
	(segment
		(start 18.415 -22.1742)
		(end 18.415 -23.0886)
		(width 0.508)
		(layer "F.Cu")
		(net "P1V0_VBST_RC")
	)
	(segment
		(start 18.94332 -22.0218)
		(end 18.5674 -22.0218)
		(width 0.508)
		(layer "F.Cu")
		(net "P1V0_VBST_RC")
	)
	(segment
		(start 20.0914 -22.606)
		(end 19.52752 -22.606)
		(width 0.508)
		(layer "F.Cu")
		(net "P1V0_VBST_RC")
	)
	(segment
		(start 19.52752 -22.606)
		(end 18.94332 -22.0218)
		(width 0.508)
		(layer "F.Cu")
		(net "P1V0_VBST_RC")
	)
	(segment
		(start 18.5674 -22.0218)
		(end 18.415 -22.1742)
		(width 0.508)
		(layer "F.Cu")
		(net "P1V0_VBST_RC")
	)
	(via
		(at 18.5674 -22.0218)
		(size 0.7112)
		(drill 0.3556)
		(layers "F.Cu" "B.Cu")
		(net "P1V0_VBST_RC")
	)
	(segment
		(start 147.9804 -69.330316)
		(end 147.9804 -68.6562)
		(width 0.1778)
		(layer "F.Cu")
		(net "M_A_DQ36")
	)
	(segment
		(start 148.150072 -69.499988)
		(end 147.9804 -69.330316)
		(width 0.1778)
		(layer "F.Cu")
		(net "M_A_DQ36")
	)
	(segment
		(start 148.150072 -70.806564)
		(end 148.150072 -69.499988)
		(width 0.1778)
		(layer "F.Cu")
		(net "M_A_DQ36")
	)
	(segment
		(start 96.081088 -46.497494)
		(end 96.235266 -46.497494)
		(width 0.1016)
		(layer "F.Cu")
		(net "M_A_DQ36")
	)
	(segment
		(start 96.235266 -46.497494)
		(end 96.95688 -45.77588)
		(width 0.1016)
		(layer "F.Cu")
		(net "M_A_DQ36")
	)
	(via
		(at 96.95688 -45.77588)
		(size 0.4318)
		(drill 0.2032)
		(layers "F.Cu" "B.Cu")
		(net "M_A_DQ36")
	)
	(via
		(at 147.9804 -68.6562)
		(size 0.4318)
		(drill 0.2032)
		(layers "F.Cu" "B.Cu")
		(net "M_A_DQ36")
	)
	(segment
		(start 147.9804 -69.348604)
		(end 147.9804 -68.6562)
		(width 0.1778)
		(layer "B.Cu")
		(net "M_A_DQ36")
	)
	(segment
		(start 147.850098 -69.478906)
		(end 147.9804 -69.348604)
		(width 0.1778)
		(layer "B.Cu")
		(net "M_A_DQ36")
	)
	(segment
		(start 147.850098 -70.79996)
		(end 147.850098 -69.478906)
		(width 0.1778)
		(layer "B.Cu")
		(net "M_A_DQ36")
	)
	(segment
		(start 139.280646 -53.97373)
		(end 138.824716 -53.5178)
		(width 0.1524)
		(layer "In4.Cu")
		(net "M_A_DQ36")
	)
	(segment
		(start 104.1654 -48.2092)
		(end 103.325168 -47.368968)
		(width 0.1016)
		(layer "In4.Cu")
		(net "M_A_DQ36")
	)
	(segment
		(start 129.911602 -53.7464)
		(end 129.308098 -53.7464)
		(width 0.1524)
		(layer "In4.Cu")
		(net "M_A_DQ36")
	)
	(segment
		(start 128.825498 -53.2638)
		(end 124.223018 -53.2638)
		(width 0.1524)
		(layer "In4.Cu")
		(net "M_A_DQ36")
	)
	(segment
		(start 144.6276 -54.9402)
		(end 143.36903 -54.9402)
		(width 0.1524)
		(layer "In4.Cu")
		(net "M_A_DQ36")
	)
	(segment
		(start 107.827826 -52.0192)
		(end 106.934 -52.0192)
		(width 0.1524)
		(layer "In4.Cu")
		(net "M_A_DQ36")
	)
	(segment
		(start 103.325168 -47.368968)
		(end 103.325168 -46.691042)
		(width 0.1016)
		(layer "In4.Cu")
		(net "M_A_DQ36")
	)
	(segment
		(start 106.934 -52.0192)
		(end 106.299 -51.3842)
		(width 0.1524)
		(layer "In4.Cu")
		(net "M_A_DQ36")
	)
	(segment
		(start 103.151432 -44.9072)
		(end 102.7176 -44.9072)
		(width 0.1016)
		(layer "In4.Cu")
		(net "M_A_DQ36")
	)
	(segment
		(start 142.40256 -53.97373)
		(end 139.280646 -53.97373)
		(width 0.1524)
		(layer "In4.Cu")
		(net "M_A_DQ36")
	)
	(segment
		(start 109.760004 -53.9496)
		(end 108.121196 -52.310792)
		(width 0.1524)
		(layer "In4.Cu")
		(net "M_A_DQ36")
	)
	(segment
		(start 103.303832 -45.0596)
		(end 103.151432 -44.9072)
		(width 0.1016)
		(layer "In4.Cu")
		(net "M_A_DQ36")
	)
	(segment
		(start 118.660418 -53.9496)
		(end 109.760004 -53.9496)
		(width 0.1524)
		(layer "In4.Cu")
		(net "M_A_DQ36")
	)
	(segment
		(start 130.140202 -53.5178)
		(end 129.911602 -53.7464)
		(width 0.1524)
		(layer "In4.Cu")
		(net "M_A_DQ36")
	)
	(segment
		(start 148.717 -67.9196)
		(end 148.717 -59.0296)
		(width 0.1524)
		(layer "In4.Cu")
		(net "M_A_DQ36")
	)
	(segment
		(start 143.36903 -54.9402)
		(end 142.40256 -53.97373)
		(width 0.1524)
		(layer "In4.Cu")
		(net "M_A_DQ36")
	)
	(segment
		(start 104.1654 -50.0634)
		(end 104.1654 -48.706024)
		(width 0.1524)
		(layer "In4.Cu")
		(net "M_A_DQ36")
	)
	(segment
		(start 124.223018 -53.2638)
		(end 123.765818 -53.721)
		(width 0.1524)
		(layer "In4.Cu")
		(net "M_A_DQ36")
	)
	(segment
		(start 138.824716 -53.5178)
		(end 130.140202 -53.5178)
		(width 0.1524)
		(layer "In4.Cu")
		(net "M_A_DQ36")
	)
	(segment
		(start 103.325168 -46.691042)
		(end 103.303832 -46.669706)
		(width 0.1016)
		(layer "In4.Cu")
		(net "M_A_DQ36")
	)
	(segment
		(start 108.121196 -52.310792)
		(end 108.119418 -52.310792)
		(width 0.1524)
		(layer "In4.Cu")
		(net "M_A_DQ36")
	)
	(segment
		(start 97.64776 -45.085)
		(end 96.95688 -45.77588)
		(width 0.1016)
		(layer "In4.Cu")
		(net "M_A_DQ36")
	)
	(segment
		(start 104.1654 -48.706024)
		(end 104.1654 -48.2092)
		(width 0.1016)
		(layer "In4.Cu")
		(net "M_A_DQ36")
	)
	(segment
		(start 118.889018 -53.721)
		(end 118.660418 -53.9496)
		(width 0.1524)
		(layer "In4.Cu")
		(net "M_A_DQ36")
	)
	(segment
		(start 103.303832 -46.669706)
		(end 103.303832 -45.0596)
		(width 0.1016)
		(layer "In4.Cu")
		(net "M_A_DQ36")
	)
	(segment
		(start 147.9804 -68.6562)
		(end 148.717 -67.9196)
		(width 0.1524)
		(layer "In4.Cu")
		(net "M_A_DQ36")
	)
	(segment
		(start 108.119418 -52.310792)
		(end 107.827826 -52.0192)
		(width 0.1524)
		(layer "In4.Cu")
		(net "M_A_DQ36")
	)
	(segment
		(start 106.299 -51.3842)
		(end 105.4862 -51.3842)
		(width 0.1524)
		(layer "In4.Cu")
		(net "M_A_DQ36")
	)
	(segment
		(start 123.765818 -53.721)
		(end 118.889018 -53.721)
		(width 0.1524)
		(layer "In4.Cu")
		(net "M_A_DQ36")
	)
	(segment
		(start 148.717 -59.0296)
		(end 144.6276 -54.9402)
		(width 0.1524)
		(layer "In4.Cu")
		(net "M_A_DQ36")
	)
	(segment
		(start 102.7176 -44.9072)
		(end 102.5398 -45.085)
		(width 0.1016)
		(layer "In4.Cu")
		(net "M_A_DQ36")
	)
	(segment
		(start 129.308098 -53.7464)
		(end 128.825498 -53.2638)
		(width 0.1524)
		(layer "In4.Cu")
		(net "M_A_DQ36")
	)
	(segment
		(start 102.5398 -45.085)
		(end 97.64776 -45.085)
		(width 0.1016)
		(layer "In4.Cu")
		(net "M_A_DQ36")
	)
	(segment
		(start 105.4862 -51.3842)
		(end 104.1654 -50.0634)
		(width 0.1524)
		(layer "In4.Cu")
		(net "M_A_DQ36")
	)
	(segment
		(start 16.637 -21.4122)
		(end 17.018 -21.0312)
		(width 0.254)
		(layer "F.Cu")
		(net "AGND_P1V0")
	)
	(segment
		(start 21.2852 -20.1422)
		(end 22.8092 -21.6662)
		(width 0.254)
		(layer "F.Cu")
		(net "AGND_P1V0")
	)
	(segment
		(start 16.0274 -21.4122)
		(end 16.637 -21.4122)
		(width 0.254)
		(layer "F.Cu")
		(net "AGND_P1V0")
	)
	(segment
		(start 22.8092 -21.6662)
		(end 22.8092 -22.1742)
		(width 0.254)
		(layer "F.Cu")
		(net "AGND_P1V0")
	)
	(segment
		(start 17.018 -21.0312)
		(end 17.907 -20.1422)
		(width 0.254)
		(layer "F.Cu")
		(net "AGND_P1V0")
	)
	(segment
		(start 16.0274 -20.3454)
		(end 15.9766 -20.2946)
		(width 0.254)
		(layer "F.Cu")
		(net "AGND_P1V0")
	)
	(segment
		(start 16.0274 -21.4122)
		(end 16.0274 -20.3454)
		(width 0.254)
		(layer "F.Cu")
		(net "AGND_P1V0")
	)
	(segment
		(start 7.0866 -22.225)
		(end 7.0866 -21.463)
		(width 0.254)
		(layer "F.Cu")
		(net "AGND_P1V0")
	)
	(segment
		(start 7.0866 -21.463)
		(end 7.0866 -20.8026)
		(width 0.254)
		(layer "F.Cu")
		(net "AGND_P1V0")
	)
	(segment
		(start 7.0866 -20.8026)
		(end 7.2136 -20.6756)
		(width 0.254)
		(layer "F.Cu")
		(net "AGND_P1V0")
	)
	(segment
		(start 17.907 -20.1422)
		(end 21.2852 -20.1422)
		(width 0.254)
		(layer "F.Cu")
		(net "AGND_P1V0")
	)
	(via
		(at 15.9766 -20.2946)
		(size 0.508)
		(drill 0.254)
		(layers "F.Cu" "B.Cu")
		(net "AGND_P1V0")
	)
	(via
		(at 22.8092 -22.1742)
		(size 0.508)
		(drill 0.254)
		(layers "F.Cu" "B.Cu")
		(net "AGND_P1V0")
	)
	(via
		(at 7.2136 -20.6756)
		(size 0.508)
		(drill 0.254)
		(layers "F.Cu" "B.Cu")
		(net "AGND_P1V0")
	)
	(via
		(at 21.6662 -23.241)
		(size 0.7112)
		(drill 0.3556)
		(layers "F.Cu" "B.Cu")
		(net "AGND_P1V0")
	)
	(segment
		(start 8.255 -21.9456)
		(end 8.255 -22.1742)
		(width 0.254)
		(layer "B.Cu")
		(net "AGND_P1V0")
	)
	(segment
		(start 13.6144 -21.844)
		(end 10.98931 -21.844)
		(width 0.254)
		(layer "B.Cu")
		(net "AGND_P1V0")
	)
	(segment
		(start 19.2278 -24.003)
		(end 19.2278 -23.2664)
		(width 0.254)
		(layer "B.Cu")
		(net "AGND_P1V0")
	)
	(segment
		(start 10.98931 -21.844)
		(end 10.73531 -21.59)
		(width 0.254)
		(layer "B.Cu")
		(net "AGND_P1V0")
	)
	(segment
		(start 10.73531 -21.59)
		(end 8.6106 -21.59)
		(width 0.254)
		(layer "B.Cu")
		(net "AGND_P1V0")
	)
	(segment
		(start 7.239 -21.1582)
		(end 7.239 -20.701)
		(width 0.254)
		(layer "B.Cu")
		(net "AGND_P1V0")
	)
	(segment
		(start 8.255 -22.1742)
		(end 7.239 -21.1582)
		(width 0.254)
		(layer "B.Cu")
		(net "AGND_P1V0")
	)
	(segment
		(start 21.6662 -23.241)
		(end 21.7424 -23.241)
		(width 0.254)
		(layer "B.Cu")
		(net "AGND_P1V0")
	)
	(segment
		(start 21.7424 -23.241)
		(end 22.8092 -22.1742)
		(width 0.254)
		(layer "B.Cu")
		(net "AGND_P1V0")
	)
	(segment
		(start 15.1638 -20.2946)
		(end 13.6144 -21.844)
		(width 0.254)
		(layer "B.Cu")
		(net "AGND_P1V0")
	)
	(segment
		(start 8.6106 -21.59)
		(end 8.255 -21.9456)
		(width 0.254)
		(layer "B.Cu")
		(net "AGND_P1V0")
	)
	(segment
		(start 21.6662 -23.241)
		(end 19.2532 -23.241)
		(width 0.254)
		(layer "B.Cu")
		(net "AGND_P1V0")
	)
	(segment
		(start 15.9766 -20.2946)
		(end 15.1638 -20.2946)
		(width 0.254)
		(layer "B.Cu")
		(net "AGND_P1V0")
	)
	(segment
		(start 19.2278 -23.2664)
		(end 19.2532 -23.241)
		(width 0.254)
		(layer "B.Cu")
		(net "AGND_P1V0")
	)
	(segment
		(start 7.239 -20.701)
		(end 7.2136 -20.6756)
		(width 0.254)
		(layer "B.Cu")
		(net "AGND_P1V0")
	)
	(segment
		(start 99.5553 -56.0832)
		(end 99.0854 -55.6133)
		(width 0.1016)
		(layer "F.Cu")
		(net "M_A_DQS_DN6")
	)
	(segment
		(start 99.0854 -55.6133)
		(end 99.0854 -52.959)
		(width 0.1016)
		(layer "F.Cu")
		(net "M_A_DQS_DN6")
	)
	(segment
		(start 136.750044 -70.806564)
		(end 136.750044 -70.088252)
		(width 0.1778)
		(layer "F.Cu")
		(net "M_A_DQS_DN6")
	)
	(segment
		(start 99.568508 -51.474878)
		(end 99.568508 -50.952654)
		(width 0.1016)
		(layer "F.Cu")
		(net "M_A_DQS_DN6")
	)
	(segment
		(start 99.184968 -52.859432)
		(end 99.184968 -51.858418)
		(width 0.1016)
		(layer "F.Cu")
		(net "M_A_DQS_DN6")
	)
	(segment
		(start 136.60247 -69.940678)
		(end 136.60247 -66.936874)
		(width 0.1778)
		(layer "F.Cu")
		(net "M_A_DQS_DN6")
	)
	(segment
		(start 99.184968 -51.858418)
		(end 99.568508 -51.474878)
		(width 0.1016)
		(layer "F.Cu")
		(net "M_A_DQS_DN6")
	)
	(segment
		(start 99.0854 -52.959)
		(end 99.184968 -52.859432)
		(width 0.1016)
		(layer "F.Cu")
		(net "M_A_DQS_DN6")
	)
	(segment
		(start 136.60247 -66.936874)
		(end 136.867138 -66.672206)
		(width 0.1778)
		(layer "F.Cu")
		(net "M_A_DQS_DN6")
	)
	(segment
		(start 136.750044 -70.088252)
		(end 136.60247 -69.940678)
		(width 0.1778)
		(layer "F.Cu")
		(net "M_A_DQS_DN6")
	)
	(via
		(at 99.5553 -56.0832)
		(size 0.4318)
		(drill 0.2032)
		(layers "F.Cu" "B.Cu")
		(net "M_A_DQS_DN6")
	)
	(via
		(at 136.867138 -66.672206)
		(size 0.4318)
		(drill 0.2032)
		(layers "F.Cu" "B.Cu")
		(net "M_A_DQS_DN6")
	)
	(segment
		(start 136.651492 -63.541656)
		(end 136.651492 -66.45656)
		(width 0.1778)
		(layer "B.Cu")
		(net "M_A_DQS_DN6")
	)
	(segment
		(start 136.750044 -62.599824)
		(end 136.750044 -63.443104)
		(width 0.1778)
		(layer "B.Cu")
		(net "M_A_DQS_DN6")
	)
	(segment
		(start 136.651492 -66.45656)
		(end 136.867138 -66.672206)
		(width 0.1778)
		(layer "B.Cu")
		(net "M_A_DQS_DN6")
	)
	(segment
		(start 136.750044 -63.443104)
		(end 136.651492 -63.541656)
		(width 0.1778)
		(layer "B.Cu")
		(net "M_A_DQS_DN6")
	)
	(segment
		(start 99.5553 -56.437276)
		(end 99.5553 -56.0832)
		(width 0.1016)
		(layer "In4.Cu")
		(net "M_A_DQS_DN6")
	)
	(segment
		(start 135.523224 -62.2808)
		(end 121.409714 -62.2808)
		(width 0.1524)
		(layer "In4.Cu")
		(net "M_A_DQS_DN6")
	)
	(segment
		(start 136.6012 -66.1162)
		(end 136.9568 -65.7606)
		(width 0.1524)
		(layer "In4.Cu")
		(net "M_A_DQS_DN6")
	)
	(segment
		(start 136.9568 -65.7606)
		(end 136.9568 -63.714376)
		(width 0.1524)
		(layer "In4.Cu")
		(net "M_A_DQS_DN6")
	)
	(segment
		(start 103.900224 -62.255908)
		(end 103.4542 -61.809884)
		(width 0.1524)
		(layer "In4.Cu")
		(net "M_A_DQS_DN6")
	)
	(segment
		(start 121.409714 -62.2808)
		(end 117.802914 -65.8876)
		(width 0.1524)
		(layer "In4.Cu")
		(net "M_A_DQS_DN6")
	)
	(segment
		(start 103.452422 -61.809884)
		(end 99.8093 -58.166762)
		(width 0.1524)
		(layer "In4.Cu")
		(net "M_A_DQS_DN6")
	)
	(segment
		(start 117.802914 -65.8876)
		(end 109.310424 -65.8876)
		(width 0.1524)
		(layer "In4.Cu")
		(net "M_A_DQS_DN6")
	)
	(segment
		(start 108.015024 -64.5922)
		(end 104.5718 -64.5922)
		(width 0.1524)
		(layer "In4.Cu")
		(net "M_A_DQS_DN6")
	)
	(segment
		(start 103.900224 -63.920624)
		(end 103.900224 -62.255908)
		(width 0.1524)
		(layer "In4.Cu")
		(net "M_A_DQS_DN6")
	)
	(segment
		(start 103.4542 -61.809884)
		(end 103.452422 -61.809884)
		(width 0.1524)
		(layer "In4.Cu")
		(net "M_A_DQS_DN6")
	)
	(segment
		(start 136.6012 -66.406522)
		(end 136.6012 -66.1162)
		(width 0.1524)
		(layer "In4.Cu")
		(net "M_A_DQS_DN6")
	)
	(segment
		(start 136.9568 -63.714376)
		(end 135.523224 -62.2808)
		(width 0.1524)
		(layer "In4.Cu")
		(net "M_A_DQS_DN6")
	)
	(segment
		(start 104.5718 -64.5922)
		(end 103.900224 -63.920624)
		(width 0.1524)
		(layer "In4.Cu")
		(net "M_A_DQS_DN6")
	)
	(segment
		(start 136.867138 -66.672206)
		(end 136.6012 -66.406522)
		(width 0.1524)
		(layer "In4.Cu")
		(net "M_A_DQS_DN6")
	)
	(segment
		(start 109.310424 -65.8876)
		(end 108.015024 -64.5922)
		(width 0.1524)
		(layer "In4.Cu")
		(net "M_A_DQS_DN6")
	)
	(segment
		(start 99.8093 -56.691276)
		(end 99.5553 -56.437276)
		(width 0.1016)
		(layer "In4.Cu")
		(net "M_A_DQS_DN6")
	)
	(segment
		(start 99.8093 -58.166762)
		(end 99.8093 -56.691276)
		(width 0.1524)
		(layer "In4.Cu")
		(net "M_A_DQS_DN6")
	)
	(segment
		(start 17.636998 -24.781002)
		(end 17.78 -24.638)
		(width 0.3048)
		(layer "F.Cu")
		(net "P1V0_VBST")
	)
	(segment
		(start 16.292322 -24.781002)
		(end 17.636998 -24.781002)
		(width 0.3048)
		(layer "F.Cu")
		(net "P1V0_VBST")
	)
	(segment
		(start 18.1864 -24.638)
		(end 18.415 -24.4094)
		(width 0.508)
		(layer "F.Cu")
		(net "P1V0_VBST")
	)
	(segment
		(start 17.78 -24.638)
		(end 18.1864 -24.638)
		(width 0.508)
		(layer "F.Cu")
		(net "P1V0_VBST")
	)
	(segment
		(start 175.8061 -64.9224)
		(end 175.8315 -64.9478)
		(width 0.1778)
		(layer "F.Cu")
		(net "M_A_DQ18")
	)
	(segment
		(start 105.004108 -45.628814)
		(end 104.936036 -45.628814)
		(width 0.1016)
		(layer "F.Cu")
		(net "M_A_DQ18")
	)
	(segment
		(start 176.04994 -63.381636)
		(end 175.8061 -63.625476)
		(width 0.1778)
		(layer "F.Cu")
		(net "M_A_DQ18")
	)
	(segment
		(start 104.936036 -45.628814)
		(end 104.534462 -46.030388)
		(width 0.1016)
		(layer "F.Cu")
		(net "M_A_DQ18")
	)
	(segment
		(start 176.04994 -62.59322)
		(end 176.04994 -63.381636)
		(width 0.1778)
		(layer "F.Cu")
		(net "M_A_DQ18")
	)
	(segment
		(start 175.8061 -63.625476)
		(end 175.8061 -64.9224)
		(width 0.1778)
		(layer "F.Cu")
		(net "M_A_DQ18")
	)
	(via
		(at 104.534462 -46.030388)
		(size 0.4318)
		(drill 0.2032)
		(layers "F.Cu" "B.Cu")
		(net "M_A_DQ18")
	)
	(via
		(at 175.8315 -64.9478)
		(size 0.4318)
		(drill 0.2032)
		(layers "F.Cu" "B.Cu")
		(net "M_A_DQ18")
	)
	(segment
		(start 175.8315 -64.8843)
		(end 175.8315 -64.9478)
		(width 0.1778)
		(layer "B.Cu")
		(net "M_A_DQ18")
	)
	(segment
		(start 175.749966 -62.599824)
		(end 175.749966 -64.802766)
		(width 0.1778)
		(layer "B.Cu")
		(net "M_A_DQ18")
	)
	(segment
		(start 175.749966 -64.802766)
		(end 175.8315 -64.8843)
		(width 0.1778)
		(layer "B.Cu")
		(net "M_A_DQ18")
	)
	(segment
		(start 109.093 -50.5206)
		(end 109.092746 -50.5206)
		(width 0.1016)
		(layer "In4.Cu")
		(net "M_A_DQ18")
	)
	(segment
		(start 153.404316 -57.7596)
		(end 151.18588 -57.7596)
		(width 0.1524)
		(layer "In4.Cu")
		(net "M_A_DQ18")
	)
	(segment
		(start 143.95831 -53.5178)
		(end 142.28191 -51.8414)
		(width 0.1524)
		(layer "In4.Cu")
		(net "M_A_DQ18")
	)
	(segment
		(start 151.03348 -57.912)
		(end 151.03348 -58.42)
		(width 0.1524)
		(layer "In4.Cu")
		(net "M_A_DQ18")
	)
	(segment
		(start 150.42388 -58.42)
		(end 150.42388 -57.912)
		(width 0.1524)
		(layer "In4.Cu")
		(net "M_A_DQ18")
	)
	(segment
		(start 153.556716 -57.912)
		(end 153.404316 -57.7596)
		(width 0.1524)
		(layer "In4.Cu")
		(net "M_A_DQ18")
	)
	(segment
		(start 108.834682 -50.262536)
		(end 108.834682 -50.262282)
		(width 0.1016)
		(layer "In4.Cu")
		(net "M_A_DQ18")
	)
	(segment
		(start 106.0704 -47.8536)
		(end 105.88117 -47.66437)
		(width 0.1016)
		(layer "In4.Cu")
		(net "M_A_DQ18")
	)
	(segment
		(start 154.775916 -58.166)
		(end 154.775916 -57.912)
		(width 0.1524)
		(layer "In4.Cu")
		(net "M_A_DQ18")
	)
	(segment
		(start 164.75583 -60.531502)
		(end 161.983928 -57.7596)
		(width 0.1524)
		(layer "In4.Cu")
		(net "M_A_DQ18")
	)
	(segment
		(start 154.166316 -57.912)
		(end 154.166316 -58.3184)
		(width 0.1524)
		(layer "In4.Cu")
		(net "M_A_DQ18")
	)
	(segment
		(start 175.8315 -64.9478)
		(end 175.44542 -64.56172)
		(width 0.1524)
		(layer "In4.Cu")
		(net "M_A_DQ18")
	)
	(segment
		(start 109.601 -50.5206)
		(end 109.093 -50.5206)
		(width 0.1524)
		(layer "In4.Cu")
		(net "M_A_DQ18")
	)
	(segment
		(start 169.903902 -63.61176)
		(end 166.823644 -60.531502)
		(width 0.1524)
		(layer "In4.Cu")
		(net "M_A_DQ18")
	)
	(segment
		(start 104.534462 -46.368462)
		(end 104.534462 -46.030388)
		(width 0.1016)
		(layer "In4.Cu")
		(net "M_A_DQ18")
	)
	(segment
		(start 161.247328 -58.2422)
		(end 161.094928 -58.3946)
		(width 0.1524)
		(layer "In4.Cu")
		(net "M_A_DQ18")
	)
	(segment
		(start 118.237 -52.2986)
		(end 117.7544 -52.7812)
		(width 0.1524)
		(layer "In4.Cu")
		(net "M_A_DQ18")
	)
	(segment
		(start 108.0516 -49.4792)
		(end 106.7054 -49.4792)
		(width 0.1016)
		(layer "In4.Cu")
		(net "M_A_DQ18")
	)
	(segment
		(start 160.637728 -57.912)
		(end 160.485328 -57.7596)
		(width 0.1524)
		(layer "In4.Cu")
		(net "M_A_DQ18")
	)
	(segment
		(start 105.1306 -47.3964)
		(end 105.1306 -46.9646)
		(width 0.1016)
		(layer "In4.Cu")
		(net "M_A_DQ18")
	)
	(segment
		(start 154.318716 -57.7596)
		(end 154.166316 -57.912)
		(width 0.1524)
		(layer "In4.Cu")
		(net "M_A_DQ18")
	)
	(segment
		(start 106.3498 -48.6918)
		(end 106.0704 -48.4124)
		(width 0.1016)
		(layer "In4.Cu")
		(net "M_A_DQ18")
	)
	(segment
		(start 160.637728 -58.2422)
		(end 160.637728 -57.912)
		(width 0.1524)
		(layer "In4.Cu")
		(net "M_A_DQ18")
	)
	(segment
		(start 154.166316 -58.3184)
		(end 154.013916 -58.4708)
		(width 0.1524)
		(layer "In4.Cu")
		(net "M_A_DQ18")
	)
	(segment
		(start 123.633738 -51.8414)
		(end 123.176538 -52.2986)
		(width 0.1524)
		(layer "In4.Cu")
		(net "M_A_DQ18")
	)
	(segment
		(start 117.7544 -52.7812)
		(end 111.8616 -52.7812)
		(width 0.1524)
		(layer "In4.Cu")
		(net "M_A_DQ18")
	)
	(segment
		(start 160.180528 -57.7596)
		(end 160.028128 -57.912)
		(width 0.1524)
		(layer "In4.Cu")
		(net "M_A_DQ18")
	)
	(segment
		(start 166.823644 -60.531502)
		(end 164.75583 -60.531502)
		(width 0.1524)
		(layer "In4.Cu")
		(net "M_A_DQ18")
	)
	(segment
		(start 155.233116 -58.3184)
		(end 154.928316 -58.3184)
		(width 0.1524)
		(layer "In4.Cu")
		(net "M_A_DQ18")
	)
	(segment
		(start 154.623516 -57.7596)
		(end 154.318716 -57.7596)
		(width 0.1524)
		(layer "In4.Cu")
		(net "M_A_DQ18")
	)
	(segment
		(start 145.21688 -53.5178)
		(end 143.95831 -53.5178)
		(width 0.1524)
		(layer "In4.Cu")
		(net "M_A_DQ18")
	)
	(segment
		(start 150.42388 -57.912)
		(end 150.27148 -57.7596)
		(width 0.1524)
		(layer "In4.Cu")
		(net "M_A_DQ18")
	)
	(segment
		(start 160.028128 -58.2422)
		(end 159.875728 -58.3946)
		(width 0.1524)
		(layer "In4.Cu")
		(net "M_A_DQ18")
	)
	(segment
		(start 175.14824 -63.61176)
		(end 169.903902 -63.61176)
		(width 0.1524)
		(layer "In4.Cu")
		(net "M_A_DQ18")
	)
	(segment
		(start 155.537916 -57.7596)
		(end 155.385516 -57.912)
		(width 0.1524)
		(layer "In4.Cu")
		(net "M_A_DQ18")
	)
	(segment
		(start 160.028128 -57.912)
		(end 160.028128 -58.2422)
		(width 0.1524)
		(layer "In4.Cu")
		(net "M_A_DQ18")
	)
	(segment
		(start 161.983928 -57.7596)
		(end 161.399728 -57.7596)
		(width 0.1524)
		(layer "In4.Cu")
		(net "M_A_DQ18")
	)
	(segment
		(start 153.556716 -58.3184)
		(end 153.556716 -57.912)
		(width 0.1524)
		(layer "In4.Cu")
		(net "M_A_DQ18")
	)
	(segment
		(start 151.03348 -58.42)
		(end 150.88108 -58.5724)
		(width 0.1524)
		(layer "In4.Cu")
		(net "M_A_DQ18")
	)
	(segment
		(start 175.44542 -63.90894)
		(end 175.14824 -63.61176)
		(width 0.1524)
		(layer "In4.Cu")
		(net "M_A_DQ18")
	)
	(segment
		(start 159.266128 -57.7596)
		(end 155.537916 -57.7596)
		(width 0.1524)
		(layer "In4.Cu")
		(net "M_A_DQ18")
	)
	(segment
		(start 159.875728 -58.3946)
		(end 159.570928 -58.3946)
		(width 0.1524)
		(layer "In4.Cu")
		(net "M_A_DQ18")
	)
	(segment
		(start 105.88117 -47.66437)
		(end 105.39857 -47.66437)
		(width 0.1016)
		(layer "In4.Cu")
		(net "M_A_DQ18")
	)
	(segment
		(start 150.27148 -57.7596)
		(end 149.45868 -57.7596)
		(width 0.1524)
		(layer "In4.Cu")
		(net "M_A_DQ18")
	)
	(segment
		(start 109.092746 -50.5206)
		(end 108.834682 -50.262536)
		(width 0.1016)
		(layer "In4.Cu")
		(net "M_A_DQ18")
	)
	(segment
		(start 123.176538 -52.2986)
		(end 118.237 -52.2986)
		(width 0.1524)
		(layer "In4.Cu")
		(net "M_A_DQ18")
	)
	(segment
		(start 153.709116 -58.4708)
		(end 153.556716 -58.3184)
		(width 0.1524)
		(layer "In4.Cu")
		(net "M_A_DQ18")
	)
	(segment
		(start 154.928316 -58.3184)
		(end 154.775916 -58.166)
		(width 0.1524)
		(layer "In4.Cu")
		(net "M_A_DQ18")
	)
	(segment
		(start 159.570928 -58.3946)
		(end 159.418528 -58.2422)
		(width 0.1524)
		(layer "In4.Cu")
		(net "M_A_DQ18")
	)
	(segment
		(start 111.8616 -52.7812)
		(end 109.601 -50.5206)
		(width 0.1524)
		(layer "In4.Cu")
		(net "M_A_DQ18")
	)
	(segment
		(start 160.790128 -58.3946)
		(end 160.637728 -58.2422)
		(width 0.1524)
		(layer "In4.Cu")
		(net "M_A_DQ18")
	)
	(segment
		(start 159.418528 -57.912)
		(end 159.266128 -57.7596)
		(width 0.1524)
		(layer "In4.Cu")
		(net "M_A_DQ18")
	)
	(segment
		(start 161.399728 -57.7596)
		(end 161.247328 -57.912)
		(width 0.1524)
		(layer "In4.Cu")
		(net "M_A_DQ18")
	)
	(segment
		(start 161.247328 -57.912)
		(end 161.247328 -58.2422)
		(width 0.1524)
		(layer "In4.Cu")
		(net "M_A_DQ18")
	)
	(segment
		(start 151.18588 -57.7596)
		(end 151.03348 -57.912)
		(width 0.1524)
		(layer "In4.Cu")
		(net "M_A_DQ18")
	)
	(segment
		(start 175.44542 -64.56172)
		(end 175.44542 -63.90894)
		(width 0.1524)
		(layer "In4.Cu")
		(net "M_A_DQ18")
	)
	(segment
		(start 155.385516 -58.166)
		(end 155.233116 -58.3184)
		(width 0.1524)
		(layer "In4.Cu")
		(net "M_A_DQ18")
	)
	(segment
		(start 105.39857 -47.66437)
		(end 105.1306 -47.3964)
		(width 0.1016)
		(layer "In4.Cu")
		(net "M_A_DQ18")
	)
	(segment
		(start 154.775916 -57.912)
		(end 154.623516 -57.7596)
		(width 0.1524)
		(layer "In4.Cu")
		(net "M_A_DQ18")
	)
	(segment
		(start 154.013916 -58.4708)
		(end 153.709116 -58.4708)
		(width 0.1524)
		(layer "In4.Cu")
		(net "M_A_DQ18")
	)
	(segment
		(start 106.0704 -48.4124)
		(end 106.0704 -47.8536)
		(width 0.1016)
		(layer "In4.Cu")
		(net "M_A_DQ18")
	)
	(segment
		(start 108.834682 -50.262282)
		(end 108.0516 -49.4792)
		(width 0.1016)
		(layer "In4.Cu")
		(net "M_A_DQ18")
	)
	(segment
		(start 150.57628 -58.5724)
		(end 150.42388 -58.42)
		(width 0.1524)
		(layer "In4.Cu")
		(net "M_A_DQ18")
	)
	(segment
		(start 106.7054 -49.4792)
		(end 106.3498 -49.1236)
		(width 0.1016)
		(layer "In4.Cu")
		(net "M_A_DQ18")
	)
	(segment
		(start 150.88108 -58.5724)
		(end 150.57628 -58.5724)
		(width 0.1524)
		(layer "In4.Cu")
		(net "M_A_DQ18")
	)
	(segment
		(start 106.3498 -49.1236)
		(end 106.3498 -48.6918)
		(width 0.1016)
		(layer "In4.Cu")
		(net "M_A_DQ18")
	)
	(segment
		(start 160.485328 -57.7596)
		(end 160.180528 -57.7596)
		(width 0.1524)
		(layer "In4.Cu")
		(net "M_A_DQ18")
	)
	(segment
		(start 159.418528 -58.2422)
		(end 159.418528 -57.912)
		(width 0.1524)
		(layer "In4.Cu")
		(net "M_A_DQ18")
	)
	(segment
		(start 161.094928 -58.3946)
		(end 160.790128 -58.3946)
		(width 0.1524)
		(layer "In4.Cu")
		(net "M_A_DQ18")
	)
	(segment
		(start 105.1306 -46.9646)
		(end 104.534462 -46.368462)
		(width 0.1016)
		(layer "In4.Cu")
		(net "M_A_DQ18")
	)
	(segment
		(start 142.28191 -51.8414)
		(end 123.633738 -51.8414)
		(width 0.1524)
		(layer "In4.Cu")
		(net "M_A_DQ18")
	)
	(segment
		(start 155.385516 -57.912)
		(end 155.385516 -58.166)
		(width 0.1524)
		(layer "In4.Cu")
		(net "M_A_DQ18")
	)
	(segment
		(start 149.45868 -57.7596)
		(end 145.21688 -53.5178)
		(width 0.1524)
		(layer "In4.Cu")
		(net "M_A_DQ18")
	)
	(segment
		(start 6.7564 -24.9936)
		(end 8.1788 -24.9936)
		(width 0.508)
		(layer "F.Cu")
		(net "P1V0_VDD")
	)
	(segment
		(start 8.1788 -24.9936)
		(end 8.217408 -24.954992)
		(width 0.508)
		(layer "F.Cu")
		(net "P1V0_VDD")
	)
	(segment
		(start 8.217408 -24.954992)
		(end 9.769856 -24.954992)
		(width 0.508)
		(layer "F.Cu")
		(net "P1V0_VDD")
	)
	(segment
		(start 6.6294 -24.8666)
		(end 6.7564 -24.9936)
		(width 0.508)
		(layer "F.Cu")
		(net "P1V0_VDD")
	)
	(segment
		(start 11.025378 -24.781002)
		(end 11.647678 -24.781002)
		(width 0.3048)
		(layer "F.Cu")
		(net "P1V0_VDD")
	)
	(segment
		(start 9.769856 -24.954992)
		(end 9.807448 -24.9174)
		(width 0.3048)
		(layer "F.Cu")
		(net "P1V0_VDD")
	)
	(segment
		(start 10.88898 -24.9174)
		(end 11.025378 -24.781002)
		(width 0.3048)
		(layer "F.Cu")
		(net "P1V0_VDD")
	)
	(segment
		(start 9.807448 -24.9174)
		(end 10.88898 -24.9174)
		(width 0.3048)
		(layer "F.Cu")
		(net "P1V0_VDD")
	)
	(via
		(at 9.769856 -24.954992)
		(size 0.7112)
		(drill 0.3556)
		(layers "F.Cu" "B.Cu")
		(net "P1V0_VDD")
	)
	(segment
		(start 173.650148 -63.862458)
		(end 173.65218 -63.86449)
		(width 0.1778)
		(layer "F.Cu")
		(net "M_A_DQ25")
	)
	(segment
		(start 173.4566 -64.7446)
		(end 173.4312 -64.7446)
		(width 0.1778)
		(layer "F.Cu")
		(net "M_A_DQ25")
	)
	(segment
		(start 112.199674 -42.019474)
		(end 111.488728 -42.019474)
		(width 0.1016)
		(layer "F.Cu")
		(net "M_A_DQ25")
	)
	(segment
		(start 114.1222 -43.942)
		(end 112.199674 -42.019474)
		(width 0.1016)
		(layer "F.Cu")
		(net "M_A_DQ25")
	)
	(segment
		(start 116.332 -43.4594)
		(end 115.8494 -43.942)
		(width 0.1016)
		(layer "F.Cu")
		(net "M_A_DQ25")
	)
	(segment
		(start 173.650148 -62.59322)
		(end 173.650148 -63.862458)
		(width 0.1778)
		(layer "F.Cu")
		(net "M_A_DQ25")
	)
	(segment
		(start 173.65218 -64.54902)
		(end 173.4566 -64.7446)
		(width 0.1778)
		(layer "F.Cu")
		(net "M_A_DQ25")
	)
	(segment
		(start 115.8494 -43.942)
		(end 114.1222 -43.942)
		(width 0.1016)
		(layer "F.Cu")
		(net "M_A_DQ25")
	)
	(segment
		(start 173.65218 -63.86449)
		(end 173.65218 -64.54902)
		(width 0.1778)
		(layer "F.Cu")
		(net "M_A_DQ25")
	)
	(via
		(at 116.332 -43.4594)
		(size 0.4318)
		(drill 0.2032)
		(layers "F.Cu" "B.Cu")
		(net "M_A_DQ25")
	)
	(via
		(at 173.4312 -64.7446)
		(size 0.4318)
		(drill 0.2032)
		(layers "F.Cu" "B.Cu")
		(net "M_A_DQ25")
	)
	(segment
		(start 173.65726 -64.54394)
		(end 173.4566 -64.7446)
		(width 0.1778)
		(layer "B.Cu")
		(net "M_A_DQ25")
	)
	(segment
		(start 173.655228 -64.235076)
		(end 173.65726 -64.237108)
		(width 0.1778)
		(layer "B.Cu")
		(net "M_A_DQ25")
	)
	(segment
		(start 173.65726 -64.237108)
		(end 173.65726 -64.54394)
		(width 0.1778)
		(layer "B.Cu")
		(net "M_A_DQ25")
	)
	(segment
		(start 173.655228 -63.749428)
		(end 173.655228 -64.235076)
		(width 0.1778)
		(layer "B.Cu")
		(net "M_A_DQ25")
	)
	(segment
		(start 173.350174 -63.444374)
		(end 173.655228 -63.749428)
		(width 0.1778)
		(layer "B.Cu")
		(net "M_A_DQ25")
	)
	(segment
		(start 173.350174 -62.599824)
		(end 173.350174 -63.444374)
		(width 0.1778)
		(layer "B.Cu")
		(net "M_A_DQ25")
	)
	(segment
		(start 173.4566 -64.7446)
		(end 173.4312 -64.7446)
		(width 0.1778)
		(layer "B.Cu")
		(net "M_A_DQ25")
	)
	(segment
		(start 173.6217 -64.5541)
		(end 173.6217 -62.3824)
		(width 0.1524)
		(layer "In2.Cu")
		(net "M_A_DQ25")
	)
	(segment
		(start 173.7868 -59.141614)
		(end 173.6344 -58.989214)
		(width 0.1524)
		(layer "In2.Cu")
		(net "M_A_DQ25")
	)
	(segment
		(start 174.5488 -59.294014)
		(end 174.3964 -59.141614)
		(width 0.1524)
		(layer "In2.Cu")
		(net "M_A_DQ25")
	)
	(segment
		(start 166.974774 -51.476656)
		(end 166.759382 -51.476656)
		(width 0.1524)
		(layer "In2.Cu")
		(net "M_A_DQ25")
	)
	(segment
		(start 166.7637 -50.1777)
		(end 166.548308 -50.1777)
		(width 0.1524)
		(layer "In2.Cu")
		(net "M_A_DQ25")
	)
	(segment
		(start 164.88918 -45.879766)
		(end 161.833814 -42.8244)
		(width 0.1524)
		(layer "In2.Cu")
		(net "M_A_DQ25")
	)
	(segment
		(start 117.7036 -43.4594)
		(end 116.332 -43.4594)
		(width 0.1016)
		(layer "In2.Cu")
		(net "M_A_DQ25")
	)
	(segment
		(start 173.6344 -58.351674)
		(end 167.406066 -52.12334)
		(width 0.1524)
		(layer "In2.Cu")
		(net "M_A_DQ25")
	)
	(segment
		(start 174.3964 -59.141614)
		(end 173.7868 -59.141614)
		(width 0.1524)
		(layer "In2.Cu")
		(net "M_A_DQ25")
	)
	(segment
		(start 166.9796 -50.608992)
		(end 166.9796 -50.3936)
		(width 0.1524)
		(layer "In2.Cu")
		(net "M_A_DQ25")
	)
	(segment
		(start 165.896798 -50.614072)
		(end 165.482778 -50.200052)
		(width 0.1524)
		(layer "In2.Cu")
		(net "M_A_DQ25")
	)
	(segment
		(start 174.5742 -60.360814)
		(end 173.7868 -60.360814)
		(width 0.1524)
		(layer "In2.Cu")
		(net "M_A_DQ25")
	)
	(segment
		(start 173.4312 -64.7446)
		(end 173.6217 -64.5541)
		(width 0.1524)
		(layer "In2.Cu")
		(net "M_A_DQ25")
	)
	(segment
		(start 174.7266 -62.0776)
		(end 174.7266 -61.732414)
		(width 0.1524)
		(layer "In2.Cu")
		(net "M_A_DQ25")
	)
	(segment
		(start 167.406066 -51.907948)
		(end 167.918384 -51.395376)
		(width 0.1524)
		(layer "In2.Cu")
		(net "M_A_DQ25")
	)
	(segment
		(start 165.482778 -50.200052)
		(end 165.482778 -46.48327)
		(width 0.1524)
		(layer "In2.Cu")
		(net "M_A_DQ25")
	)
	(segment
		(start 174.5742 -61.580014)
		(end 173.7868 -61.580014)
		(width 0.1524)
		(layer "In2.Cu")
		(net "M_A_DQ25")
	)
	(segment
		(start 173.6344 -58.989214)
		(end 173.6344 -58.351674)
		(width 0.1524)
		(layer "In2.Cu")
		(net "M_A_DQ25")
	)
	(segment
		(start 164.88918 -45.889672)
		(end 164.88918 -45.879766)
		(width 0.1524)
		(layer "In2.Cu")
		(net "M_A_DQ25")
	)
	(segment
		(start 167.406066 -52.12334)
		(end 167.406066 -51.907948)
		(width 0.1524)
		(layer "In2.Cu")
		(net "M_A_DQ25")
	)
	(segment
		(start 173.6344 -60.208414)
		(end 173.6344 -59.903614)
		(width 0.1524)
		(layer "In2.Cu")
		(net "M_A_DQ25")
	)
	(segment
		(start 173.7868 -59.751214)
		(end 174.3964 -59.751214)
		(width 0.1524)
		(layer "In2.Cu")
		(net "M_A_DQ25")
	)
	(segment
		(start 174.3964 -59.751214)
		(end 174.5488 -59.598814)
		(width 0.1524)
		(layer "In2.Cu")
		(net "M_A_DQ25")
	)
	(segment
		(start 118.3386 -42.8244)
		(end 117.7036 -43.4594)
		(width 0.1016)
		(layer "In2.Cu")
		(net "M_A_DQ25")
	)
	(segment
		(start 173.7741 -62.23)
		(end 174.5742 -62.23)
		(width 0.1524)
		(layer "In2.Cu")
		(net "M_A_DQ25")
	)
	(segment
		(start 173.6217 -62.3824)
		(end 173.7741 -62.23)
		(width 0.1524)
		(layer "In2.Cu")
		(net "M_A_DQ25")
	)
	(segment
		(start 174.7266 -61.732414)
		(end 174.5742 -61.580014)
		(width 0.1524)
		(layer "In2.Cu")
		(net "M_A_DQ25")
	)
	(segment
		(start 173.7868 -61.580014)
		(end 173.6344 -61.427614)
		(width 0.1524)
		(layer "In2.Cu")
		(net "M_A_DQ25")
	)
	(segment
		(start 174.5742 -60.970414)
		(end 174.7266 -60.818014)
		(width 0.1524)
		(layer "In2.Cu")
		(net "M_A_DQ25")
	)
	(segment
		(start 167.918384 -51.395376)
		(end 167.918384 -51.179984)
		(width 0.1524)
		(layer "In2.Cu")
		(net "M_A_DQ25")
	)
	(segment
		(start 161.833814 -42.8244)
		(end 118.3386 -42.8244)
		(width 0.1524)
		(layer "In2.Cu")
		(net "M_A_DQ25")
	)
	(segment
		(start 166.9796 -50.3936)
		(end 166.7637 -50.1777)
		(width 0.1524)
		(layer "In2.Cu")
		(net "M_A_DQ25")
	)
	(segment
		(start 166.11219 -50.614072)
		(end 165.896798 -50.614072)
		(width 0.1524)
		(layer "In2.Cu")
		(net "M_A_DQ25")
	)
	(segment
		(start 173.7868 -60.360814)
		(end 173.6344 -60.208414)
		(width 0.1524)
		(layer "In2.Cu")
		(net "M_A_DQ25")
	)
	(segment
		(start 166.548308 -50.1777)
		(end 166.11219 -50.614072)
		(width 0.1524)
		(layer "In2.Cu")
		(net "M_A_DQ25")
	)
	(segment
		(start 166.543482 -51.260756)
		(end 166.543482 -51.045364)
		(width 0.1524)
		(layer "In2.Cu")
		(net "M_A_DQ25")
	)
	(segment
		(start 173.6344 -59.903614)
		(end 173.7868 -59.751214)
		(width 0.1524)
		(layer "In2.Cu")
		(net "M_A_DQ25")
	)
	(segment
		(start 174.5488 -59.598814)
		(end 174.5488 -59.294014)
		(width 0.1524)
		(layer "In2.Cu")
		(net "M_A_DQ25")
	)
	(segment
		(start 173.6344 -61.427614)
		(end 173.6344 -61.122814)
		(width 0.1524)
		(layer "In2.Cu")
		(net "M_A_DQ25")
	)
	(segment
		(start 167.487092 -50.964084)
		(end 166.974774 -51.476656)
		(width 0.1524)
		(layer "In2.Cu")
		(net "M_A_DQ25")
	)
	(segment
		(start 167.702484 -50.964084)
		(end 167.487092 -50.964084)
		(width 0.1524)
		(layer "In2.Cu")
		(net "M_A_DQ25")
	)
	(segment
		(start 166.543482 -51.045364)
		(end 166.9796 -50.608992)
		(width 0.1524)
		(layer "In2.Cu")
		(net "M_A_DQ25")
	)
	(segment
		(start 174.7266 -60.818014)
		(end 174.7266 -60.513214)
		(width 0.1524)
		(layer "In2.Cu")
		(net "M_A_DQ25")
	)
	(segment
		(start 165.482778 -46.48327)
		(end 164.88918 -45.889672)
		(width 0.1524)
		(layer "In2.Cu")
		(net "M_A_DQ25")
	)
	(segment
		(start 174.7266 -60.513214)
		(end 174.5742 -60.360814)
		(width 0.1524)
		(layer "In2.Cu")
		(net "M_A_DQ25")
	)
	(segment
		(start 166.759382 -51.476656)
		(end 166.543482 -51.260756)
		(width 0.1524)
		(layer "In2.Cu")
		(net "M_A_DQ25")
	)
	(segment
		(start 167.918384 -51.179984)
		(end 167.702484 -50.964084)
		(width 0.1524)
		(layer "In2.Cu")
		(net "M_A_DQ25")
	)
	(segment
		(start 173.6344 -61.122814)
		(end 173.7868 -60.970414)
		(width 0.1524)
		(layer "In2.Cu")
		(net "M_A_DQ25")
	)
	(segment
		(start 174.5742 -62.23)
		(end 174.7266 -62.0776)
		(width 0.1524)
		(layer "In2.Cu")
		(net "M_A_DQ25")
	)
	(segment
		(start 173.7868 -60.970414)
		(end 174.5742 -60.970414)
		(width 0.1524)
		(layer "In2.Cu")
		(net "M_A_DQ25")
	)
	(segment
		(start 109.728 -48.147986)
		(end 109.195108 -47.615094)
		(width 0.1016)
		(layer "F.Cu")
		(net "M_A_MA12")
	)
	(segment
		(start 109.728 -48.3362)
		(end 109.728 -48.147986)
		(width 0.1016)
		(layer "F.Cu")
		(net "M_A_MA12")
	)
	(segment
		(start 160.13557 -68.498212)
		(end 160.13557 -67.4116)
		(width 0.2413)
		(layer "F.Cu")
		(net "M_A_MA12")
	)
	(segment
		(start 159.502348 -69.547486)
		(end 159.502348 -69.131434)
		(width 0.2413)
		(layer "F.Cu")
		(net "M_A_MA12")
	)
	(segment
		(start 109.7534 -48.3616)
		(end 109.728 -48.3362)
		(width 0.1016)
		(layer "F.Cu")
		(net "M_A_MA12")
	)
	(segment
		(start 159.5501 -69.595238)
		(end 159.502348 -69.547486)
		(width 0.2413)
		(layer "F.Cu")
		(net "M_A_MA12")
	)
	(segment
		(start 159.502348 -69.131434)
		(end 160.13557 -68.498212)
		(width 0.2413)
		(layer "F.Cu")
		(net "M_A_MA12")
	)
	(segment
		(start 159.5501 -70.806564)
		(end 159.5501 -69.595238)
		(width 0.2413)
		(layer "F.Cu")
		(net "M_A_MA12")
	)
	(via
		(at 160.13557 -67.4116)
		(size 0.4318)
		(drill 0.2032)
		(layers "F.Cu" "B.Cu")
		(net "M_A_MA12")
	)
	(via
		(at 109.7534 -48.3616)
		(size 0.4318)
		(drill 0.2032)
		(layers "F.Cu" "B.Cu")
		(net "M_A_MA12")
	)
	(segment
		(start 159.5501 -62.599824)
		(end 159.5501 -64.75095)
		(width 0.2413)
		(layer "B.Cu")
		(net "M_A_MA12")
	)
	(segment
		(start 160.225486 -67.343528)
		(end 160.203642 -67.343528)
		(width 0.2413)
		(layer "B.Cu")
		(net "M_A_MA12")
	)
	(segment
		(start 160.612328 -66.956686)
		(end 160.225486 -67.343528)
		(width 0.2413)
		(layer "B.Cu")
		(net "M_A_MA12")
	)
	(segment
		(start 160.612328 -65.813178)
		(end 160.612328 -66.956686)
		(width 0.2413)
		(layer "B.Cu")
		(net "M_A_MA12")
	)
	(segment
		(start 159.5501 -64.75095)
		(end 160.612328 -65.813178)
		(width 0.2413)
		(layer "B.Cu")
		(net "M_A_MA12")
	)
	(segment
		(start 160.203642 -67.343528)
		(end 160.13557 -67.4116)
		(width 0.2413)
		(layer "B.Cu")
		(net "M_A_MA12")
	)
	(segment
		(start 111.9378 -49.784)
		(end 112.649 -50.4952)
		(width 0.1016)
		(layer "In9.Cu")
		(net "M_A_MA12")
	)
	(segment
		(start 109.7534 -48.3616)
		(end 109.9185 -48.5267)
		(width 0.1016)
		(layer "In9.Cu")
		(net "M_A_MA12")
	)
	(segment
		(start 152.09139 -52.954174)
		(end 153.653236 -54.51602)
		(width 0.1905)
		(layer "In9.Cu")
		(net "M_A_MA12")
	)
	(segment
		(start 157.61335 -58.568336)
		(end 159.2326 -60.187586)
		(width 0.1905)
		(layer "In9.Cu")
		(net "M_A_MA12")
	)
	(segment
		(start 117.96395 -49.65065)
		(end 144.57553 -49.65065)
		(width 0.1905)
		(layer "In9.Cu")
		(net "M_A_MA12")
	)
	(segment
		(start 117.1194 -50.4952)
		(end 117.96395 -49.65065)
		(width 0.1016)
		(layer "In9.Cu")
		(net "M_A_MA12")
	)
	(segment
		(start 111.9378 -49.0601)
		(end 111.9378 -49.784)
		(width 0.1016)
		(layer "In9.Cu")
		(net "M_A_MA12")
	)
	(segment
		(start 160.13557 -67.396614)
		(end 160.13557 -67.4116)
		(width 0.1905)
		(layer "In9.Cu")
		(net "M_A_MA12")
	)
	(segment
		(start 149.9235 -50.1777)
		(end 152.09139 -52.34559)
		(width 0.1905)
		(layer "In9.Cu")
		(net "M_A_MA12")
	)
	(segment
		(start 159.678878 -66.939922)
		(end 160.13557 -67.396614)
		(width 0.1905)
		(layer "In9.Cu")
		(net "M_A_MA12")
	)
	(segment
		(start 159.678878 -65.634362)
		(end 159.678878 -66.939922)
		(width 0.1905)
		(layer "In9.Cu")
		(net "M_A_MA12")
	)
	(segment
		(start 153.653236 -54.51602)
		(end 154.26182 -54.51602)
		(width 0.1905)
		(layer "In9.Cu")
		(net "M_A_MA12")
	)
	(segment
		(start 145.10258 -50.1777)
		(end 149.9235 -50.1777)
		(width 0.1905)
		(layer "In9.Cu")
		(net "M_A_MA12")
	)
	(segment
		(start 159.2326 -65.188084)
		(end 159.678878 -65.634362)
		(width 0.1905)
		(layer "In9.Cu")
		(net "M_A_MA12")
	)
	(segment
		(start 112.649 -50.4952)
		(end 117.1194 -50.4952)
		(width 0.1016)
		(layer "In9.Cu")
		(net "M_A_MA12")
	)
	(segment
		(start 111.4044 -48.5267)
		(end 111.9378 -49.0601)
		(width 0.1016)
		(layer "In9.Cu")
		(net "M_A_MA12")
	)
	(segment
		(start 109.9185 -48.5267)
		(end 111.4044 -48.5267)
		(width 0.1016)
		(layer "In9.Cu")
		(net "M_A_MA12")
	)
	(segment
		(start 157.61335 -57.86755)
		(end 157.61335 -58.568336)
		(width 0.1905)
		(layer "In9.Cu")
		(net "M_A_MA12")
	)
	(segment
		(start 144.57553 -49.65065)
		(end 145.10258 -50.1777)
		(width 0.1905)
		(layer "In9.Cu")
		(net "M_A_MA12")
	)
	(segment
		(start 152.09139 -52.34559)
		(end 152.09139 -52.954174)
		(width 0.1905)
		(layer "In9.Cu")
		(net "M_A_MA12")
	)
	(segment
		(start 154.26182 -54.51602)
		(end 157.61335 -57.86755)
		(width 0.1905)
		(layer "In9.Cu")
		(net "M_A_MA12")
	)
	(segment
		(start 159.2326 -60.187586)
		(end 159.2326 -65.188084)
		(width 0.1905)
		(layer "In9.Cu")
		(net "M_A_MA12")
	)
	(segment
		(start 112.522 -71.5518)
		(end 113.284 -71.5518)
		(width 0.1143)
		(layer "F.Cu")
		(net "CHA_1_SA0")
	)
	(segment
		(start 111.633 -71.5264)
		(end 111.6584 -71.5518)
		(width 0.1143)
		(layer "F.Cu")
		(net "CHA_1_SA0")
	)
	(segment
		(start 111.6584 -71.5518)
		(end 112.522 -71.5518)
		(width 0.1143)
		(layer "F.Cu")
		(net "CHA_1_SA0")
	)
	(segment
		(start 128.949958 -70.806564)
		(end 128.949958 -71.583042)
		(width 0.1143)
		(layer "F.Cu")
		(net "CHA_1_SA0")
	)
	(segment
		(start 113.284 -71.882)
		(end 113.284 -71.5518)
		(width 0.1143)
		(layer "F.Cu")
		(net "CHA_1_SA0")
	)
	(segment
		(start 128.949958 -71.583042)
		(end 128.060196 -72.472804)
		(width 0.1143)
		(layer "F.Cu")
		(net "CHA_1_SA0")
	)
	(segment
		(start 113.874804 -72.472804)
		(end 113.284 -71.882)
		(width 0.1143)
		(layer "F.Cu")
		(net "CHA_1_SA0")
	)
	(segment
		(start 111.6076 -71.5264)
		(end 111.633 -71.5264)
		(width 0.1143)
		(layer "F.Cu")
		(net "CHA_1_SA0")
	)
	(segment
		(start 128.060196 -72.472804)
		(end 113.874804 -72.472804)
		(width 0.1143)
		(layer "F.Cu")
		(net "CHA_1_SA0")
	)
	(via
		(at 111.6076 -71.5264)
		(size 0.7112)
		(drill 0.3556)
		(layers "F.Cu" "B.Cu")
		(net "CHA_1_SA0")
	)
	(segment
		(start 11.06805 -25.3492)
		(end 10.795 -25.3492)
		(width 0.3048)
		(layer "F.Cu")
		(net "P1V0_VREG")
	)
	(segment
		(start 11.136376 -25.280874)
		(end 11.06805 -25.3492)
		(width 0.3048)
		(layer "F.Cu")
		(net "P1V0_VREG")
	)
	(segment
		(start 10.795 -25.3492)
		(end 10.541 -25.6032)
		(width 0.3048)
		(layer "F.Cu")
		(net "P1V0_VREG")
	)
	(segment
		(start 11.647678 -25.280874)
		(end 11.136376 -25.280874)
		(width 0.3048)
		(layer "F.Cu")
		(net "P1V0_VREG")
	)
	(via
		(at 15.4432 -22.225)
		(size 0.508)
		(drill 0.254)
		(layers "F.Cu" "B.Cu")
		(net "P1V0_VREG")
	)
	(via
		(at 15.367 -21.209)
		(size 0.7112)
		(drill 0.3556)
		(layers "F.Cu" "B.Cu")
		(net "P1V0_VREG")
	)
	(via
		(at 10.541 -25.6032)
		(size 0.508)
		(drill 0.254)
		(layers "F.Cu" "B.Cu")
		(net "P1V0_VREG")
	)
	(segment
		(start 11.2268 -22.907752)
		(end 11.2268 -24.9174)
		(width 0.3048)
		(layer "B.Cu")
		(net "P1V0_VREG")
	)
	(segment
		(start 15.4432 -22.225)
		(end 15.4432 -23.114)
		(width 0.508)
		(layer "B.Cu")
		(net "P1V0_VREG")
	)
	(segment
		(start 15.4432 -22.225)
		(end 15.4432 -21.2852)
		(width 0.508)
		(layer "B.Cu")
		(net "P1V0_VREG")
	)
	(segment
		(start 8.9408 -24.384)
		(end 8.9408 -25.1206)
		(width 0.3048)
		(layer "B.Cu")
		(net "P1V0_VREG")
	)
	(segment
		(start 8.9662 -25.146)
		(end 10.0838 -25.146)
		(width 0.3048)
		(layer "B.Cu")
		(net "P1V0_VREG")
	)
	(segment
		(start 10.493248 -22.1742)
		(end 11.2268 -22.907752)
		(width 0.3048)
		(layer "B.Cu")
		(net "P1V0_VREG")
	)
	(segment
		(start 8.9408 -25.1206)
		(end 8.9662 -25.146)
		(width 0.3048)
		(layer "B.Cu")
		(net "P1V0_VREG")
	)
	(segment
		(start 15.4432 -21.2852)
		(end 15.367 -21.209)
		(width 0.508)
		(layer "B.Cu")
		(net "P1V0_VREG")
	)
	(segment
		(start 11.2268 -24.9174)
		(end 10.541 -25.6032)
		(width 0.3048)
		(layer "B.Cu")
		(net "P1V0_VREG")
	)
	(segment
		(start 9.017 -22.1742)
		(end 10.493248 -22.1742)
		(width 0.3048)
		(layer "B.Cu")
		(net "P1V0_VREG")
	)
	(segment
		(start 10.0838 -25.146)
		(end 10.541 -25.6032)
		(width 0.3048)
		(layer "B.Cu")
		(net "P1V0_VREG")
	)
	(segment
		(start 13.9192 -23.749)
		(end 12.3952 -23.749)
		(width 0.508)
		(layer "In7.Cu")
		(net "P1V0_VREG")
	)
	(segment
		(start 12.3952 -23.749)
		(end 10.541 -25.6032)
		(width 0.508)
		(layer "In7.Cu")
		(net "P1V0_VREG")
	)
	(segment
		(start 15.4432 -22.225)
		(end 13.9192 -23.749)
		(width 0.508)
		(layer "In7.Cu")
		(net "P1V0_VREG")
	)
	(segment
		(start 9.017 -47.9044)
		(end 8.450072 -48.471328)
		(width 0.1143)
		(layer "F.Cu")
		(net "TEMP_1_A2")
	)
	(segment
		(start 9.017 -46.736)
		(end 9.017 -47.498)
		(width 0.1143)
		(layer "F.Cu")
		(net "TEMP_1_A2")
	)
	(segment
		(start 9.017 -47.498)
		(end 9.017 -47.9044)
		(width 0.1143)
		(layer "F.Cu")
		(net "TEMP_1_A2")
	)
	(segment
		(start 8.450072 -48.471328)
		(end 7.815326 -48.471328)
		(width 0.1143)
		(layer "F.Cu")
		(net "TEMP_1_A2")
	)
	(segment
		(start 12.573 -30.48)
		(end 13.4112 -29.6418)
		(width 0.3048)
		(layer "F.Cu")
		(net "P1V0_SNB")
	)
	(segment
		(start 14.0208 -29.464)
		(end 14.6558 -30.099)
		(width 0.508)
		(layer "F.Cu")
		(net "P1V0_SNB")
	)
	(segment
		(start 13.4112 -29.6418)
		(end 13.4112 -29.464)
		(width 0.3048)
		(layer "F.Cu")
		(net "P1V0_SNB")
	)
	(segment
		(start 13.4112 -29.464)
		(end 14.0208 -29.464)
		(width 0.508)
		(layer "F.Cu")
		(net "P1V0_SNB")
	)
	(via
		(at 12.573 -30.48)
		(size 0.7112)
		(drill 0.3556)
		(layers "F.Cu" "B.Cu")
		(net "P1V0_SNB")
	)
	(segment
		(start 183.526176 -68.7832)
		(end 183.4896 -68.7832)
		(width 0.1778)
		(layer "F.Cu")
		(net "M_A_DQ13")
	)
	(segment
		(start 183.769 -69.450458)
		(end 183.769 -69.026024)
		(width 0.1778)
		(layer "F.Cu")
		(net "M_A_DQ13")
	)
	(segment
		(start 184.15 -69.831458)
		(end 183.769 -69.450458)
		(width 0.1778)
		(layer "F.Cu")
		(net "M_A_DQ13")
	)
	(segment
		(start 105.385108 -43.642534)
		(end 105.7656 -43.2562)
		(width 0.1016)
		(layer "F.Cu")
		(net "M_A_DQ13")
	)
	(segment
		(start 183.769 -69.026024)
		(end 183.526176 -68.7832)
		(width 0.1778)
		(layer "F.Cu")
		(net "M_A_DQ13")
	)
	(segment
		(start 184.15 -70.806564)
		(end 184.15 -69.831458)
		(width 0.1778)
		(layer "F.Cu")
		(net "M_A_DQ13")
	)
	(via
		(at 183.4896 -68.7832)
		(size 0.4318)
		(drill 0.2032)
		(layers "F.Cu" "B.Cu")
		(net "M_A_DQ13")
	)
	(via
		(at 105.7656 -43.2562)
		(size 0.4318)
		(drill 0.2032)
		(layers "F.Cu" "B.Cu")
		(net "M_A_DQ13")
	)
	(segment
		(start 183.250078 -70.79996)
		(end 183.250078 -70.038722)
		(width 0.1778)
		(layer "B.Cu")
		(net "M_A_DQ13")
	)
	(segment
		(start 183.7944 -69.4944)
		(end 183.7944 -69.051424)
		(width 0.1778)
		(layer "B.Cu")
		(net "M_A_DQ13")
	)
	(segment
		(start 183.526176 -68.7832)
		(end 183.4896 -68.7832)
		(width 0.1778)
		(layer "B.Cu")
		(net "M_A_DQ13")
	)
	(segment
		(start 183.7944 -69.051424)
		(end 183.526176 -68.7832)
		(width 0.1778)
		(layer "B.Cu")
		(net "M_A_DQ13")
	)
	(segment
		(start 183.250078 -70.038722)
		(end 183.7944 -69.4944)
		(width 0.1778)
		(layer "B.Cu")
		(net "M_A_DQ13")
	)
	(segment
		(start 183.4896 -67.8942)
		(end 183.4896 -68.7832)
		(width 0.1524)
		(layer "In4.Cu")
		(net "M_A_DQ13")
	)
	(segment
		(start 109.510322 -41.199562)
		(end 107.520994 -41.199562)
		(width 0.1016)
		(layer "In4.Cu")
		(net "M_A_DQ13")
	)
	(segment
		(start 174.10557 -49.939194)
		(end 174.142146 -50.151538)
		(width 0.1524)
		(layer "In4.Cu")
		(net "M_A_DQ13")
	)
	(segment
		(start 184.8104 -64.36741)
		(end 183.769 -66.7512)
		(width 0.1524)
		(layer "In4.Cu")
		(net "M_A_DQ13")
	)
	(segment
		(start 175.636428 -51.207416)
		(end 175.848518 -51.171094)
		(width 0.1524)
		(layer "In4.Cu")
		(net "M_A_DQ13")
	)
	(segment
		(start 110.9472 -41.0718)
		(end 109.638084 -41.0718)
		(width 0.1016)
		(layer "In4.Cu")
		(net "M_A_DQ13")
	)
	(segment
		(start 106.135678 -42.074338)
		(end 105.947718 -42.262298)
		(width 0.1016)
		(layer "In4.Cu")
		(net "M_A_DQ13")
	)
	(segment
		(start 174.956216 -51.113436)
		(end 174.992792 -51.325526)
		(width 0.1524)
		(layer "In4.Cu")
		(net "M_A_DQ13")
	)
	(segment
		(start 176.9491 -51.948842)
		(end 182.118 -57.117742)
		(width 0.1524)
		(layer "In4.Cu")
		(net "M_A_DQ13")
	)
	(segment
		(start 109.638084 -41.0718)
		(end 109.510322 -41.199562)
		(width 0.1016)
		(layer "In4.Cu")
		(net "M_A_DQ13")
	)
	(segment
		(start 165.888162 -44.1325)
		(end 174.10557 -49.939194)
		(width 0.1524)
		(layer "In4.Cu")
		(net "M_A_DQ13")
	)
	(segment
		(start 118.8212 -40.9702)
		(end 119.0752 -41.2242)
		(width 0.1524)
		(layer "In4.Cu")
		(net "M_A_DQ13")
	)
	(segment
		(start 119.0752 -41.2242)
		(end 154.305 -41.2242)
		(width 0.1524)
		(layer "In4.Cu")
		(net "M_A_DQ13")
	)
	(segment
		(start 106.912156 -41.8084)
		(end 106.7054 -41.8084)
		(width 0.1016)
		(layer "In4.Cu")
		(net "M_A_DQ13")
	)
	(segment
		(start 174.64024 -50.503328)
		(end 174.85233 -50.467006)
		(width 0.1524)
		(layer "In4.Cu")
		(net "M_A_DQ13")
	)
	(segment
		(start 105.947718 -42.262298)
		(end 105.7656 -42.844212)
		(width 0.1016)
		(layer "In4.Cu")
		(net "M_A_DQ13")
	)
	(segment
		(start 111.0488 -40.9702)
		(end 118.8212 -40.9702)
		(width 0.1524)
		(layer "In4.Cu")
		(net "M_A_DQ13")
	)
	(segment
		(start 107.520994 -41.199562)
		(end 106.912156 -41.8084)
		(width 0.1016)
		(layer "In4.Cu")
		(net "M_A_DQ13")
	)
	(segment
		(start 184.3024 -60.634626)
		(end 184.8104 -63.070486)
		(width 0.1524)
		(layer "In4.Cu")
		(net "M_A_DQ13")
	)
	(segment
		(start 175.101758 -50.643282)
		(end 175.138334 -50.855626)
		(width 0.1524)
		(layer "In4.Cu")
		(net "M_A_DQ13")
	)
	(segment
		(start 154.305 -41.2242)
		(end 165.888162 -44.1325)
		(width 0.1524)
		(layer "In4.Cu")
		(net "M_A_DQ13")
	)
	(segment
		(start 183.769 -66.7512)
		(end 183.769 -67.6148)
		(width 0.1524)
		(layer "In4.Cu")
		(net "M_A_DQ13")
	)
	(segment
		(start 174.142146 -50.151538)
		(end 173.960028 -50.409348)
		(width 0.1524)
		(layer "In4.Cu")
		(net "M_A_DQ13")
	)
	(segment
		(start 174.458122 -50.761138)
		(end 174.64024 -50.503328)
		(width 0.1524)
		(layer "In4.Cu")
		(net "M_A_DQ13")
	)
	(segment
		(start 174.992792 -51.325526)
		(end 175.24222 -51.501802)
		(width 0.1524)
		(layer "In4.Cu")
		(net "M_A_DQ13")
	)
	(segment
		(start 173.960028 -50.409348)
		(end 173.996604 -50.621438)
		(width 0.1524)
		(layer "In4.Cu")
		(net "M_A_DQ13")
	)
	(segment
		(start 175.45431 -51.465226)
		(end 175.636428 -51.207416)
		(width 0.1524)
		(layer "In4.Cu")
		(net "M_A_DQ13")
	)
	(segment
		(start 174.85233 -50.467006)
		(end 175.101758 -50.643282)
		(width 0.1524)
		(layer "In4.Cu")
		(net "M_A_DQ13")
	)
	(segment
		(start 106.186986 -42.023284)
		(end 106.135678 -42.074338)
		(width 0.1016)
		(layer "In4.Cu")
		(net "M_A_DQ13")
	)
	(segment
		(start 110.9472 -41.0718)
		(end 111.0488 -40.9702)
		(width 0.1524)
		(layer "In4.Cu")
		(net "M_A_DQ13")
	)
	(segment
		(start 182.118 -57.117742)
		(end 184.3024 -60.634626)
		(width 0.1524)
		(layer "In4.Cu")
		(net "M_A_DQ13")
	)
	(segment
		(start 183.769 -67.6148)
		(end 183.4896 -67.8942)
		(width 0.1524)
		(layer "In4.Cu")
		(net "M_A_DQ13")
	)
	(segment
		(start 105.7656 -42.844212)
		(end 105.7656 -43.2562)
		(width 0.1016)
		(layer "In4.Cu")
		(net "M_A_DQ13")
	)
	(segment
		(start 173.996604 -50.621438)
		(end 174.246032 -50.797714)
		(width 0.1524)
		(layer "In4.Cu")
		(net "M_A_DQ13")
	)
	(segment
		(start 184.8104 -63.070486)
		(end 184.8104 -64.36741)
		(width 0.1524)
		(layer "In4.Cu")
		(net "M_A_DQ13")
	)
	(segment
		(start 175.138334 -50.855626)
		(end 174.956216 -51.113436)
		(width 0.1524)
		(layer "In4.Cu")
		(net "M_A_DQ13")
	)
	(segment
		(start 175.24222 -51.501802)
		(end 175.45431 -51.465226)
		(width 0.1524)
		(layer "In4.Cu")
		(net "M_A_DQ13")
	)
	(segment
		(start 175.848518 -51.171094)
		(end 176.9491 -51.948842)
		(width 0.1524)
		(layer "In4.Cu")
		(net "M_A_DQ13")
	)
	(segment
		(start 174.246032 -50.797714)
		(end 174.458122 -50.761138)
		(width 0.1524)
		(layer "In4.Cu")
		(net "M_A_DQ13")
	)
	(arc
		(start 106.7054 -41.8084)
		(mid 106.424833 -41.864302)
		(end 106.186986 -42.023284)
		(width 0.1016)
		(layer "In4.Cu")
		(net "M_A_DQ13")
	)
	(segment
		(start 96.251268 -38.399974)
		(end 96.251268 -38.393116)
		(width 0.254)
		(layer "F.Cu")
		(net "VCCRAMCPUSI1_SENSE")
	)
	(segment
		(start 96.251268 -38.393116)
		(end 95.878904 -38.020752)
		(width 0.254)
		(layer "F.Cu")
		(net "VCCRAMCPUSI1_SENSE")
	)
	(via
		(at 105.696512 -68.293488)
		(size 0.7112)
		(drill 0.3556)
		(layers "F.Cu" "B.Cu")
		(net "VCCRAMCPUSI1_SENSE")
	)
	(via
		(at 95.878904 -38.020752)
		(size 0.4318)
		(drill 0.2032)
		(layers "F.Cu" "B.Cu")
		(net "VCCRAMCPUSI1_SENSE")
	)
	(via
		(at 105.696512 -69.315584)
		(size 0.508)
		(drill 0.254)
		(layers "F.Cu" "B.Cu")
		(net "VCCRAMCPUSI1_SENSE")
	)
	(segment
		(start 105.696512 -68.293488)
		(end 105.696512 -69.315584)
		(width 0.254)
		(layer "B.Cu")
		(net "VCCRAMCPUSI1_SENSE")
	)
	(segment
		(start 105.696512 -67.342512)
		(end 105.696512 -68.293488)
		(width 0.254)
		(layer "B.Cu")
		(net "VCCRAMCPUSI1_SENSE")
	)
	(segment
		(start 105.1052 -66.7512)
		(end 105.696512 -67.342512)
		(width 0.254)
		(layer "B.Cu")
		(net "VCCRAMCPUSI1_SENSE")
	)
	(segment
		(start 104.8004 -66.7512)
		(end 105.1052 -66.7512)
		(width 0.254)
		(layer "B.Cu")
		(net "VCCRAMCPUSI1_SENSE")
	)
	(segment
		(start 92.2655 -42.4815)
		(end 92.2655 -43.274234)
		(width 0.254)
		(layer "In2.Cu")
		(net "VCCRAMCPUSI1_SENSE")
	)
	(segment
		(start 91.57843 -49.599596)
		(end 92.272358 -50.293524)
		(width 0.254)
		(layer "In2.Cu")
		(net "VCCRAMCPUSI1_SENSE")
	)
	(segment
		(start 94.742 -37.3634)
		(end 94.160848 -37.944552)
		(width 0.254)
		(layer "In2.Cu")
		(net "VCCRAMCPUSI1_SENSE")
	)
	(segment
		(start 93.0021 -39.8653)
		(end 93.0021 -40.9321)
		(width 0.254)
		(layer "In2.Cu")
		(net "VCCRAMCPUSI1_SENSE")
	)
	(segment
		(start 95.5294 -37.3634)
		(end 94.742 -37.3634)
		(width 0.254)
		(layer "In2.Cu")
		(net "VCCRAMCPUSI1_SENSE")
	)
	(segment
		(start 91.3003 -44.239434)
		(end 91.3003 -46.70425)
		(width 0.254)
		(layer "In2.Cu")
		(net "VCCRAMCPUSI1_SENSE")
	)
	(segment
		(start 94.160848 -37.944552)
		(end 94.160848 -38.706552)
		(width 0.254)
		(layer "In2.Cu")
		(net "VCCRAMCPUSI1_SENSE")
	)
	(segment
		(start 94.74962 -63.627)
		(end 103.042974 -63.627)
		(width 0.254)
		(layer "In2.Cu")
		(net "VCCRAMCPUSI1_SENSE")
	)
	(segment
		(start 92.272358 -50.293524)
		(end 92.272358 -56.690768)
		(width 0.254)
		(layer "In2.Cu")
		(net "VCCRAMCPUSI1_SENSE")
	)
	(segment
		(start 93.3196 -62.19698)
		(end 94.74962 -63.627)
		(width 0.254)
		(layer "In2.Cu")
		(net "VCCRAMCPUSI1_SENSE")
	)
	(segment
		(start 92.2655 -43.274234)
		(end 91.3003 -44.239434)
		(width 0.254)
		(layer "In2.Cu")
		(net "VCCRAMCPUSI1_SENSE")
	)
	(segment
		(start 95.878904 -38.020752)
		(end 95.878904 -37.712904)
		(width 0.254)
		(layer "In2.Cu")
		(net "VCCRAMCPUSI1_SENSE")
	)
	(segment
		(start 91.3257 -46.72965)
		(end 91.3257 -47.54245)
		(width 0.254)
		(layer "In2.Cu")
		(net "VCCRAMCPUSI1_SENSE")
	)
	(segment
		(start 91.3003 -46.70425)
		(end 91.3257 -46.72965)
		(width 0.254)
		(layer "In2.Cu")
		(net "VCCRAMCPUSI1_SENSE")
	)
	(segment
		(start 93.3196 -57.738264)
		(end 93.3196 -62.19698)
		(width 0.254)
		(layer "In2.Cu")
		(net "VCCRAMCPUSI1_SENSE")
	)
	(segment
		(start 91.575128 -49.599596)
		(end 91.57843 -49.599596)
		(width 0.254)
		(layer "In2.Cu")
		(net "VCCRAMCPUSI1_SENSE")
	)
	(segment
		(start 91.3257 -47.54245)
		(end 91.314778 -47.553372)
		(width 0.254)
		(layer "In2.Cu")
		(net "VCCRAMCPUSI1_SENSE")
	)
	(segment
		(start 105.6132 -69.232272)
		(end 105.696512 -69.315584)
		(width 0.254)
		(layer "In2.Cu")
		(net "VCCRAMCPUSI1_SENSE")
	)
	(segment
		(start 92.1639 -42.3799)
		(end 92.2655 -42.4815)
		(width 0.254)
		(layer "In2.Cu")
		(net "VCCRAMCPUSI1_SENSE")
	)
	(segment
		(start 105.6132 -66.197226)
		(end 105.6132 -69.232272)
		(width 0.254)
		(layer "In2.Cu")
		(net "VCCRAMCPUSI1_SENSE")
	)
	(segment
		(start 94.160848 -38.706552)
		(end 93.0021 -39.8653)
		(width 0.254)
		(layer "In2.Cu")
		(net "VCCRAMCPUSI1_SENSE")
	)
	(segment
		(start 91.314778 -47.553372)
		(end 91.314778 -49.339246)
		(width 0.254)
		(layer "In2.Cu")
		(net "VCCRAMCPUSI1_SENSE")
	)
	(segment
		(start 92.272358 -56.690768)
		(end 93.3196 -57.738264)
		(width 0.254)
		(layer "In2.Cu")
		(net "VCCRAMCPUSI1_SENSE")
	)
	(segment
		(start 93.0021 -40.9321)
		(end 92.1639 -41.7703)
		(width 0.254)
		(layer "In2.Cu")
		(net "VCCRAMCPUSI1_SENSE")
	)
	(segment
		(start 91.314778 -49.339246)
		(end 91.575128 -49.599596)
		(width 0.254)
		(layer "In2.Cu")
		(net "VCCRAMCPUSI1_SENSE")
	)
	(segment
		(start 92.1639 -41.7703)
		(end 92.1639 -42.3799)
		(width 0.254)
		(layer "In2.Cu")
		(net "VCCRAMCPUSI1_SENSE")
	)
	(segment
		(start 103.042974 -63.627)
		(end 105.6132 -66.197226)
		(width 0.254)
		(layer "In2.Cu")
		(net "VCCRAMCPUSI1_SENSE")
	)
	(segment
		(start 95.878904 -37.712904)
		(end 95.5294 -37.3634)
		(width 0.254)
		(layer "In2.Cu")
		(net "VCCRAMCPUSI1_SENSE")
	)
	(segment
		(start 143.050006 -64.340994)
		(end 142.6718 -64.7192)
		(width 0.1778)
		(layer "F.Cu")
		(net "M_A_DQ41")
	)
	(segment
		(start 104.297988 -52.140612)
		(end 104.297988 -51.880262)
		(width 0.1016)
		(layer "F.Cu")
		(net "M_A_DQ41")
	)
	(segment
		(start 142.613126 -64.7192)
		(end 142.600426 -64.7319)
		(width 0.1778)
		(layer "F.Cu")
		(net "M_A_DQ41")
	)
	(segment
		(start 104.071928 -51.654202)
		(end 104.071928 -50.952654)
		(width 0.1016)
		(layer "F.Cu")
		(net "M_A_DQ41")
	)
	(segment
		(start 104.225852 -52.212748)
		(end 104.297988 -52.140612)
		(width 0.1016)
		(layer "F.Cu")
		(net "M_A_DQ41")
	)
	(segment
		(start 104.225852 -53.222652)
		(end 104.225852 -52.212748)
		(width 0.1016)
		(layer "F.Cu")
		(net "M_A_DQ41")
	)
	(segment
		(start 142.6718 -64.7192)
		(end 142.613126 -64.7192)
		(width 0.1778)
		(layer "F.Cu")
		(net "M_A_DQ41")
	)
	(segment
		(start 143.050006 -62.59322)
		(end 143.050006 -64.340994)
		(width 0.1778)
		(layer "F.Cu")
		(net "M_A_DQ41")
	)
	(segment
		(start 105.5624 -56.5658)
		(end 105.1306 -56.134)
		(width 0.1016)
		(layer "F.Cu")
		(net "M_A_DQ41")
	)
	(segment
		(start 105.1306 -56.134)
		(end 105.1306 -54.1274)
		(width 0.1016)
		(layer "F.Cu")
		(net "M_A_DQ41")
	)
	(segment
		(start 104.297988 -51.880262)
		(end 104.071928 -51.654202)
		(width 0.1016)
		(layer "F.Cu")
		(net "M_A_DQ41")
	)
	(segment
		(start 105.1306 -54.1274)
		(end 104.225852 -53.222652)
		(width 0.1016)
		(layer "F.Cu")
		(net "M_A_DQ41")
	)
	(via
		(at 105.5624 -56.5658)
		(size 0.4318)
		(drill 0.2032)
		(layers "F.Cu" "B.Cu")
		(net "M_A_DQ41")
	)
	(via
		(at 142.600426 -64.7319)
		(size 0.4318)
		(drill 0.2032)
		(layers "F.Cu" "B.Cu")
		(net "M_A_DQ41")
	)
	(segment
		(start 142.81277 -64.50203)
		(end 142.600426 -64.714374)
		(width 0.1778)
		(layer "B.Cu")
		(net "M_A_DQ41")
	)
	(segment
		(start 142.150084 -62.599824)
		(end 142.150084 -63.294006)
		(width 0.1778)
		(layer "B.Cu")
		(net "M_A_DQ41")
	)
	(segment
		(start 142.81277 -63.956692)
		(end 142.81277 -64.50203)
		(width 0.1778)
		(layer "B.Cu")
		(net "M_A_DQ41")
	)
	(segment
		(start 142.150084 -63.294006)
		(end 142.81277 -63.956692)
		(width 0.1778)
		(layer "B.Cu")
		(net "M_A_DQ41")
	)
	(segment
		(start 142.600426 -64.714374)
		(end 142.600426 -64.7319)
		(width 0.1778)
		(layer "B.Cu")
		(net "M_A_DQ41")
	)
	(segment
		(start 125.787404 -56.5912)
		(end 125.787404 -57.305702)
		(width 0.1524)
		(layer "In2.Cu")
		(net "M_A_DQ41")
	)
	(segment
		(start 128.225804 -56.5912)
		(end 128.225804 -57.305702)
		(width 0.1524)
		(layer "In2.Cu")
		(net "M_A_DQ41")
	)
	(segment
		(start 125.939804 -57.458102)
		(end 126.244604 -57.458102)
		(width 0.1524)
		(layer "In2.Cu")
		(net "M_A_DQ41")
	)
	(segment
		(start 126.397004 -56.5912)
		(end 126.549404 -56.4388)
		(width 0.1524)
		(layer "In2.Cu")
		(net "M_A_DQ41")
	)
	(segment
		(start 127.463804 -57.458102)
		(end 127.616204 -57.305702)
		(width 0.1524)
		(layer "In2.Cu")
		(net "M_A_DQ41")
	)
	(segment
		(start 127.768604 -56.4388)
		(end 128.073404 -56.4388)
		(width 0.1524)
		(layer "In2.Cu")
		(net "M_A_DQ41")
	)
	(segment
		(start 131.273804 -57.305702)
		(end 131.273804 -56.9722)
		(width 0.1524)
		(layer "In2.Cu")
		(net "M_A_DQ41")
	)
	(segment
		(start 126.244604 -57.458102)
		(end 126.397004 -57.305702)
		(width 0.1524)
		(layer "In2.Cu")
		(net "M_A_DQ41")
	)
	(segment
		(start 134.4803 -57.5183)
		(end 138.708384 -57.5183)
		(width 0.1524)
		(layer "In2.Cu")
		(net "M_A_DQ41")
	)
	(segment
		(start 142.823184 -63.909956)
		(end 142.823184 -64.491616)
		(width 0.1524)
		(layer "In2.Cu")
		(net "M_A_DQ41")
	)
	(segment
		(start 126.549404 -56.4388)
		(end 126.854204 -56.4388)
		(width 0.1524)
		(layer "In2.Cu")
		(net "M_A_DQ41")
	)
	(segment
		(start 131.883404 -56.9722)
		(end 131.883404 -57.305702)
		(width 0.1524)
		(layer "In2.Cu")
		(net "M_A_DQ41")
	)
	(segment
		(start 133.615938 -57.8612)
		(end 134.1374 -57.8612)
		(width 0.1524)
		(layer "In2.Cu")
		(net "M_A_DQ41")
	)
	(segment
		(start 129.445004 -56.5912)
		(end 129.445004 -57.305702)
		(width 0.1524)
		(layer "In2.Cu")
		(net "M_A_DQ41")
	)
	(segment
		(start 127.006604 -57.305702)
		(end 127.159004 -57.458102)
		(width 0.1524)
		(layer "In2.Cu")
		(net "M_A_DQ41")
	)
	(segment
		(start 132.035804 -57.458102)
		(end 133.21284 -57.458102)
		(width 0.1524)
		(layer "In2.Cu")
		(net "M_A_DQ41")
	)
	(segment
		(start 128.225804 -57.305702)
		(end 128.378204 -57.458102)
		(width 0.1524)
		(layer "In2.Cu")
		(net "M_A_DQ41")
	)
	(segment
		(start 128.683004 -57.458102)
		(end 128.835404 -57.305702)
		(width 0.1524)
		(layer "In2.Cu")
		(net "M_A_DQ41")
	)
	(segment
		(start 127.616204 -57.305702)
		(end 127.616204 -56.5912)
		(width 0.1524)
		(layer "In2.Cu")
		(net "M_A_DQ41")
	)
	(segment
		(start 128.835404 -56.5912)
		(end 128.987804 -56.4388)
		(width 0.1524)
		(layer "In2.Cu")
		(net "M_A_DQ41")
	)
	(segment
		(start 105.5624 -56.5658)
		(end 105.5624 -57.2516)
		(width 0.1524)
		(layer "In2.Cu")
		(net "M_A_DQ41")
	)
	(segment
		(start 126.397004 -57.305702)
		(end 126.397004 -56.5912)
		(width 0.1524)
		(layer "In2.Cu")
		(net "M_A_DQ41")
	)
	(segment
		(start 125.177804 -57.305702)
		(end 125.177804 -56.5912)
		(width 0.1524)
		(layer "In2.Cu")
		(net "M_A_DQ41")
	)
	(segment
		(start 131.883404 -57.305702)
		(end 132.035804 -57.458102)
		(width 0.1524)
		(layer "In2.Cu")
		(net "M_A_DQ41")
	)
	(segment
		(start 128.987804 -56.4388)
		(end 129.292604 -56.4388)
		(width 0.1524)
		(layer "In2.Cu")
		(net "M_A_DQ41")
	)
	(segment
		(start 125.635004 -56.4388)
		(end 125.787404 -56.5912)
		(width 0.1524)
		(layer "In2.Cu")
		(net "M_A_DQ41")
	)
	(segment
		(start 131.273804 -56.9722)
		(end 131.426204 -56.8198)
		(width 0.1524)
		(layer "In2.Cu")
		(net "M_A_DQ41")
	)
	(segment
		(start 128.073404 -56.4388)
		(end 128.225804 -56.5912)
		(width 0.1524)
		(layer "In2.Cu")
		(net "M_A_DQ41")
	)
	(segment
		(start 106.1466 -57.8358)
		(end 107.696 -57.8358)
		(width 0.1524)
		(layer "In2.Cu")
		(net "M_A_DQ41")
	)
	(segment
		(start 125.177804 -56.5912)
		(end 125.330204 -56.4388)
		(width 0.1524)
		(layer "In2.Cu")
		(net "M_A_DQ41")
	)
	(segment
		(start 129.597404 -57.458102)
		(end 131.121404 -57.458102)
		(width 0.1524)
		(layer "In2.Cu")
		(net "M_A_DQ41")
	)
	(segment
		(start 125.787404 -57.305702)
		(end 125.939804 -57.458102)
		(width 0.1524)
		(layer "In2.Cu")
		(net "M_A_DQ41")
	)
	(segment
		(start 107.696 -57.8358)
		(end 108.073698 -57.458102)
		(width 0.1524)
		(layer "In2.Cu")
		(net "M_A_DQ41")
	)
	(segment
		(start 133.21284 -57.458102)
		(end 133.615938 -57.8612)
		(width 0.1524)
		(layer "In2.Cu")
		(net "M_A_DQ41")
	)
	(segment
		(start 134.1374 -57.8612)
		(end 134.4803 -57.5183)
		(width 0.1524)
		(layer "In2.Cu")
		(net "M_A_DQ41")
	)
	(segment
		(start 105.5624 -57.2516)
		(end 106.1466 -57.8358)
		(width 0.1524)
		(layer "In2.Cu")
		(net "M_A_DQ41")
	)
	(segment
		(start 131.426204 -56.8198)
		(end 131.731004 -56.8198)
		(width 0.1524)
		(layer "In2.Cu")
		(net "M_A_DQ41")
	)
	(segment
		(start 127.159004 -57.458102)
		(end 127.463804 -57.458102)
		(width 0.1524)
		(layer "In2.Cu")
		(net "M_A_DQ41")
	)
	(segment
		(start 127.006604 -56.5912)
		(end 127.006604 -57.305702)
		(width 0.1524)
		(layer "In2.Cu")
		(net "M_A_DQ41")
	)
	(segment
		(start 128.835404 -57.305702)
		(end 128.835404 -56.5912)
		(width 0.1524)
		(layer "In2.Cu")
		(net "M_A_DQ41")
	)
	(segment
		(start 129.292604 -56.4388)
		(end 129.445004 -56.5912)
		(width 0.1524)
		(layer "In2.Cu")
		(net "M_A_DQ41")
	)
	(segment
		(start 125.330204 -56.4388)
		(end 125.635004 -56.4388)
		(width 0.1524)
		(layer "In2.Cu")
		(net "M_A_DQ41")
	)
	(segment
		(start 129.445004 -57.305702)
		(end 129.597404 -57.458102)
		(width 0.1524)
		(layer "In2.Cu")
		(net "M_A_DQ41")
	)
	(segment
		(start 125.025404 -57.458102)
		(end 125.177804 -57.305702)
		(width 0.1524)
		(layer "In2.Cu")
		(net "M_A_DQ41")
	)
	(segment
		(start 142.600426 -64.714374)
		(end 142.600426 -64.7319)
		(width 0.1524)
		(layer "In2.Cu")
		(net "M_A_DQ41")
	)
	(segment
		(start 142.8242 -61.634116)
		(end 142.8242 -63.90894)
		(width 0.1524)
		(layer "In2.Cu")
		(net "M_A_DQ41")
	)
	(segment
		(start 108.073698 -57.458102)
		(end 125.025404 -57.458102)
		(width 0.1524)
		(layer "In2.Cu")
		(net "M_A_DQ41")
	)
	(segment
		(start 142.823184 -64.491616)
		(end 142.600426 -64.714374)
		(width 0.1524)
		(layer "In2.Cu")
		(net "M_A_DQ41")
	)
	(segment
		(start 138.708384 -57.5183)
		(end 142.8242 -61.634116)
		(width 0.1524)
		(layer "In2.Cu")
		(net "M_A_DQ41")
	)
	(segment
		(start 142.8242 -63.90894)
		(end 142.823184 -63.909956)
		(width 0.1524)
		(layer "In2.Cu")
		(net "M_A_DQ41")
	)
	(segment
		(start 131.121404 -57.458102)
		(end 131.273804 -57.305702)
		(width 0.1524)
		(layer "In2.Cu")
		(net "M_A_DQ41")
	)
	(segment
		(start 127.616204 -56.5912)
		(end 127.768604 -56.4388)
		(width 0.1524)
		(layer "In2.Cu")
		(net "M_A_DQ41")
	)
	(segment
		(start 126.854204 -56.4388)
		(end 127.006604 -56.5912)
		(width 0.1524)
		(layer "In2.Cu")
		(net "M_A_DQ41")
	)
	(segment
		(start 128.378204 -57.458102)
		(end 128.683004 -57.458102)
		(width 0.1524)
		(layer "In2.Cu")
		(net "M_A_DQ41")
	)
	(segment
		(start 131.731004 -56.8198)
		(end 131.883404 -56.9722)
		(width 0.1524)
		(layer "In2.Cu")
		(net "M_A_DQ41")
	)
	(segment
		(start 101.338888 -46.116494)
		(end 101.338888 -46.144688)
		(width 0.1016)
		(layer "F.Cu")
		(net "M_A_MA13")
	)
	(segment
		(start 149.628606 -66.011806)
		(end 150.072598 -66.011806)
		(width 0.2413)
		(layer "F.Cu")
		(net "M_A_MA13")
	)
	(segment
		(start 149.049994 -62.59322)
		(end 149.049994 -63.561722)
		(width 0.2413)
		(layer "F.Cu")
		(net "M_A_MA13")
	)
	(segment
		(start 148.759418 -63.852298)
		(end 148.759418 -65.142618)
		(width 0.2413)
		(layer "F.Cu")
		(net "M_A_MA13")
	)
	(segment
		(start 101.338888 -46.144688)
		(end 101.6254 -46.4312)
		(width 0.1016)
		(layer "F.Cu")
		(net "M_A_MA13")
	)
	(segment
		(start 101.6254 -46.4312)
		(end 101.6254 -46.434756)
		(width 0.1016)
		(layer "F.Cu")
		(net "M_A_MA13")
	)
	(segment
		(start 149.049994 -63.561722)
		(end 148.759418 -63.852298)
		(width 0.2413)
		(layer "F.Cu")
		(net "M_A_MA13")
	)
	(segment
		(start 148.759418 -65.142618)
		(end 149.628606 -66.011806)
		(width 0.2413)
		(layer "F.Cu")
		(net "M_A_MA13")
	)
	(segment
		(start 101.6254 -46.434756)
		(end 101.664008 -46.473364)
		(width 0.1016)
		(layer "F.Cu")
		(net "M_A_MA13")
	)
	(via
		(at 150.072598 -66.011806)
		(size 0.4318)
		(drill 0.2032)
		(layers "F.Cu" "B.Cu")
		(net "M_A_MA13")
	)
	(via
		(at 101.664008 -46.473364)
		(size 0.4318)
		(drill 0.2032)
		(layers "F.Cu" "B.Cu")
		(net "M_A_MA13")
	)
	(segment
		(start 148.884894 -67.015106)
		(end 149.888194 -66.011806)
		(width 0.2413)
		(layer "B.Cu")
		(net "M_A_MA13")
	)
	(segment
		(start 149.888194 -66.011806)
		(end 150.072598 -66.011806)
		(width 0.2413)
		(layer "B.Cu")
		(net "M_A_MA13")
	)
	(segment
		(start 149.049994 -69.727064)
		(end 148.884894 -69.561964)
		(width 0.2413)
		(layer "B.Cu")
		(net "M_A_MA13")
	)
	(segment
		(start 149.049994 -70.79996)
		(end 149.049994 -69.727064)
		(width 0.2413)
		(layer "B.Cu")
		(net "M_A_MA13")
	)
	(segment
		(start 148.884894 -69.561964)
		(end 148.884894 -67.015106)
		(width 0.2413)
		(layer "B.Cu")
		(net "M_A_MA13")
	)
	(segment
		(start 149.455886 -63.5762)
		(end 149.303486 -63.4238)
		(width 0.1905)
		(layer "In9.Cu")
		(net "M_A_MA13")
	)
	(segment
		(start 100.97008 -50.42916)
		(end 100.3427 -49.80178)
		(width 0.1016)
		(layer "In9.Cu")
		(net "M_A_MA13")
	)
	(segment
		(start 150.072598 -65.5828)
		(end 150.224998 -65.4304)
		(width 0.1905)
		(layer "In9.Cu")
		(net "M_A_MA13")
	)
	(segment
		(start 150.677118 -65.278)
		(end 150.677118 -63.7286)
		(width 0.1905)
		(layer "In9.Cu")
		(net "M_A_MA13")
	)
	(segment
		(start 149.303486 -62.181486)
		(end 148.0312 -60.9092)
		(width 0.1905)
		(layer "In9.Cu")
		(net "M_A_MA13")
	)
	(segment
		(start 150.072598 -66.011806)
		(end 150.072598 -65.5828)
		(width 0.1905)
		(layer "In9.Cu")
		(net "M_A_MA13")
	)
	(segment
		(start 100.18522 -49.421542)
		(end 100.18522 -48.772064)
		(width 0.1016)
		(layer "In9.Cu")
		(net "M_A_MA13")
	)
	(segment
		(start 149.303486 -63.4238)
		(end 149.303486 -62.181486)
		(width 0.1905)
		(layer "In9.Cu")
		(net "M_A_MA13")
	)
	(segment
		(start 100.1141 -47.874682)
		(end 100.099368 -47.85995)
		(width 0.1016)
		(layer "In9.Cu")
		(net "M_A_MA13")
	)
	(segment
		(start 100.579174 -47.21352)
		(end 101.31933 -46.473364)
		(width 0.1016)
		(layer "In9.Cu")
		(net "M_A_MA13")
	)
	(segment
		(start 105.33761 -59.8805)
		(end 104.2162 -58.75909)
		(width 0.1905)
		(layer "In9.Cu")
		(net "M_A_MA13")
	)
	(segment
		(start 148.0312 -60.9092)
		(end 144.8562 -60.9092)
		(width 0.1905)
		(layer "In9.Cu")
		(net "M_A_MA13")
	)
	(segment
		(start 150.524718 -63.5762)
		(end 149.455886 -63.5762)
		(width 0.1905)
		(layer "In9.Cu")
		(net "M_A_MA13")
	)
	(segment
		(start 100.099368 -47.85995)
		(end 100.099368 -47.550832)
		(width 0.1016)
		(layer "In9.Cu")
		(net "M_A_MA13")
	)
	(segment
		(start 144.8562 -60.9092)
		(end 144.5387 -60.5917)
		(width 0.1905)
		(layer "In9.Cu")
		(net "M_A_MA13")
	)
	(segment
		(start 100.43668 -47.21352)
		(end 100.579174 -47.21352)
		(width 0.1016)
		(layer "In9.Cu")
		(net "M_A_MA13")
	)
	(segment
		(start 150.677118 -63.7286)
		(end 150.524718 -63.5762)
		(width 0.1905)
		(layer "In9.Cu")
		(net "M_A_MA13")
	)
	(segment
		(start 101.08438 -50.42916)
		(end 100.97008 -50.42916)
		(width 0.1016)
		(layer "In9.Cu")
		(net "M_A_MA13")
	)
	(segment
		(start 100.099368 -47.550832)
		(end 100.43668 -47.21352)
		(width 0.1016)
		(layer "In9.Cu")
		(net "M_A_MA13")
	)
	(segment
		(start 150.524718 -65.4304)
		(end 150.677118 -65.278)
		(width 0.1905)
		(layer "In9.Cu")
		(net "M_A_MA13")
	)
	(segment
		(start 103.59771 -52.94249)
		(end 101.08438 -50.42916)
		(width 0.1016)
		(layer "In9.Cu")
		(net "M_A_MA13")
	)
	(segment
		(start 144.5387 -60.5917)
		(end 121.83237 -60.5917)
		(width 0.1905)
		(layer "In9.Cu")
		(net "M_A_MA13")
	)
	(segment
		(start 121.83237 -60.5917)
		(end 121.12117 -59.8805)
		(width 0.1905)
		(layer "In9.Cu")
		(net "M_A_MA13")
	)
	(segment
		(start 100.1141 -48.60036)
		(end 100.1141 -47.874682)
		(width 0.1016)
		(layer "In9.Cu")
		(net "M_A_MA13")
	)
	(segment
		(start 150.224998 -65.4304)
		(end 150.524718 -65.4304)
		(width 0.1905)
		(layer "In9.Cu")
		(net "M_A_MA13")
	)
	(segment
		(start 101.31933 -46.473364)
		(end 101.664008 -46.473364)
		(width 0.1016)
		(layer "In9.Cu")
		(net "M_A_MA13")
	)
	(segment
		(start 104.2162 -53.56098)
		(end 103.59771 -52.94249)
		(width 0.1905)
		(layer "In9.Cu")
		(net "M_A_MA13")
	)
	(segment
		(start 104.2162 -58.75909)
		(end 104.2162 -53.56098)
		(width 0.1905)
		(layer "In9.Cu")
		(net "M_A_MA13")
	)
	(segment
		(start 121.12117 -59.8805)
		(end 105.33761 -59.8805)
		(width 0.1905)
		(layer "In9.Cu")
		(net "M_A_MA13")
	)
	(arc
		(start 100.18522 -48.772064)
		(mid 100.166736 -48.679139)
		(end 100.1141 -48.60036)
		(width 0.1016)
		(layer "In9.Cu")
		(net "M_A_MA13")
	)
	(arc
		(start 100.3427 -49.80178)
		(mid 100.226133 -49.627325)
		(end 100.18522 -49.421542)
		(width 0.1016)
		(layer "In9.Cu")
		(net "M_A_MA13")
	)
	(segment
		(start 111.068358 -41.415716)
		(end 110.750096 -41.097454)
		(width 0.1016)
		(layer "F.Cu")
		(net "M_A_DQ29")
	)
	(segment
		(start 116.6876 -42.9768)
		(end 114.155474 -42.9768)
		(width 0.1016)
		(layer "F.Cu")
		(net "M_A_DQ29")
	)
	(segment
		(start 114.155474 -42.9768)
		(end 112.59439 -41.415716)
		(width 0.1016)
		(layer "F.Cu")
		(net "M_A_DQ29")
	)
	(segment
		(start 117.1448 -42.5196)
		(end 116.6876 -42.9768)
		(width 0.1016)
		(layer "F.Cu")
		(net "M_A_DQ29")
	)
	(segment
		(start 112.59439 -41.415716)
		(end 111.068358 -41.415716)
		(width 0.1016)
		(layer "F.Cu")
		(net "M_A_DQ29")
	)
	(segment
		(start 110.750096 -41.097454)
		(end 110.749588 -41.097454)
		(width 0.1016)
		(layer "F.Cu")
		(net "M_A_DQ29")
	)
	(segment
		(start 173.350174 -70.806564)
		(end 173.350174 -68.7578)
		(width 0.1778)
		(layer "F.Cu")
		(net "M_A_DQ29")
	)
	(via
		(at 117.1448 -42.5196)
		(size 0.4318)
		(drill 0.2032)
		(layers "F.Cu" "B.Cu")
		(net "M_A_DQ29")
	)
	(via
		(at 173.350174 -68.7578)
		(size 0.4318)
		(drill 0.2032)
		(layers "F.Cu" "B.Cu")
		(net "M_A_DQ29")
	)
	(segment
		(start 173.650148 -69.637148)
		(end 173.350174 -69.337174)
		(width 0.1778)
		(layer "B.Cu")
		(net "M_A_DQ29")
	)
	(segment
		(start 173.650148 -70.79996)
		(end 173.650148 -69.637148)
		(width 0.1778)
		(layer "B.Cu")
		(net "M_A_DQ29")
	)
	(segment
		(start 173.350174 -69.337174)
		(end 173.350174 -68.7578)
		(width 0.1778)
		(layer "B.Cu")
		(net "M_A_DQ29")
	)
	(segment
		(start 166.651178 -47.181516)
		(end 175.87468 -56.405018)
		(width 0.1524)
		(layer "In2.Cu")
		(net "M_A_DQ29")
	)
	(segment
		(start 175.8188 -64.31788)
		(end 176.2506 -64.74968)
		(width 0.1524)
		(layer "In2.Cu")
		(net "M_A_DQ29")
	)
	(segment
		(start 175.87468 -56.405018)
		(end 175.87468 -63.21552)
		(width 0.1524)
		(layer "In2.Cu")
		(net "M_A_DQ29")
	)
	(segment
		(start 175.8188 -63.2714)
		(end 175.8188 -64.31788)
		(width 0.1524)
		(layer "In2.Cu")
		(net "M_A_DQ29")
	)
	(segment
		(start 175.87468 -63.21552)
		(end 175.8188 -63.2714)
		(width 0.1524)
		(layer "In2.Cu")
		(net "M_A_DQ29")
	)
	(segment
		(start 173.431454 -68.7578)
		(end 173.350174 -68.7578)
		(width 0.1524)
		(layer "In2.Cu")
		(net "M_A_DQ29")
	)
	(segment
		(start 176.2506 -64.74968)
		(end 176.2506 -65.938654)
		(width 0.1524)
		(layer "In2.Cu")
		(net "M_A_DQ29")
	)
	(segment
		(start 118.0084 -41.656)
		(end 162.317938 -41.656)
		(width 0.1524)
		(layer "In2.Cu")
		(net "M_A_DQ29")
	)
	(segment
		(start 117.1448 -42.5196)
		(end 118.0084 -41.656)
		(width 0.1524)
		(layer "In2.Cu")
		(net "M_A_DQ29")
	)
	(segment
		(start 162.317938 -41.656)
		(end 166.651178 -45.98924)
		(width 0.1524)
		(layer "In2.Cu")
		(net "M_A_DQ29")
	)
	(segment
		(start 166.651178 -45.98924)
		(end 166.651178 -47.181516)
		(width 0.1524)
		(layer "In2.Cu")
		(net "M_A_DQ29")
	)
	(segment
		(start 176.2506 -65.938654)
		(end 173.431454 -68.7578)
		(width 0.1524)
		(layer "In2.Cu")
		(net "M_A_DQ29")
	)
	(segment
		(start 154.750008 -70.806564)
		(end 154.750008 -70.027292)
		(width 0.2159)
		(layer "F.Cu")
		(net "M_A_CK_DP2")
	)
	(segment
		(start 154.59456 -69.46011)
		(end 154.740864 -69.313806)
		(width 0.2159)
		(layer "F.Cu")
		(net "M_A_CK_DP2")
	)
	(segment
		(start 103.325168 -48.744632)
		(end 103.325168 -48.783494)
		(width 0.1016)
		(layer "F.Cu")
		(net "M_A_CK_DP2")
	)
	(segment
		(start 154.750008 -70.027292)
		(end 154.59456 -69.871844)
		(width 0.2159)
		(layer "F.Cu")
		(net "M_A_CK_DP2")
	)
	(segment
		(start 154.740864 -69.313806)
		(end 154.913584 -69.313806)
		(width 0.2159)
		(layer "F.Cu")
		(net "M_A_CK_DP2")
	)
	(segment
		(start 154.59456 -69.871844)
		(end 154.59456 -69.46011)
		(width 0.2159)
		(layer "F.Cu")
		(net "M_A_CK_DP2")
	)
	(segment
		(start 103.6828 -48.387)
		(end 103.325168 -48.744632)
		(width 0.1016)
		(layer "F.Cu")
		(net "M_A_CK_DP2")
	)
	(via
		(at 154.913584 -69.313806)
		(size 0.4318)
		(drill 0.2032)
		(layers "F.Cu" "B.Cu")
		(net "M_A_CK_DP2")
	)
	(via
		(at 103.6828 -48.387)
		(size 0.4318)
		(drill 0.2032)
		(layers "F.Cu" "B.Cu")
		(net "M_A_CK_DP2")
	)
	(segment
		(start 107.569 -53.779928)
		(end 107.569 -53.8988)
		(width 0.1016)
		(layer "In7.Cu")
		(net "M_A_CK_DP2")
	)
	(segment
		(start 103.5304 -51.562)
		(end 105.181146 -53.212746)
		(width 0.1016)
		(layer "In7.Cu")
		(net "M_A_CK_DP2")
	)
	(segment
		(start 126.080774 -52.615846)
		(end 126.652274 -52.615846)
		(width 0.1905)
		(layer "In7.Cu")
		(net "M_A_CK_DP2")
	)
	(segment
		(start 118.3894 -54.4322)
		(end 120.205754 -52.615846)
		(width 0.1905)
		(layer "In7.Cu")
		(net "M_A_CK_DP2")
	)
	(segment
		(start 154.695906 -69.313806)
		(end 154.913584 -69.313806)
		(width 0.1905)
		(layer "In7.Cu")
		(net "M_A_CK_DP2")
	)
	(segment
		(start 153.68905 -58.015886)
		(end 153.68905 -60.68695)
		(width 0.1905)
		(layer "In7.Cu")
		(net "M_A_CK_DP2")
	)
	(segment
		(start 128.16967 -52.88915)
		(end 128.442974 -52.615846)
		(width 0.1905)
		(layer "In7.Cu")
		(net "M_A_CK_DP2")
	)
	(segment
		(start 107.001818 -53.212746)
		(end 107.569 -53.779928)
		(width 0.1016)
		(layer "In7.Cu")
		(net "M_A_CK_DP2")
	)
	(segment
		(start 144.40281 -53.27015)
		(end 145.88236 -54.7497)
		(width 0.1905)
		(layer "In7.Cu")
		(net "M_A_CK_DP2")
	)
	(segment
		(start 146.612864 -54.7497)
		(end 146.9517 -55.088536)
		(width 0.1905)
		(layer "In7.Cu")
		(net "M_A_CK_DP2")
	)
	(segment
		(start 147.42033 -56.28767)
		(end 148.461222 -56.28767)
		(width 0.1905)
		(layer "In7.Cu")
		(net "M_A_CK_DP2")
	)
	(segment
		(start 133.8961 -53.2003)
		(end 134.254494 -52.841906)
		(width 0.1905)
		(layer "In7.Cu")
		(net "M_A_CK_DP2")
	)
	(segment
		(start 149.122892 -55.626)
		(end 149.840696 -55.626)
		(width 0.1905)
		(layer "In7.Cu")
		(net "M_A_CK_DP2")
	)
	(segment
		(start 151.788114 -57.573418)
		(end 153.246582 -57.573418)
		(width 0.1905)
		(layer "In7.Cu")
		(net "M_A_CK_DP2")
	)
	(segment
		(start 123.718574 -52.615846)
		(end 124.290074 -52.615846)
		(width 0.1905)
		(layer "In7.Cu")
		(net "M_A_CK_DP2")
	)
	(segment
		(start 123.44527 -52.88915)
		(end 123.718574 -52.615846)
		(width 0.1905)
		(layer "In7.Cu")
		(net "M_A_CK_DP2")
	)
	(segment
		(start 141.986 -52.615846)
		(end 142.640304 -53.27015)
		(width 0.1905)
		(layer "In7.Cu")
		(net "M_A_CK_DP2")
	)
	(segment
		(start 103.5304 -49.8094)
		(end 103.5304 -51.562)
		(width 0.1016)
		(layer "In7.Cu")
		(net "M_A_CK_DP2")
	)
	(segment
		(start 122.201178 -52.88915)
		(end 123.44527 -52.88915)
		(width 0.1905)
		(layer "In7.Cu")
		(net "M_A_CK_DP2")
	)
	(segment
		(start 131.650486 -53.27015)
		(end 132.07873 -52.841906)
		(width 0.1905)
		(layer "In7.Cu")
		(net "M_A_CK_DP2")
	)
	(segment
		(start 146.9517 -55.088536)
		(end 146.9517 -55.81904)
		(width 0.1905)
		(layer "In7.Cu")
		(net "M_A_CK_DP2")
	)
	(segment
		(start 130.706114 -53.27015)
		(end 131.650486 -53.27015)
		(width 0.1905)
		(layer "In7.Cu")
		(net "M_A_CK_DP2")
	)
	(segment
		(start 152.33015 -64.76238)
		(end 153.74747 -66.1797)
		(width 0.1905)
		(layer "In7.Cu")
		(net "M_A_CK_DP2")
	)
	(segment
		(start 121.927874 -52.615846)
		(end 122.201178 -52.88915)
		(width 0.1905)
		(layer "In7.Cu")
		(net "M_A_CK_DP2")
	)
	(segment
		(start 146.9517 -55.81904)
		(end 147.42033 -56.28767)
		(width 0.1905)
		(layer "In7.Cu")
		(net "M_A_CK_DP2")
	)
	(segment
		(start 108.1024 -54.4322)
		(end 118.3894 -54.4322)
		(width 0.1905)
		(layer "In7.Cu")
		(net "M_A_CK_DP2")
	)
	(segment
		(start 135.31215 -53.27015)
		(end 137.968482 -53.27015)
		(width 0.1905)
		(layer "In7.Cu")
		(net "M_A_CK_DP2")
	)
	(segment
		(start 124.563378 -52.88915)
		(end 125.80747 -52.88915)
		(width 0.1905)
		(layer "In7.Cu")
		(net "M_A_CK_DP2")
	)
	(segment
		(start 134.254494 -52.841906)
		(end 134.883906 -52.841906)
		(width 0.1905)
		(layer "In7.Cu")
		(net "M_A_CK_DP2")
	)
	(segment
		(start 154.246834 -68.384166)
		(end 154.246834 -68.864734)
		(width 0.1905)
		(layer "In7.Cu")
		(net "M_A_CK_DP2")
	)
	(segment
		(start 153.246582 -57.573418)
		(end 153.68905 -58.015886)
		(width 0.1905)
		(layer "In7.Cu")
		(net "M_A_CK_DP2")
	)
	(segment
		(start 145.88236 -54.7497)
		(end 146.612864 -54.7497)
		(width 0.1905)
		(layer "In7.Cu")
		(net "M_A_CK_DP2")
	)
	(segment
		(start 130.05181 -52.615846)
		(end 130.706114 -53.27015)
		(width 0.1905)
		(layer "In7.Cu")
		(net "M_A_CK_DP2")
	)
	(segment
		(start 107.569 -53.8988)
		(end 108.1024 -54.4322)
		(width 0.1905)
		(layer "In7.Cu")
		(net "M_A_CK_DP2")
	)
	(segment
		(start 132.782564 -52.841906)
		(end 133.140958 -53.2003)
		(width 0.1905)
		(layer "In7.Cu")
		(net "M_A_CK_DP2")
	)
	(segment
		(start 125.80747 -52.88915)
		(end 126.080774 -52.615846)
		(width 0.1905)
		(layer "In7.Cu")
		(net "M_A_CK_DP2")
	)
	(segment
		(start 154.460194 -68.170806)
		(end 154.246834 -68.384166)
		(width 0.1905)
		(layer "In7.Cu")
		(net "M_A_CK_DP2")
	)
	(segment
		(start 134.883906 -52.841906)
		(end 135.31215 -53.27015)
		(width 0.1905)
		(layer "In7.Cu")
		(net "M_A_CK_DP2")
	)
	(segment
		(start 153.68905 -60.68695)
		(end 152.33015 -62.04585)
		(width 0.1905)
		(layer "In7.Cu")
		(net "M_A_CK_DP2")
	)
	(segment
		(start 124.290074 -52.615846)
		(end 124.563378 -52.88915)
		(width 0.1905)
		(layer "In7.Cu")
		(net "M_A_CK_DP2")
	)
	(segment
		(start 142.640304 -53.27015)
		(end 144.40281 -53.27015)
		(width 0.1905)
		(layer "In7.Cu")
		(net "M_A_CK_DP2")
	)
	(segment
		(start 148.461222 -56.28767)
		(end 149.122892 -55.626)
		(width 0.1905)
		(layer "In7.Cu")
		(net "M_A_CK_DP2")
	)
	(segment
		(start 154.460194 -66.38163)
		(end 154.460194 -68.170806)
		(width 0.1905)
		(layer "In7.Cu")
		(net "M_A_CK_DP2")
	)
	(segment
		(start 103.6828 -48.387)
		(end 103.2256 -48.8442)
		(width 0.1016)
		(layer "In7.Cu")
		(net "M_A_CK_DP2")
	)
	(segment
		(start 133.140958 -53.2003)
		(end 133.8961 -53.2003)
		(width 0.1905)
		(layer "In7.Cu")
		(net "M_A_CK_DP2")
	)
	(segment
		(start 152.33015 -62.04585)
		(end 152.33015 -64.76238)
		(width 0.1905)
		(layer "In7.Cu")
		(net "M_A_CK_DP2")
	)
	(segment
		(start 103.2256 -49.5046)
		(end 103.5304 -49.8094)
		(width 0.1016)
		(layer "In7.Cu")
		(net "M_A_CK_DP2")
	)
	(segment
		(start 137.968482 -53.27015)
		(end 138.622786 -52.615846)
		(width 0.1905)
		(layer "In7.Cu")
		(net "M_A_CK_DP2")
	)
	(segment
		(start 153.74747 -66.1797)
		(end 154.258264 -66.1797)
		(width 0.1905)
		(layer "In7.Cu")
		(net "M_A_CK_DP2")
	)
	(segment
		(start 126.925578 -52.88915)
		(end 128.16967 -52.88915)
		(width 0.1905)
		(layer "In7.Cu")
		(net "M_A_CK_DP2")
	)
	(segment
		(start 149.840696 -55.626)
		(end 151.788114 -57.573418)
		(width 0.1905)
		(layer "In7.Cu")
		(net "M_A_CK_DP2")
	)
	(segment
		(start 154.258264 -66.1797)
		(end 154.460194 -66.38163)
		(width 0.1905)
		(layer "In7.Cu")
		(net "M_A_CK_DP2")
	)
	(segment
		(start 128.442974 -52.615846)
		(end 130.05181 -52.615846)
		(width 0.1905)
		(layer "In7.Cu")
		(net "M_A_CK_DP2")
	)
	(segment
		(start 105.181146 -53.212746)
		(end 107.001818 -53.212746)
		(width 0.1016)
		(layer "In7.Cu")
		(net "M_A_CK_DP2")
	)
	(segment
		(start 103.2256 -48.8442)
		(end 103.2256 -49.5046)
		(width 0.1016)
		(layer "In7.Cu")
		(net "M_A_CK_DP2")
	)
	(segment
		(start 120.205754 -52.615846)
		(end 121.927874 -52.615846)
		(width 0.1905)
		(layer "In7.Cu")
		(net "M_A_CK_DP2")
	)
	(segment
		(start 132.07873 -52.841906)
		(end 132.782564 -52.841906)
		(width 0.1905)
		(layer "In7.Cu")
		(net "M_A_CK_DP2")
	)
	(segment
		(start 138.622786 -52.615846)
		(end 141.986 -52.615846)
		(width 0.1905)
		(layer "In7.Cu")
		(net "M_A_CK_DP2")
	)
	(segment
		(start 126.652274 -52.615846)
		(end 126.925578 -52.88915)
		(width 0.1905)
		(layer "In7.Cu")
		(net "M_A_CK_DP2")
	)
	(segment
		(start 154.246834 -68.864734)
		(end 154.695906 -69.313806)
		(width 0.1905)
		(layer "In7.Cu")
		(net "M_A_CK_DP2")
	)
	(segment
		(start 133.450076 -63.298324)
		(end 132.969 -63.7794)
		(width 0.1778)
		(layer "F.Cu")
		(net "M_A_DQ57")
	)
	(segment
		(start 132.969 -64.643)
		(end 132.818632 -64.793368)
		(width 0.1778)
		(layer "F.Cu")
		(net "M_A_DQ57")
	)
	(segment
		(start 96.4565 -54.229)
		(end 96.274636 -54.047136)
		(width 0.1016)
		(layer "F.Cu")
		(net "M_A_DQ57")
	)
	(segment
		(start 132.969 -63.7794)
		(end 132.969 -64.643)
		(width 0.1778)
		(layer "F.Cu")
		(net "M_A_DQ57")
	)
	(segment
		(start 96.109028 -50.411634)
		(end 96.256348 -50.264314)
		(width 0.1016)
		(layer "F.Cu")
		(net "M_A_DQ57")
	)
	(segment
		(start 96.274636 -52.236624)
		(end 96.109028 -52.071016)
		(width 0.1016)
		(layer "F.Cu")
		(net "M_A_DQ57")
	)
	(segment
		(start 96.274636 -54.047136)
		(end 96.274636 -52.236624)
		(width 0.1016)
		(layer "F.Cu")
		(net "M_A_DQ57")
	)
	(segment
		(start 96.109028 -52.071016)
		(end 96.109028 -50.411634)
		(width 0.1016)
		(layer "F.Cu")
		(net "M_A_DQ57")
	)
	(segment
		(start 133.450076 -62.59322)
		(end 133.450076 -63.298324)
		(width 0.1778)
		(layer "F.Cu")
		(net "M_A_DQ57")
	)
	(segment
		(start 132.818632 -64.793368)
		(end 132.818632 -64.799718)
		(width 0.1778)
		(layer "F.Cu")
		(net "M_A_DQ57")
	)
	(via
		(at 132.818632 -64.799718)
		(size 0.4318)
		(drill 0.2032)
		(layers "F.Cu" "B.Cu")
		(net "M_A_DQ57")
	)
	(via
		(at 96.4565 -54.229)
		(size 0.4318)
		(drill 0.2032)
		(layers "F.Cu" "B.Cu")
		(net "M_A_DQ57")
	)
	(segment
		(start 132.969 -64.643)
		(end 132.818632 -64.793368)
		(width 0.1778)
		(layer "B.Cu")
		(net "M_A_DQ57")
	)
	(segment
		(start 132.550154 -62.599824)
		(end 132.550154 -63.462154)
		(width 0.1778)
		(layer "B.Cu")
		(net "M_A_DQ57")
	)
	(segment
		(start 132.550154 -63.462154)
		(end 132.969 -63.881)
		(width 0.1778)
		(layer "B.Cu")
		(net "M_A_DQ57")
	)
	(segment
		(start 132.969 -63.881)
		(end 132.969 -64.643)
		(width 0.1778)
		(layer "B.Cu")
		(net "M_A_DQ57")
	)
	(segment
		(start 132.818632 -64.793368)
		(end 132.818632 -64.799718)
		(width 0.1778)
		(layer "B.Cu")
		(net "M_A_DQ57")
	)
	(segment
		(start 124.4092 -64.4652)
		(end 123.974098 -64.900302)
		(width 0.1524)
		(layer "In7.Cu")
		(net "M_A_DQ57")
	)
	(segment
		(start 113.029238 -65.052702)
		(end 113.029238 -65.278)
		(width 0.1524)
		(layer "In7.Cu")
		(net "M_A_DQ57")
	)
	(segment
		(start 102.042214 -64.8462)
		(end 101.889814 -64.9986)
		(width 0.1524)
		(layer "In7.Cu")
		(net "M_A_DQ57")
	)
	(segment
		(start 101.737414 -65.4304)
		(end 101.432614 -65.4304)
		(width 0.1524)
		(layer "In7.Cu")
		(net "M_A_DQ57")
	)
	(segment
		(start 112.419638 -65.278)
		(end 112.419638 -65.052702)
		(width 0.1524)
		(layer "In7.Cu")
		(net "M_A_DQ57")
	)
	(segment
		(start 110.133638 -65.4304)
		(end 109.981238 -65.278)
		(width 0.1524)
		(layer "In7.Cu")
		(net "M_A_DQ57")
	)
	(segment
		(start 110.590838 -65.052702)
		(end 110.590838 -65.278)
		(width 0.1524)
		(layer "In7.Cu")
		(net "M_A_DQ57")
	)
	(segment
		(start 128.2192 -63.0174)
		(end 126.7714 -64.4652)
		(width 0.1524)
		(layer "In7.Cu")
		(net "M_A_DQ57")
	)
	(segment
		(start 101.432614 -65.4304)
		(end 101.280214 -65.278)
		(width 0.1524)
		(layer "In7.Cu")
		(net "M_A_DQ57")
	)
	(segment
		(start 111.810038 -65.052702)
		(end 111.810038 -65.278)
		(width 0.1524)
		(layer "In7.Cu")
		(net "M_A_DQ57")
	)
	(segment
		(start 104.175814 -65.4304)
		(end 103.871014 -65.4304)
		(width 0.1524)
		(layer "In7.Cu")
		(net "M_A_DQ57")
	)
	(segment
		(start 111.962438 -64.900302)
		(end 111.810038 -65.052702)
		(width 0.1524)
		(layer "In7.Cu")
		(net "M_A_DQ57")
	)
	(segment
		(start 96.012 -58.6486)
		(end 96.012 -54.6735)
		(width 0.1016)
		(layer "In7.Cu")
		(net "M_A_DQ57")
	)
	(segment
		(start 111.810038 -65.278)
		(end 111.657638 -65.4304)
		(width 0.1524)
		(layer "In7.Cu")
		(net "M_A_DQ57")
	)
	(segment
		(start 105.156 -65.2526)
		(end 104.7496 -64.8462)
		(width 0.1524)
		(layer "In7.Cu")
		(net "M_A_DQ57")
	)
	(segment
		(start 111.352838 -65.4304)
		(end 111.200438 -65.278)
		(width 0.1524)
		(layer "In7.Cu")
		(net "M_A_DQ57")
	)
	(segment
		(start 101.889814 -64.9986)
		(end 101.889814 -65.278)
		(width 0.1524)
		(layer "In7.Cu")
		(net "M_A_DQ57")
	)
	(segment
		(start 97.278952 -61.581538)
		(end 97.278952 -59.915552)
		(width 0.1524)
		(layer "In7.Cu")
		(net "M_A_DQ57")
	)
	(segment
		(start 101.127814 -64.8462)
		(end 100.543614 -64.8462)
		(width 0.1524)
		(layer "In7.Cu")
		(net "M_A_DQ57")
	)
	(segment
		(start 105.4608 -65.2526)
		(end 105.156 -65.2526)
		(width 0.1524)
		(layer "In7.Cu")
		(net "M_A_DQ57")
	)
	(segment
		(start 111.200438 -65.278)
		(end 111.200438 -65.052702)
		(width 0.1524)
		(layer "In7.Cu")
		(net "M_A_DQ57")
	)
	(segment
		(start 109.981238 -65.052702)
		(end 109.828838 -64.900302)
		(width 0.1524)
		(layer "In7.Cu")
		(net "M_A_DQ57")
	)
	(segment
		(start 108.914438 -65.4304)
		(end 108.762038 -65.278)
		(width 0.1524)
		(layer "In7.Cu")
		(net "M_A_DQ57")
	)
	(segment
		(start 104.480614 -64.8462)
		(end 104.328214 -64.9986)
		(width 0.1524)
		(layer "In7.Cu")
		(net "M_A_DQ57")
	)
	(segment
		(start 131.92379 -63.0174)
		(end 128.2192 -63.0174)
		(width 0.1524)
		(layer "In7.Cu")
		(net "M_A_DQ57")
	)
	(segment
		(start 102.956614 -65.4304)
		(end 102.651814 -65.4304)
		(width 0.1524)
		(layer "In7.Cu")
		(net "M_A_DQ57")
	)
	(segment
		(start 104.328214 -64.9986)
		(end 104.328214 -65.278)
		(width 0.1524)
		(layer "In7.Cu")
		(net "M_A_DQ57")
	)
	(segment
		(start 112.572038 -65.4304)
		(end 112.419638 -65.278)
		(width 0.1524)
		(layer "In7.Cu")
		(net "M_A_DQ57")
	)
	(segment
		(start 103.566214 -64.8462)
		(end 103.261414 -64.8462)
		(width 0.1524)
		(layer "In7.Cu")
		(net "M_A_DQ57")
	)
	(segment
		(start 102.499414 -65.278)
		(end 102.499414 -64.9986)
		(width 0.1524)
		(layer "In7.Cu")
		(net "M_A_DQ57")
	)
	(segment
		(start 101.280214 -64.9986)
		(end 101.127814 -64.8462)
		(width 0.1524)
		(layer "In7.Cu")
		(net "M_A_DQ57")
	)
	(segment
		(start 104.328214 -65.278)
		(end 104.175814 -65.4304)
		(width 0.1524)
		(layer "In7.Cu")
		(net "M_A_DQ57")
	)
	(segment
		(start 108.609638 -64.900302)
		(end 105.813098 -64.900302)
		(width 0.1524)
		(layer "In7.Cu")
		(net "M_A_DQ57")
	)
	(segment
		(start 101.889814 -65.278)
		(end 101.737414 -65.4304)
		(width 0.1524)
		(layer "In7.Cu")
		(net "M_A_DQ57")
	)
	(segment
		(start 109.371638 -65.052702)
		(end 109.371638 -65.278)
		(width 0.1524)
		(layer "In7.Cu")
		(net "M_A_DQ57")
	)
	(segment
		(start 108.762038 -65.278)
		(end 108.762038 -65.052702)
		(width 0.1524)
		(layer "In7.Cu")
		(net "M_A_DQ57")
	)
	(segment
		(start 112.267238 -64.900302)
		(end 111.962438 -64.900302)
		(width 0.1524)
		(layer "In7.Cu")
		(net "M_A_DQ57")
	)
	(segment
		(start 109.828838 -64.900302)
		(end 109.524038 -64.900302)
		(width 0.1524)
		(layer "In7.Cu")
		(net "M_A_DQ57")
	)
	(segment
		(start 126.7714 -64.4652)
		(end 124.4092 -64.4652)
		(width 0.1524)
		(layer "In7.Cu")
		(net "M_A_DQ57")
	)
	(segment
		(start 102.347014 -64.8462)
		(end 102.042214 -64.8462)
		(width 0.1524)
		(layer "In7.Cu")
		(net "M_A_DQ57")
	)
	(segment
		(start 123.974098 -64.900302)
		(end 113.181638 -64.900302)
		(width 0.1524)
		(layer "In7.Cu")
		(net "M_A_DQ57")
	)
	(segment
		(start 108.762038 -65.052702)
		(end 108.609638 -64.900302)
		(width 0.1524)
		(layer "In7.Cu")
		(net "M_A_DQ57")
	)
	(segment
		(start 97.278952 -59.915552)
		(end 96.012 -58.6486)
		(width 0.1016)
		(layer "In7.Cu")
		(net "M_A_DQ57")
	)
	(segment
		(start 101.280214 -65.278)
		(end 101.280214 -64.9986)
		(width 0.1524)
		(layer "In7.Cu")
		(net "M_A_DQ57")
	)
	(segment
		(start 103.109014 -65.278)
		(end 102.956614 -65.4304)
		(width 0.1524)
		(layer "In7.Cu")
		(net "M_A_DQ57")
	)
	(segment
		(start 112.419638 -65.052702)
		(end 112.267238 -64.900302)
		(width 0.1524)
		(layer "In7.Cu")
		(net "M_A_DQ57")
	)
	(segment
		(start 111.200438 -65.052702)
		(end 111.048038 -64.900302)
		(width 0.1524)
		(layer "In7.Cu")
		(net "M_A_DQ57")
	)
	(segment
		(start 96.012 -54.6735)
		(end 96.4565 -54.229)
		(width 0.1016)
		(layer "In7.Cu")
		(net "M_A_DQ57")
	)
	(segment
		(start 132.9563 -64.66205)
		(end 132.9563 -64.04991)
		(width 0.1524)
		(layer "In7.Cu")
		(net "M_A_DQ57")
	)
	(segment
		(start 103.261414 -64.8462)
		(end 103.109014 -64.9986)
		(width 0.1524)
		(layer "In7.Cu")
		(net "M_A_DQ57")
	)
	(segment
		(start 112.876838 -65.4304)
		(end 112.572038 -65.4304)
		(width 0.1524)
		(layer "In7.Cu")
		(net "M_A_DQ57")
	)
	(segment
		(start 110.743238 -64.900302)
		(end 110.590838 -65.052702)
		(width 0.1524)
		(layer "In7.Cu")
		(net "M_A_DQ57")
	)
	(segment
		(start 103.718614 -65.278)
		(end 103.718614 -64.9986)
		(width 0.1524)
		(layer "In7.Cu")
		(net "M_A_DQ57")
	)
	(segment
		(start 109.371638 -65.278)
		(end 109.219238 -65.4304)
		(width 0.1524)
		(layer "In7.Cu")
		(net "M_A_DQ57")
	)
	(segment
		(start 104.7496 -64.8462)
		(end 104.480614 -64.8462)
		(width 0.1524)
		(layer "In7.Cu")
		(net "M_A_DQ57")
	)
	(segment
		(start 109.219238 -65.4304)
		(end 108.914438 -65.4304)
		(width 0.1524)
		(layer "In7.Cu")
		(net "M_A_DQ57")
	)
	(segment
		(start 111.048038 -64.900302)
		(end 110.743238 -64.900302)
		(width 0.1524)
		(layer "In7.Cu")
		(net "M_A_DQ57")
	)
	(segment
		(start 132.9563 -64.04991)
		(end 131.92379 -63.0174)
		(width 0.1524)
		(layer "In7.Cu")
		(net "M_A_DQ57")
	)
	(segment
		(start 111.657638 -65.4304)
		(end 111.352838 -65.4304)
		(width 0.1524)
		(layer "In7.Cu")
		(net "M_A_DQ57")
	)
	(segment
		(start 100.543614 -64.8462)
		(end 97.278952 -61.581538)
		(width 0.1524)
		(layer "In7.Cu")
		(net "M_A_DQ57")
	)
	(segment
		(start 132.818632 -64.799718)
		(end 132.9563 -64.66205)
		(width 0.1524)
		(layer "In7.Cu")
		(net "M_A_DQ57")
	)
	(segment
		(start 103.718614 -64.9986)
		(end 103.566214 -64.8462)
		(width 0.1524)
		(layer "In7.Cu")
		(net "M_A_DQ57")
	)
	(segment
		(start 102.499414 -64.9986)
		(end 102.347014 -64.8462)
		(width 0.1524)
		(layer "In7.Cu")
		(net "M_A_DQ57")
	)
	(segment
		(start 105.813098 -64.900302)
		(end 105.4608 -65.2526)
		(width 0.1524)
		(layer "In7.Cu")
		(net "M_A_DQ57")
	)
	(segment
		(start 109.981238 -65.278)
		(end 109.981238 -65.052702)
		(width 0.1524)
		(layer "In7.Cu")
		(net "M_A_DQ57")
	)
	(segment
		(start 110.590838 -65.278)
		(end 110.438438 -65.4304)
		(width 0.1524)
		(layer "In7.Cu")
		(net "M_A_DQ57")
	)
	(segment
		(start 103.109014 -64.9986)
		(end 103.109014 -65.278)
		(width 0.1524)
		(layer "In7.Cu")
		(net "M_A_DQ57")
	)
	(segment
		(start 102.651814 -65.4304)
		(end 102.499414 -65.278)
		(width 0.1524)
		(layer "In7.Cu")
		(net "M_A_DQ57")
	)
	(segment
		(start 103.871014 -65.4304)
		(end 103.718614 -65.278)
		(width 0.1524)
		(layer "In7.Cu")
		(net "M_A_DQ57")
	)
	(segment
		(start 113.029238 -65.278)
		(end 112.876838 -65.4304)
		(width 0.1524)
		(layer "In7.Cu")
		(net "M_A_DQ57")
	)
	(segment
		(start 109.524038 -64.900302)
		(end 109.371638 -65.052702)
		(width 0.1524)
		(layer "In7.Cu")
		(net "M_A_DQ57")
	)
	(segment
		(start 113.181638 -64.900302)
		(end 113.029238 -65.052702)
		(width 0.1524)
		(layer "In7.Cu")
		(net "M_A_DQ57")
	)
	(segment
		(start 110.438438 -65.4304)
		(end 110.133638 -65.4304)
		(width 0.1524)
		(layer "In7.Cu")
		(net "M_A_DQ57")
	)
	(segment
		(start 105.550208 -30.032706)
		(end 105.893616 -30.376114)
		(width 0.1397)
		(layer "F.Cu")
		(net "CLK_100M_CPU_MPLL1_DP")
	)
	(segment
		(start 105.550208 -29.997654)
		(end 105.550208 -30.032706)
		(width 0.1397)
		(layer "F.Cu")
		(net "CLK_100M_CPU_MPLL1_DP")
	)
	(via
		(at 105.893616 -30.376114)
		(size 0.4318)
		(drill 0.2032)
		(layers "F.Cu" "B.Cu")
		(net "CLK_100M_CPU_MPLL1_DP")
	)
	(via
		(at 51.282346 -34.0868)
		(size 0.508)
		(drill 0.254)
		(layers "F.Cu" "B.Cu")
		(net "CLK_100M_CPU_MPLL1_DP")
	)
	(segment
		(start 49.379886 -49.497234)
		(end 48.668178 -49.497234)
		(width 0.1397)
		(layer "B.Cu")
		(net "CLK_100M_CPU_MPLL1_DP")
	)
	(segment
		(start 51.282346 -34.0868)
		(end 51.6128 -34.417254)
		(width 0.1397)
		(layer "B.Cu")
		(net "CLK_100M_CPU_MPLL1_DP")
	)
	(segment
		(start 51.7017 -41.3893)
		(end 51.7017 -45.819568)
		(width 0.1397)
		(layer "B.Cu")
		(net "CLK_100M_CPU_MPLL1_DP")
	)
	(segment
		(start 51.2572 -35.8648)
		(end 51.2572 -40.9448)
		(width 0.1397)
		(layer "B.Cu")
		(net "CLK_100M_CPU_MPLL1_DP")
	)
	(segment
		(start 49.408334 -49.525682)
		(end 49.379886 -49.497234)
		(width 0.1397)
		(layer "B.Cu")
		(net "CLK_100M_CPU_MPLL1_DP")
	)
	(segment
		(start 51.2572 -40.9448)
		(end 51.7017 -41.3893)
		(width 0.1397)
		(layer "B.Cu")
		(net "CLK_100M_CPU_MPLL1_DP")
	)
	(segment
		(start 51.7017 -45.819568)
		(end 53.3146 -47.432468)
		(width 0.1397)
		(layer "B.Cu")
		(net "CLK_100M_CPU_MPLL1_DP")
	)
	(segment
		(start 53.3146 -48.049942)
		(end 52.7431 -48.621442)
		(width 0.1397)
		(layer "B.Cu")
		(net "CLK_100M_CPU_MPLL1_DP")
	)
	(segment
		(start 49.728882 -49.525682)
		(end 49.408334 -49.525682)
		(width 0.1397)
		(layer "B.Cu")
		(net "CLK_100M_CPU_MPLL1_DP")
	)
	(segment
		(start 51.6128 -34.417254)
		(end 51.6128 -35.5092)
		(width 0.1397)
		(layer "B.Cu")
		(net "CLK_100M_CPU_MPLL1_DP")
	)
	(segment
		(start 52.7431 -48.621442)
		(end 52.7431 -49.4665)
		(width 0.1397)
		(layer "B.Cu")
		(net "CLK_100M_CPU_MPLL1_DP")
	)
	(segment
		(start 52.7431 -49.4665)
		(end 51.8287 -50.3809)
		(width 0.1397)
		(layer "B.Cu")
		(net "CLK_100M_CPU_MPLL1_DP")
	)
	(segment
		(start 51.8287 -50.3809)
		(end 50.5841 -50.3809)
		(width 0.1397)
		(layer "B.Cu")
		(net "CLK_100M_CPU_MPLL1_DP")
	)
	(segment
		(start 53.3146 -47.432468)
		(end 53.3146 -48.049942)
		(width 0.1397)
		(layer "B.Cu")
		(net "CLK_100M_CPU_MPLL1_DP")
	)
	(segment
		(start 50.5841 -50.3809)
		(end 49.728882 -49.525682)
		(width 0.1397)
		(layer "B.Cu")
		(net "CLK_100M_CPU_MPLL1_DP")
	)
	(segment
		(start 51.6128 -35.5092)
		(end 51.2572 -35.8648)
		(width 0.1397)
		(layer "B.Cu")
		(net "CLK_100M_CPU_MPLL1_DP")
	)
	(segment
		(start 86.159594 -25.019)
		(end 86.921594 -24.257)
		(width 0.1143)
		(layer "In4.Cu")
		(net "CLK_100M_CPU_MPLL1_DP")
	)
	(segment
		(start 84.6328 -24.843994)
		(end 84.807806 -25.019)
		(width 0.1143)
		(layer "In4.Cu")
		(net "CLK_100M_CPU_MPLL1_DP")
	)
	(segment
		(start 96.4184 -33.3629)
		(end 96.4819 -33.4264)
		(width 0.1016)
		(layer "In4.Cu")
		(net "CLK_100M_CPU_MPLL1_DP")
	)
	(segment
		(start 90.661998 -25.736296)
		(end 92.822268 -25.736296)
		(width 0.1143)
		(layer "In4.Cu")
		(net "CLK_100M_CPU_MPLL1_DP")
	)
	(segment
		(start 105.6132 -30.65653)
		(end 105.893616 -30.376114)
		(width 0.1016)
		(layer "In4.Cu")
		(net "CLK_100M_CPU_MPLL1_DP")
	)
	(segment
		(start 104.193848 -32.599376)
		(end 104.193848 -31.027624)
		(width 0.1016)
		(layer "In4.Cu")
		(net "CLK_100M_CPU_MPLL1_DP")
	)
	(segment
		(start 64.68618 -23.55215)
		(end 67.399916 -23.55215)
		(width 0.1143)
		(layer "In4.Cu")
		(net "CLK_100M_CPU_MPLL1_DP")
	)
	(segment
		(start 104.3178 -30.903672)
		(end 104.3178 -30.738318)
		(width 0.1016)
		(layer "In4.Cu")
		(net "CLK_100M_CPU_MPLL1_DP")
	)
	(segment
		(start 78.012544 -25.43175)
		(end 79.257144 -24.18715)
		(width 0.1143)
		(layer "In4.Cu")
		(net "CLK_100M_CPU_MPLL1_DP")
	)
	(segment
		(start 51.5366 -33.2232)
		(end 56.190134 -28.569666)
		(width 0.1143)
		(layer "In4.Cu")
		(net "CLK_100M_CPU_MPLL1_DP")
	)
	(segment
		(start 61.635894 -24.638)
		(end 63.60033 -24.638)
		(width 0.1143)
		(layer "In4.Cu")
		(net "CLK_100M_CPU_MPLL1_DP")
	)
	(segment
		(start 105.455212 -30.65653)
		(end 105.6132 -30.65653)
		(width 0.1016)
		(layer "In4.Cu")
		(net "CLK_100M_CPU_MPLL1_DP")
	)
	(segment
		(start 92.822268 -25.736296)
		(end 95.401384 -28.315412)
		(width 0.1143)
		(layer "In4.Cu")
		(net "CLK_100M_CPU_MPLL1_DP")
	)
	(segment
		(start 82.794094 -23.9522)
		(end 83.747102 -23.9522)
		(width 0.1143)
		(layer "In4.Cu")
		(net "CLK_100M_CPU_MPLL1_DP")
	)
	(segment
		(start 51.5366 -33.832546)
		(end 51.5366 -33.2232)
		(width 0.1143)
		(layer "In4.Cu")
		(net "CLK_100M_CPU_MPLL1_DP")
	)
	(segment
		(start 63.60033 -24.638)
		(end 64.68618 -23.55215)
		(width 0.1143)
		(layer "In4.Cu")
		(net "CLK_100M_CPU_MPLL1_DP")
	)
	(segment
		(start 74.024744 -25.7429)
		(end 74.335894 -25.43175)
		(width 0.1143)
		(layer "In4.Cu")
		(net "CLK_100M_CPU_MPLL1_DP")
	)
	(segment
		(start 71.270622 -25.7429)
		(end 74.024744 -25.7429)
		(width 0.1143)
		(layer "In4.Cu")
		(net "CLK_100M_CPU_MPLL1_DP")
	)
	(segment
		(start 95.401384 -32.536384)
		(end 96.2279 -33.3629)
		(width 0.1143)
		(layer "In4.Cu")
		(net "CLK_100M_CPU_MPLL1_DP")
	)
	(segment
		(start 89.182702 -24.257)
		(end 90.661998 -25.736296)
		(width 0.1143)
		(layer "In4.Cu")
		(net "CLK_100M_CPU_MPLL1_DP")
	)
	(segment
		(start 74.335894 -25.43175)
		(end 78.012544 -25.43175)
		(width 0.1143)
		(layer "In4.Cu")
		(net "CLK_100M_CPU_MPLL1_DP")
	)
	(segment
		(start 83.893152 -24.09825)
		(end 84.051902 -24.09825)
		(width 0.1143)
		(layer "In4.Cu")
		(net "CLK_100M_CPU_MPLL1_DP")
	)
	(segment
		(start 102.64648 -33.66008)
		(end 103.7844 -33.66008)
		(width 0.1016)
		(layer "In4.Cu")
		(net "CLK_100M_CPU_MPLL1_DP")
	)
	(segment
		(start 67.399916 -23.55215)
		(end 68.200016 -24.35225)
		(width 0.1143)
		(layer "In4.Cu")
		(net "CLK_100M_CPU_MPLL1_DP")
	)
	(segment
		(start 69.879972 -24.35225)
		(end 71.270622 -25.7429)
		(width 0.1143)
		(layer "In4.Cu")
		(net "CLK_100M_CPU_MPLL1_DP")
	)
	(segment
		(start 60.40755 -27.14625)
		(end 60.40755 -25.866344)
		(width 0.1143)
		(layer "In4.Cu")
		(net "CLK_100M_CPU_MPLL1_DP")
	)
	(segment
		(start 103.7844 -33.66008)
		(end 104.25176 -33.19272)
		(width 0.1016)
		(layer "In4.Cu")
		(net "CLK_100M_CPU_MPLL1_DP")
	)
	(segment
		(start 102.4128 -33.4264)
		(end 102.64648 -33.66008)
		(width 0.1016)
		(layer "In4.Cu")
		(net "CLK_100M_CPU_MPLL1_DP")
	)
	(segment
		(start 86.921594 -24.257)
		(end 89.182702 -24.257)
		(width 0.1143)
		(layer "In4.Cu")
		(net "CLK_100M_CPU_MPLL1_DP")
	)
	(segment
		(start 82.559144 -24.18715)
		(end 82.794094 -23.9522)
		(width 0.1143)
		(layer "In4.Cu")
		(net "CLK_100M_CPU_MPLL1_DP")
	)
	(segment
		(start 105.164382 -30.3657)
		(end 105.455212 -30.65653)
		(width 0.1016)
		(layer "In4.Cu")
		(net "CLK_100M_CPU_MPLL1_DP")
	)
	(segment
		(start 83.747102 -23.9522)
		(end 83.893152 -24.09825)
		(width 0.1143)
		(layer "In4.Cu")
		(net "CLK_100M_CPU_MPLL1_DP")
	)
	(segment
		(start 56.190134 -28.569666)
		(end 58.984134 -28.569666)
		(width 0.1143)
		(layer "In4.Cu")
		(net "CLK_100M_CPU_MPLL1_DP")
	)
	(segment
		(start 104.3178 -30.738318)
		(end 104.690418 -30.3657)
		(width 0.1016)
		(layer "In4.Cu")
		(net "CLK_100M_CPU_MPLL1_DP")
	)
	(segment
		(start 96.2279 -33.3629)
		(end 96.4184 -33.3629)
		(width 0.1143)
		(layer "In4.Cu")
		(net "CLK_100M_CPU_MPLL1_DP")
	)
	(segment
		(start 79.257144 -24.18715)
		(end 82.559144 -24.18715)
		(width 0.1143)
		(layer "In4.Cu")
		(net "CLK_100M_CPU_MPLL1_DP")
	)
	(segment
		(start 104.25176 -33.19272)
		(end 104.25176 -32.657288)
		(width 0.1016)
		(layer "In4.Cu")
		(net "CLK_100M_CPU_MPLL1_DP")
	)
	(segment
		(start 96.4819 -33.4264)
		(end 102.4128 -33.4264)
		(width 0.1016)
		(layer "In4.Cu")
		(net "CLK_100M_CPU_MPLL1_DP")
	)
	(segment
		(start 84.051902 -24.09825)
		(end 84.6328 -24.679148)
		(width 0.1143)
		(layer "In4.Cu")
		(net "CLK_100M_CPU_MPLL1_DP")
	)
	(segment
		(start 58.984134 -28.569666)
		(end 60.40755 -27.14625)
		(width 0.1143)
		(layer "In4.Cu")
		(net "CLK_100M_CPU_MPLL1_DP")
	)
	(segment
		(start 95.401384 -28.315412)
		(end 95.401384 -32.536384)
		(width 0.1143)
		(layer "In4.Cu")
		(net "CLK_100M_CPU_MPLL1_DP")
	)
	(segment
		(start 104.690418 -30.3657)
		(end 105.164382 -30.3657)
		(width 0.1016)
		(layer "In4.Cu")
		(net "CLK_100M_CPU_MPLL1_DP")
	)
	(segment
		(start 51.282346 -34.0868)
		(end 51.5366 -33.832546)
		(width 0.1143)
		(layer "In4.Cu")
		(net "CLK_100M_CPU_MPLL1_DP")
	)
	(segment
		(start 84.6328 -24.679148)
		(end 84.6328 -24.843994)
		(width 0.1143)
		(layer "In4.Cu")
		(net "CLK_100M_CPU_MPLL1_DP")
	)
	(segment
		(start 60.40755 -25.866344)
		(end 61.635894 -24.638)
		(width 0.1143)
		(layer "In4.Cu")
		(net "CLK_100M_CPU_MPLL1_DP")
	)
	(segment
		(start 84.807806 -25.019)
		(end 86.159594 -25.019)
		(width 0.1143)
		(layer "In4.Cu")
		(net "CLK_100M_CPU_MPLL1_DP")
	)
	(segment
		(start 104.193848 -31.027624)
		(end 104.3178 -30.903672)
		(width 0.1016)
		(layer "In4.Cu")
		(net "CLK_100M_CPU_MPLL1_DP")
	)
	(segment
		(start 68.200016 -24.35225)
		(end 69.879972 -24.35225)
		(width 0.1143)
		(layer "In4.Cu")
		(net "CLK_100M_CPU_MPLL1_DP")
	)
	(segment
		(start 104.25176 -32.657288)
		(end 104.193848 -32.599376)
		(width 0.1016)
		(layer "In4.Cu")
		(net "CLK_100M_CPU_MPLL1_DP")
	)
	(segment
		(start 7.15645 -49.642522)
		(end 7.15645 -50.76825)
		(width 0.1143)
		(layer "F.Cu")
		(net "TEMP_1_A1")
	)
	(segment
		(start 7.15645 -50.76825)
		(end 7.2136 -50.8254)
		(width 0.1143)
		(layer "F.Cu")
		(net "TEMP_1_A1")
	)
	(segment
		(start 7.2136 -51.7652)
		(end 7.2136 -50.8254)
		(width 0.1143)
		(layer "F.Cu")
		(net "TEMP_1_A1")
	)
	(segment
		(start 7.165086 -48.471328)
		(end 7.165086 -49.633886)
		(width 0.1143)
		(layer "F.Cu")
		(net "TEMP_1_A1")
	)
	(segment
		(start 7.2136 -52.5526)
		(end 7.2136 -51.7652)
		(width 0.1143)
		(layer "F.Cu")
		(net "TEMP_1_A1")
	)
	(segment
		(start 7.165086 -49.633886)
		(end 7.15645 -49.642522)
		(width 0.1143)
		(layer "F.Cu")
		(net "TEMP_1_A1")
	)
	(via
		(at 7.2136 -50.8254)
		(size 0.7112)
		(drill 0.3556)
		(layers "F.Cu" "B.Cu")
		(net "TEMP_1_A1")
	)
	(segment
		(start 106.0704 -56.0705)
		(end 106.0704 -54.4068)
		(width 0.1016)
		(layer "F.Cu")
		(net "M_A_DQ45")
	)
	(segment
		(start 142.150084 -69.939916)
		(end 142.5702 -69.5198)
		(width 0.1778)
		(layer "F.Cu")
		(net "M_A_DQ45")
	)
	(segment
		(start 106.0704 -54.4068)
		(end 104.752648 -53.089048)
		(width 0.1016)
		(layer "F.Cu")
		(net "M_A_DQ45")
	)
	(segment
		(start 142.5702 -69.5198)
		(end 142.5702 -68.834)
		(width 0.1778)
		(layer "F.Cu")
		(net "M_A_DQ45")
	)
	(segment
		(start 106.5657 -56.5658)
		(end 106.0704 -56.0705)
		(width 0.1016)
		(layer "F.Cu")
		(net "M_A_DQ45")
	)
	(segment
		(start 142.150084 -70.806564)
		(end 142.150084 -69.939916)
		(width 0.1778)
		(layer "F.Cu")
		(net "M_A_DQ45")
	)
	(segment
		(start 104.752648 -53.089048)
		(end 104.752648 -52.448714)
		(width 0.1016)
		(layer "F.Cu")
		(net "M_A_DQ45")
	)
	(segment
		(start 142.5702 -68.834)
		(end 142.3924 -68.6562)
		(width 0.1778)
		(layer "F.Cu")
		(net "M_A_DQ45")
	)
	(via
		(at 106.5657 -56.5658)
		(size 0.4318)
		(drill 0.2032)
		(layers "F.Cu" "B.Cu")
		(net "M_A_DQ45")
	)
	(via
		(at 142.3924 -68.6562)
		(size 0.4318)
		(drill 0.2032)
		(layers "F.Cu" "B.Cu")
		(net "M_A_DQ45")
	)
	(segment
		(start 142.579598 -69.390006)
		(end 142.579598 -68.843398)
		(width 0.1778)
		(layer "B.Cu")
		(net "M_A_DQ45")
	)
	(segment
		(start 143.050006 -69.860414)
		(end 142.579598 -69.390006)
		(width 0.1778)
		(layer "B.Cu")
		(net "M_A_DQ45")
	)
	(segment
		(start 142.579598 -68.843398)
		(end 142.3924 -68.6562)
		(width 0.1778)
		(layer "B.Cu")
		(net "M_A_DQ45")
	)
	(segment
		(start 143.050006 -70.79996)
		(end 143.050006 -69.860414)
		(width 0.1778)
		(layer "B.Cu")
		(net "M_A_DQ45")
	)
	(segment
		(start 124.12218 -55.118)
		(end 124.12218 -54.7624)
		(width 0.1524)
		(layer "In2.Cu")
		(net "M_A_DQ45")
	)
	(segment
		(start 119.1514 -55.0164)
		(end 120.3198 -55.0164)
		(width 0.1524)
		(layer "In2.Cu")
		(net "M_A_DQ45")
	)
	(segment
		(start 124.73178 -55.118)
		(end 124.88418 -55.2704)
		(width 0.1524)
		(layer "In2.Cu")
		(net "M_A_DQ45")
	)
	(segment
		(start 117.878098 -56.289702)
		(end 119.1514 -55.0164)
		(width 0.1524)
		(layer "In2.Cu")
		(net "M_A_DQ45")
	)
	(segment
		(start 125.49378 -54.61)
		(end 125.79858 -54.61)
		(width 0.1524)
		(layer "In2.Cu")
		(net "M_A_DQ45")
	)
	(segment
		(start 125.79858 -54.61)
		(end 125.95098 -54.7624)
		(width 0.1524)
		(layer "In2.Cu")
		(net "M_A_DQ45")
	)
	(segment
		(start 124.57938 -54.61)
		(end 124.73178 -54.7624)
		(width 0.1524)
		(layer "In2.Cu")
		(net "M_A_DQ45")
	)
	(segment
		(start 122.90298 -54.7624)
		(end 123.05538 -54.61)
		(width 0.1524)
		(layer "In2.Cu")
		(net "M_A_DQ45")
	)
	(segment
		(start 125.34138 -54.7624)
		(end 125.49378 -54.61)
		(width 0.1524)
		(layer "In2.Cu")
		(net "M_A_DQ45")
	)
	(segment
		(start 123.66498 -55.2704)
		(end 123.96978 -55.2704)
		(width 0.1524)
		(layer "In2.Cu")
		(net "M_A_DQ45")
	)
	(segment
		(start 126.10338 -55.2704)
		(end 139.294362 -55.2704)
		(width 0.1524)
		(layer "In2.Cu")
		(net "M_A_DQ45")
	)
	(segment
		(start 124.88418 -55.2704)
		(end 125.18898 -55.2704)
		(width 0.1524)
		(layer "In2.Cu")
		(net "M_A_DQ45")
	)
	(segment
		(start 123.96978 -55.2704)
		(end 124.12218 -55.118)
		(width 0.1524)
		(layer "In2.Cu")
		(net "M_A_DQ45")
	)
	(segment
		(start 107.061 -56.5658)
		(end 107.337098 -56.289702)
		(width 0.1524)
		(layer "In2.Cu")
		(net "M_A_DQ45")
	)
	(segment
		(start 123.05538 -54.61)
		(end 123.36018 -54.61)
		(width 0.1524)
		(layer "In2.Cu")
		(net "M_A_DQ45")
	)
	(segment
		(start 142.5702 -68.4784)
		(end 142.3924 -68.6562)
		(width 0.1524)
		(layer "In2.Cu")
		(net "M_A_DQ45")
	)
	(segment
		(start 144.8054 -60.781438)
		(end 144.8054 -65.4304)
		(width 0.1524)
		(layer "In2.Cu")
		(net "M_A_DQ45")
	)
	(segment
		(start 125.95098 -54.7624)
		(end 125.95098 -55.118)
		(width 0.1524)
		(layer "In2.Cu")
		(net "M_A_DQ45")
	)
	(segment
		(start 123.51258 -55.118)
		(end 123.66498 -55.2704)
		(width 0.1524)
		(layer "In2.Cu")
		(net "M_A_DQ45")
	)
	(segment
		(start 106.5657 -56.5658)
		(end 107.061 -56.5658)
		(width 0.1524)
		(layer "In2.Cu")
		(net "M_A_DQ45")
	)
	(segment
		(start 125.18898 -55.2704)
		(end 125.34138 -55.118)
		(width 0.1524)
		(layer "In2.Cu")
		(net "M_A_DQ45")
	)
	(segment
		(start 122.75058 -55.2704)
		(end 122.90298 -55.118)
		(width 0.1524)
		(layer "In2.Cu")
		(net "M_A_DQ45")
	)
	(segment
		(start 123.51258 -54.7624)
		(end 123.51258 -55.118)
		(width 0.1524)
		(layer "In2.Cu")
		(net "M_A_DQ45")
	)
	(segment
		(start 124.73178 -54.7624)
		(end 124.73178 -55.118)
		(width 0.1524)
		(layer "In2.Cu")
		(net "M_A_DQ45")
	)
	(segment
		(start 139.294362 -55.2704)
		(end 144.8054 -60.781438)
		(width 0.1524)
		(layer "In2.Cu")
		(net "M_A_DQ45")
	)
	(segment
		(start 122.90298 -55.118)
		(end 122.90298 -54.7624)
		(width 0.1524)
		(layer "In2.Cu")
		(net "M_A_DQ45")
	)
	(segment
		(start 124.12218 -54.7624)
		(end 124.27458 -54.61)
		(width 0.1524)
		(layer "In2.Cu")
		(net "M_A_DQ45")
	)
	(segment
		(start 142.5702 -67.6656)
		(end 142.5702 -68.4784)
		(width 0.1524)
		(layer "In2.Cu")
		(net "M_A_DQ45")
	)
	(segment
		(start 120.5738 -55.2704)
		(end 122.75058 -55.2704)
		(width 0.1524)
		(layer "In2.Cu")
		(net "M_A_DQ45")
	)
	(segment
		(start 144.8054 -65.4304)
		(end 142.5702 -67.6656)
		(width 0.1524)
		(layer "In2.Cu")
		(net "M_A_DQ45")
	)
	(segment
		(start 120.3198 -55.0164)
		(end 120.5738 -55.2704)
		(width 0.1524)
		(layer "In2.Cu")
		(net "M_A_DQ45")
	)
	(segment
		(start 123.36018 -54.61)
		(end 123.51258 -54.7624)
		(width 0.1524)
		(layer "In2.Cu")
		(net "M_A_DQ45")
	)
	(segment
		(start 124.27458 -54.61)
		(end 124.57938 -54.61)
		(width 0.1524)
		(layer "In2.Cu")
		(net "M_A_DQ45")
	)
	(segment
		(start 125.34138 -55.118)
		(end 125.34138 -54.7624)
		(width 0.1524)
		(layer "In2.Cu")
		(net "M_A_DQ45")
	)
	(segment
		(start 107.337098 -56.289702)
		(end 117.878098 -56.289702)
		(width 0.1524)
		(layer "In2.Cu")
		(net "M_A_DQ45")
	)
	(segment
		(start 125.95098 -55.118)
		(end 126.10338 -55.2704)
		(width 0.1524)
		(layer "In2.Cu")
		(net "M_A_DQ45")
	)
	(via
		(at 96.6216 -38.7858)
		(size 0.4318)
		(drill 0.2032)
		(layers "F.Cu" "B.Cu")
		(net "P1V1")
	)
	(via
		(at 94.742 -60.6806)
		(size 0.508)
		(drill 0.254)
		(layers "F.Cu" "B.Cu")
		(net "P1V1")
	)
	(via
		(at 100.584 -69.619368)
		(size 0.7112)
		(drill 0.3556)
		(layers "F.Cu" "B.Cu")
		(net "P1V1")
	)
	(via
		(at 94.742 -61.5442)
		(size 0.508)
		(drill 0.254)
		(layers "F.Cu" "B.Cu")
		(net "P1V1")
	)
	(via
		(at 97.42805 -37.999162)
		(size 0.4318)
		(drill 0.2032)
		(layers "F.Cu" "B.Cu")
		(net "P1V1")
	)
	(via
		(at 96.652588 -37.989256)
		(size 0.4318)
		(drill 0.2032)
		(layers "F.Cu" "B.Cu")
		(net "P1V1")
	)
	(via
		(at 92.8878 -61.0362)
		(size 0.7112)
		(drill 0.3556)
		(layers "F.Cu" "B.Cu")
		(net "P1V1")
	)
	(via
		(at 97.421192 -37.228272)
		(size 0.4318)
		(drill 0.2032)
		(layers "F.Cu" "B.Cu")
		(net "P1V1")
	)
	(via
		(at 96.621092 -37.228272)
		(size 0.4318)
		(drill 0.2032)
		(layers "F.Cu" "B.Cu")
		(net "P1V1")
	)
	(via
		(at 94.742 -59.944)
		(size 0.508)
		(drill 0.254)
		(layers "F.Cu" "B.Cu")
		(net "P1V1")
	)
	(via
		(at 99.822 -69.85)
		(size 0.508)
		(drill 0.254)
		(layers "F.Cu" "B.Cu")
		(net "P1V1")
	)
	(segment
		(start 100.584 -69.619368)
		(end 101.092 -69.111368)
		(width 0.3048)
		(layer "B.Cu")
		(net "P1V1")
	)
	(segment
		(start 100.353368 -69.85)
		(end 99.822 -69.85)
		(width 0.3048)
		(layer "B.Cu")
		(net "P1V1")
	)
	(segment
		(start 100.584 -69.619368)
		(end 100.353368 -69.85)
		(width 0.3048)
		(layer "B.Cu")
		(net "P1V1")
	)
	(segment
		(start 101.092 -69.111368)
		(end 101.092 -68.7578)
		(width 0.3048)
		(layer "B.Cu")
		(net "P1V1")
	)
	(segment
		(start 98.552 -68.58)
		(end 98.552 -64.3128)
		(width 0.3048)
		(layer "In4.Cu")
		(net "P1V1")
	)
	(segment
		(start 98.552 -64.3128)
		(end 96.3676 -62.1284)
		(width 0.3048)
		(layer "In4.Cu")
		(net "P1V1")
	)
	(segment
		(start 99.822 -69.85)
		(end 98.552 -68.58)
		(width 0.3048)
		(layer "In4.Cu")
		(net "P1V1")
	)
	(segment
		(start 96.3676 -62.1284)
		(end 95.3262 -62.1284)
		(width 0.3048)
		(layer "In4.Cu")
		(net "P1V1")
	)
	(segment
		(start 95.3262 -62.1284)
		(end 94.742 -61.5442)
		(width 0.3048)
		(layer "In4.Cu")
		(net "P1V1")
	)
	(segment
		(start 107.671108 -43.642534)
		(end 107.73029 -43.642534)
		(width 0.1016)
		(layer "F.Cu")
		(net "M_A_DQ10")
	)
	(segment
		(start 180.467 -63.65875)
		(end 180.467 -64.559688)
		(width 0.1778)
		(layer "F.Cu")
		(net "M_A_DQ10")
	)
	(segment
		(start 180.250084 -63.441834)
		(end 180.467 -63.65875)
		(width 0.1778)
		(layer "F.Cu")
		(net "M_A_DQ10")
	)
	(segment
		(start 107.73029 -43.642534)
		(end 108.058458 -43.970702)
		(width 0.1016)
		(layer "F.Cu")
		(net "M_A_DQ10")
	)
	(segment
		(start 180.467 -64.559688)
		(end 180.6956 -64.788288)
		(width 0.1778)
		(layer "F.Cu")
		(net "M_A_DQ10")
	)
	(segment
		(start 180.250084 -62.59322)
		(end 180.250084 -63.441834)
		(width 0.1778)
		(layer "F.Cu")
		(net "M_A_DQ10")
	)
	(via
		(at 180.6956 -64.788288)
		(size 0.4318)
		(drill 0.2032)
		(layers "F.Cu" "B.Cu")
		(net "M_A_DQ10")
	)
	(via
		(at 108.058458 -43.970702)
		(size 0.4318)
		(drill 0.2032)
		(layers "F.Cu" "B.Cu")
		(net "M_A_DQ10")
	)
	(segment
		(start 181.150006 -62.599824)
		(end 181.150006 -63.346584)
		(width 0.1778)
		(layer "B.Cu")
		(net "M_A_DQ10")
	)
	(segment
		(start 181.150006 -63.346584)
		(end 180.5051 -63.99149)
		(width 0.1778)
		(layer "B.Cu")
		(net "M_A_DQ10")
	)
	(segment
		(start 180.5051 -63.99149)
		(end 180.5051 -64.597788)
		(width 0.1778)
		(layer "B.Cu")
		(net "M_A_DQ10")
	)
	(segment
		(start 180.5051 -64.597788)
		(end 180.6956 -64.788288)
		(width 0.1778)
		(layer "B.Cu")
		(net "M_A_DQ10")
	)
	(segment
		(start 157.294072 -49.8729)
		(end 157.0101 -49.8729)
		(width 0.1524)
		(layer "In4.Cu")
		(net "M_A_DQ10")
	)
	(segment
		(start 172.790104 -56.6166)
		(end 172.790104 -55.885842)
		(width 0.1524)
		(layer "In4.Cu")
		(net "M_A_DQ10")
	)
	(segment
		(start 173.856904 -55.733442)
		(end 173.552104 -55.733442)
		(width 0.1524)
		(layer "In4.Cu")
		(net "M_A_DQ10")
	)
	(segment
		(start 155.9814 -49.5173)
		(end 155.9814 -48.8188)
		(width 0.1524)
		(layer "In4.Cu")
		(net "M_A_DQ10")
	)
	(segment
		(start 157.0101 -49.8729)
		(end 156.8069 -49.6697)
		(width 0.1524)
		(layer "In4.Cu")
		(net "M_A_DQ10")
	)
	(segment
		(start 154.454606 -48.714406)
		(end 154.239214 -48.714406)
		(width 0.1524)
		(layer "In4.Cu")
		(net "M_A_DQ10")
	)
	(segment
		(start 174.009304 -55.885842)
		(end 173.856904 -55.733442)
		(width 0.1524)
		(layer "In4.Cu")
		(net "M_A_DQ10")
	)
	(segment
		(start 158.056072 -50.0253)
		(end 158.056072 -50.2158)
		(width 0.1524)
		(layer "In4.Cu")
		(net "M_A_DQ10")
	)
	(segment
		(start 153.327354 -48.979074)
		(end 153.327354 -48.763682)
		(width 0.1524)
		(layer "In4.Cu")
		(net "M_A_DQ10")
	)
	(segment
		(start 172.180504 -55.885842)
		(end 172.180504 -56.6166)
		(width 0.1524)
		(layer "In4.Cu")
		(net "M_A_DQ10")
	)
	(segment
		(start 153.807922 -48.067722)
		(end 153.592022 -47.851822)
		(width 0.1524)
		(layer "In4.Cu")
		(net "M_A_DQ10")
	)
	(segment
		(start 121.1072 -45.1866)
		(end 120.5865 -45.7073)
		(width 0.1524)
		(layer "In4.Cu")
		(net "M_A_DQ10")
	)
	(segment
		(start 158.056072 -50.2158)
		(end 157.903672 -50.3682)
		(width 0.1524)
		(layer "In4.Cu")
		(net "M_A_DQ10")
	)
	(segment
		(start 173.247304 -56.769)
		(end 172.942504 -56.769)
		(width 0.1524)
		(layer "In4.Cu")
		(net "M_A_DQ10")
	)
	(segment
		(start 180.6956 -64.788288)
		(end 180.6956 -64.7446)
		(width 0.1524)
		(layer "In4.Cu")
		(net "M_A_DQ10")
	)
	(segment
		(start 152.100788 -47.27575)
		(end 151.19985 -46.374812)
		(width 0.1524)
		(layer "In4.Cu")
		(net "M_A_DQ10")
	)
	(segment
		(start 111.55172 -44.50588)
		(end 110.777782 -44.50588)
		(width 0.1016)
		(layer "In4.Cu")
		(net "M_A_DQ10")
	)
	(segment
		(start 174.161704 -56.769)
		(end 174.009304 -56.6166)
		(width 0.1524)
		(layer "In4.Cu")
		(net "M_A_DQ10")
	)
	(segment
		(start 114.3254 -45.1866)
		(end 113.3348 -45.1866)
		(width 0.1524)
		(layer "In4.Cu")
		(net "M_A_DQ10")
	)
	(segment
		(start 164.364162 -49.8729)
		(end 158.208472 -49.8729)
		(width 0.1524)
		(layer "In4.Cu")
		(net "M_A_DQ10")
	)
	(segment
		(start 180.44922 -63.758064)
		(end 180.715412 -63.491872)
		(width 0.1524)
		(layer "In4.Cu")
		(net "M_A_DQ10")
	)
	(segment
		(start 114.5794 -44.9326)
		(end 114.3254 -45.1866)
		(width 0.1524)
		(layer "In4.Cu")
		(net "M_A_DQ10")
	)
	(segment
		(start 155.2194 -50.5714)
		(end 154.91968 -50.5714)
		(width 0.1524)
		(layer "In4.Cu")
		(net "M_A_DQ10")
	)
	(segment
		(start 157.598872 -50.3682)
		(end 157.446472 -50.2158)
		(width 0.1524)
		(layer "In4.Cu")
		(net "M_A_DQ10")
	)
	(segment
		(start 155.5242 -48.6664)
		(end 155.3718 -48.8188)
		(width 0.1524)
		(layer "In4.Cu")
		(net "M_A_DQ10")
	)
	(segment
		(start 171.723304 -56.769)
		(end 171.570904 -56.6166)
		(width 0.1524)
		(layer "In4.Cu")
		(net "M_A_DQ10")
	)
	(segment
		(start 109.506512 -44.54398)
		(end 108.47324 -44.54398)
		(width 0.1016)
		(layer "In4.Cu")
		(net "M_A_DQ10")
	)
	(segment
		(start 158.208472 -49.8729)
		(end 158.056072 -50.0253)
		(width 0.1524)
		(layer "In4.Cu")
		(net "M_A_DQ10")
	)
	(segment
		(start 174.009304 -56.6166)
		(end 174.009304 -55.885842)
		(width 0.1524)
		(layer "In4.Cu")
		(net "M_A_DQ10")
	)
	(segment
		(start 108.47324 -44.54398)
		(end 108.058458 -44.129198)
		(width 0.1016)
		(layer "In4.Cu")
		(net "M_A_DQ10")
	)
	(segment
		(start 110.777782 -44.50588)
		(end 110.650528 -44.378626)
		(width 0.1016)
		(layer "In4.Cu")
		(net "M_A_DQ10")
	)
	(segment
		(start 150.0378 -45.5168)
		(end 149.733 -45.8216)
		(width 0.1524)
		(layer "In4.Cu")
		(net "M_A_DQ10")
	)
	(segment
		(start 153.543254 -49.194974)
		(end 153.327354 -48.979074)
		(width 0.1524)
		(layer "In4.Cu")
		(net "M_A_DQ10")
	)
	(segment
		(start 171.570904 -56.6166)
		(end 171.570904 -55.885842)
		(width 0.1524)
		(layer "In4.Cu")
		(net "M_A_DQ10")
	)
	(segment
		(start 149.733 -45.8216)
		(end 149.4282 -45.8216)
		(width 0.1524)
		(layer "In4.Cu")
		(net "M_A_DQ10")
	)
	(segment
		(start 170.224704 -55.733442)
		(end 164.364162 -49.8729)
		(width 0.1524)
		(layer "In4.Cu")
		(net "M_A_DQ10")
	)
	(segment
		(start 156.8069 -49.6697)
		(end 156.1338 -49.6697)
		(width 0.1524)
		(layer "In4.Cu")
		(net "M_A_DQ10")
	)
	(segment
		(start 152.68067 -48.33239)
		(end 152.100788 -47.752508)
		(width 0.1524)
		(layer "In4.Cu")
		(net "M_A_DQ10")
	)
	(segment
		(start 171.570904 -55.885842)
		(end 171.418504 -55.733442)
		(width 0.1524)
		(layer "In4.Cu")
		(net "M_A_DQ10")
	)
	(segment
		(start 171.418504 -55.733442)
		(end 170.224704 -55.733442)
		(width 0.1524)
		(layer "In4.Cu")
		(net "M_A_DQ10")
	)
	(segment
		(start 154.91968 -50.5714)
		(end 154.189938 -49.841658)
		(width 0.1524)
		(layer "In4.Cu")
		(net "M_A_DQ10")
	)
	(segment
		(start 172.637704 -55.733442)
		(end 172.332904 -55.733442)
		(width 0.1524)
		(layer "In4.Cu")
		(net "M_A_DQ10")
	)
	(segment
		(start 178.3334 -58.711338)
		(end 175.355504 -55.733442)
		(width 0.1524)
		(layer "In4.Cu")
		(net "M_A_DQ10")
	)
	(segment
		(start 154.189938 -49.626266)
		(end 154.670506 -49.145698)
		(width 0.1524)
		(layer "In4.Cu")
		(net "M_A_DQ10")
	)
	(segment
		(start 121.68759 -45.1866)
		(end 121.1072 -45.1866)
		(width 0.1524)
		(layer "In4.Cu")
		(net "M_A_DQ10")
	)
	(segment
		(start 173.399704 -55.885842)
		(end 173.399704 -56.6166)
		(width 0.1524)
		(layer "In4.Cu")
		(net "M_A_DQ10")
	)
	(segment
		(start 112.42802 -44.27982)
		(end 111.77778 -44.27982)
		(width 0.1016)
		(layer "In4.Cu")
		(net "M_A_DQ10")
	)
	(segment
		(start 180.715412 -63.491872)
		(end 180.715412 -62.453012)
		(width 0.1524)
		(layer "In4.Cu")
		(net "M_A_DQ10")
	)
	(segment
		(start 111.77778 -44.27982)
		(end 111.55172 -44.50588)
		(width 0.1016)
		(layer "In4.Cu")
		(net "M_A_DQ10")
	)
	(segment
		(start 157.903672 -50.3682)
		(end 157.598872 -50.3682)
		(width 0.1524)
		(layer "In4.Cu")
		(net "M_A_DQ10")
	)
	(segment
		(start 156.1338 -49.6697)
		(end 155.9814 -49.5173)
		(width 0.1524)
		(layer "In4.Cu")
		(net "M_A_DQ10")
	)
	(segment
		(start 180.6956 -64.7446)
		(end 180.44922 -64.49822)
		(width 0.1524)
		(layer "In4.Cu")
		(net "M_A_DQ10")
	)
	(segment
		(start 108.058458 -44.129198)
		(end 108.058458 -43.970702)
		(width 0.1016)
		(layer "In4.Cu")
		(net "M_A_DQ10")
	)
	(segment
		(start 151.19985 -46.374812)
		(end 151.19985 -46.362366)
		(width 0.1524)
		(layer "In4.Cu")
		(net "M_A_DQ10")
	)
	(segment
		(start 174.618904 -55.885842)
		(end 174.618904 -56.6166)
		(width 0.1524)
		(layer "In4.Cu")
		(net "M_A_DQ10")
	)
	(segment
		(start 110.650528 -44.378626)
		(end 109.671866 -44.378626)
		(width 0.1016)
		(layer "In4.Cu")
		(net "M_A_DQ10")
	)
	(segment
		(start 118.1735 -45.7073)
		(end 117.3988 -44.9326)
		(width 0.1524)
		(layer "In4.Cu")
		(net "M_A_DQ10")
	)
	(segment
		(start 155.3718 -48.8188)
		(end 155.3718 -50.419)
		(width 0.1524)
		(layer "In4.Cu")
		(net "M_A_DQ10")
	)
	(segment
		(start 155.9814 -48.8188)
		(end 155.829 -48.6664)
		(width 0.1524)
		(layer "In4.Cu")
		(net "M_A_DQ10")
	)
	(segment
		(start 154.239214 -48.714406)
		(end 153.758646 -49.194974)
		(width 0.1524)
		(layer "In4.Cu")
		(net "M_A_DQ10")
	)
	(segment
		(start 153.327354 -48.763682)
		(end 153.807922 -48.283114)
		(width 0.1524)
		(layer "In4.Cu")
		(net "M_A_DQ10")
	)
	(segment
		(start 157.446472 -50.0253)
		(end 157.294072 -49.8729)
		(width 0.1524)
		(layer "In4.Cu")
		(net "M_A_DQ10")
	)
	(segment
		(start 172.180504 -56.6166)
		(end 172.028104 -56.769)
		(width 0.1524)
		(layer "In4.Cu")
		(net "M_A_DQ10")
	)
	(segment
		(start 152.896062 -48.33239)
		(end 152.68067 -48.33239)
		(width 0.1524)
		(layer "In4.Cu")
		(net "M_A_DQ10")
	)
	(segment
		(start 178.3334 -60.071)
		(end 178.3334 -58.711338)
		(width 0.1524)
		(layer "In4.Cu")
		(net "M_A_DQ10")
	)
	(segment
		(start 157.446472 -50.2158)
		(end 157.446472 -50.0253)
		(width 0.1524)
		(layer "In4.Cu")
		(net "M_A_DQ10")
	)
	(segment
		(start 154.189938 -49.841658)
		(end 154.189938 -49.626266)
		(width 0.1524)
		(layer "In4.Cu")
		(net "M_A_DQ10")
	)
	(segment
		(start 173.399704 -56.6166)
		(end 173.247304 -56.769)
		(width 0.1524)
		(layer "In4.Cu")
		(net "M_A_DQ10")
	)
	(segment
		(start 174.771304 -55.733442)
		(end 174.618904 -55.885842)
		(width 0.1524)
		(layer "In4.Cu")
		(net "M_A_DQ10")
	)
	(segment
		(start 149.4282 -45.8216)
		(end 149.1234 -45.5168)
		(width 0.1524)
		(layer "In4.Cu")
		(net "M_A_DQ10")
	)
	(segment
		(start 154.670506 -49.145698)
		(end 154.670506 -48.930306)
		(width 0.1524)
		(layer "In4.Cu")
		(net "M_A_DQ10")
	)
	(segment
		(start 175.355504 -55.733442)
		(end 174.771304 -55.733442)
		(width 0.1524)
		(layer "In4.Cu")
		(net "M_A_DQ10")
	)
	(segment
		(start 174.618904 -56.6166)
		(end 174.466504 -56.769)
		(width 0.1524)
		(layer "In4.Cu")
		(net "M_A_DQ10")
	)
	(segment
		(start 153.592022 -47.851822)
		(end 153.37663 -47.851822)
		(width 0.1524)
		(layer "In4.Cu")
		(net "M_A_DQ10")
	)
	(segment
		(start 173.552104 -55.733442)
		(end 173.399704 -55.885842)
		(width 0.1524)
		(layer "In4.Cu")
		(net "M_A_DQ10")
	)
	(segment
		(start 180.44922 -64.49822)
		(end 180.44922 -63.758064)
		(width 0.1524)
		(layer "In4.Cu")
		(net "M_A_DQ10")
	)
	(segment
		(start 180.715412 -62.453012)
		(end 178.3334 -60.071)
		(width 0.1524)
		(layer "In4.Cu")
		(net "M_A_DQ10")
	)
	(segment
		(start 172.332904 -55.733442)
		(end 172.180504 -55.885842)
		(width 0.1524)
		(layer "In4.Cu")
		(net "M_A_DQ10")
	)
	(segment
		(start 109.671866 -44.378626)
		(end 109.506512 -44.54398)
		(width 0.1016)
		(layer "In4.Cu")
		(net "M_A_DQ10")
	)
	(segment
		(start 174.466504 -56.769)
		(end 174.161704 -56.769)
		(width 0.1524)
		(layer "In4.Cu")
		(net "M_A_DQ10")
	)
	(segment
		(start 154.670506 -48.930306)
		(end 154.454606 -48.714406)
		(width 0.1524)
		(layer "In4.Cu")
		(net "M_A_DQ10")
	)
	(segment
		(start 117.3988 -44.9326)
		(end 114.5794 -44.9326)
		(width 0.1524)
		(layer "In4.Cu")
		(net "M_A_DQ10")
	)
	(segment
		(start 149.1234 -45.5168)
		(end 122.01779 -45.5168)
		(width 0.1524)
		(layer "In4.Cu")
		(net "M_A_DQ10")
	)
	(segment
		(start 155.829 -48.6664)
		(end 155.5242 -48.6664)
		(width 0.1524)
		(layer "In4.Cu")
		(net "M_A_DQ10")
	)
	(segment
		(start 120.5865 -45.7073)
		(end 118.1735 -45.7073)
		(width 0.1524)
		(layer "In4.Cu")
		(net "M_A_DQ10")
	)
	(segment
		(start 113.3348 -45.1866)
		(end 112.42802 -44.27982)
		(width 0.1016)
		(layer "In4.Cu")
		(net "M_A_DQ10")
	)
	(segment
		(start 155.3718 -50.419)
		(end 155.2194 -50.5714)
		(width 0.1524)
		(layer "In4.Cu")
		(net "M_A_DQ10")
	)
	(segment
		(start 172.942504 -56.769)
		(end 172.790104 -56.6166)
		(width 0.1524)
		(layer "In4.Cu")
		(net "M_A_DQ10")
	)
	(segment
		(start 153.807922 -48.283114)
		(end 153.807922 -48.067722)
		(width 0.1524)
		(layer "In4.Cu")
		(net "M_A_DQ10")
	)
	(segment
		(start 151.19985 -46.362366)
		(end 150.354284 -45.5168)
		(width 0.1524)
		(layer "In4.Cu")
		(net "M_A_DQ10")
	)
	(segment
		(start 122.01779 -45.5168)
		(end 121.68759 -45.1866)
		(width 0.1524)
		(layer "In4.Cu")
		(net "M_A_DQ10")
	)
	(segment
		(start 153.37663 -47.851822)
		(end 152.896062 -48.33239)
		(width 0.1524)
		(layer "In4.Cu")
		(net "M_A_DQ10")
	)
	(segment
		(start 153.758646 -49.194974)
		(end 153.543254 -49.194974)
		(width 0.1524)
		(layer "In4.Cu")
		(net "M_A_DQ10")
	)
	(segment
		(start 150.354284 -45.5168)
		(end 150.0378 -45.5168)
		(width 0.1524)
		(layer "In4.Cu")
		(net "M_A_DQ10")
	)
	(segment
		(start 152.100788 -47.752508)
		(end 152.100788 -47.27575)
		(width 0.1524)
		(layer "In4.Cu")
		(net "M_A_DQ10")
	)
	(segment
		(start 172.790104 -55.885842)
		(end 172.637704 -55.733442)
		(width 0.1524)
		(layer "In4.Cu")
		(net "M_A_DQ10")
	)
	(segment
		(start 172.028104 -56.769)
		(end 171.723304 -56.769)
		(width 0.1524)
		(layer "In4.Cu")
		(net "M_A_DQ10")
	)
	(segment
		(start 93.002862 -47.595028)
		(end 92.657168 -47.940722)
		(width 0.1143)
		(layer "F.Cu")
		(net "PCIE_OBS_P")
	)
	(segment
		(start 93.393768 -46.878494)
		(end 93.002862 -47.2694)
		(width 0.1143)
		(layer "F.Cu")
		(net "PCIE_OBS_P")
	)
	(segment
		(start 93.002862 -47.2694)
		(end 93.002862 -47.595028)
		(width 0.1143)
		(layer "F.Cu")
		(net "PCIE_OBS_P")
	)
	(via
		(at 92.657168 -47.940722)
		(size 0.4318)
		(drill 0.2032)
		(layers "F.Cu" "B.Cu")
		(net "PCIE_OBS_P")
	)
	(via
		(at 92.3544 -49.784)
		(size 0.7112)
		(drill 0.3556)
		(layers "F.Cu" "B.Cu")
		(net "PCIE_OBS_P")
	)
	(segment
		(start 92.658184 -51.603402)
		(end 92.658184 -50.689002)
		(width 0.1143)
		(layer "B.Cu")
		(net "PCIE_OBS_P")
	)
	(segment
		(start 92.658184 -50.087784)
		(end 92.3544 -49.784)
		(width 0.1143)
		(layer "B.Cu")
		(net "PCIE_OBS_P")
	)
	(segment
		(start 92.658184 -50.689002)
		(end 92.658184 -50.087784)
		(width 0.1143)
		(layer "B.Cu")
		(net "PCIE_OBS_P")
	)
	(segment
		(start 92.505784 -51.755802)
		(end 92.658184 -51.603402)
		(width 0.1143)
		(layer "B.Cu")
		(net "PCIE_OBS_P")
	)
	(segment
		(start 92.30868 -49.73828)
		(end 92.3544 -49.784)
		(width 0.1143)
		(layer "B.Cu")
		(net "PCIE_OBS_P")
	)
	(segment
		(start 92.657168 -47.940722)
		(end 92.30868 -48.28921)
		(width 0.1143)
		(layer "B.Cu")
		(net "PCIE_OBS_P")
	)
	(segment
		(start 92.30868 -48.28921)
		(end 92.30868 -49.73828)
		(width 0.1143)
		(layer "B.Cu")
		(net "PCIE_OBS_P")
	)
	(via
		(at 41.459404 -48.292004)
		(size 0.7112)
		(drill 0.3556)
		(layers "F.Cu" "B.Cu")
		(net "CLK_14M_CPU_R")
	)
	(segment
		(start 43.04919 -47.897288)
		(end 41.840912 -47.897288)
		(width 0.1143)
		(layer "B.Cu")
		(net "CLK_14M_CPU_R")
	)
	(segment
		(start 41.4782 -48.273208)
		(end 41.459404 -48.292004)
		(width 0.1143)
		(layer "B.Cu")
		(net "CLK_14M_CPU_R")
	)
	(segment
		(start 39.896796 -48.292004)
		(end 41.459404 -48.292004)
		(width 0.1143)
		(layer "B.Cu")
		(net "CLK_14M_CPU_R")
	)
	(segment
		(start 41.840912 -47.897288)
		(end 41.4782 -48.26)
		(width 0.1143)
		(layer "B.Cu")
		(net "CLK_14M_CPU_R")
	)
	(segment
		(start 41.4782 -48.26)
		(end 41.4782 -48.273208)
		(width 0.1143)
		(layer "B.Cu")
		(net "CLK_14M_CPU_R")
	)
	(segment
		(start 39.4208 -48.768)
		(end 39.896796 -48.292004)
		(width 0.1143)
		(layer "B.Cu")
		(net "CLK_14M_CPU_R")
	)
	(segment
		(start 96.84512 -48.6537)
		(end 96.85528 -48.6537)
		(width 0.1524)
		(layer "F.Cu")
		(net "M_A_DQ34")
	)
	(segment
		(start 96.85528 -48.6537)
		(end 97.106486 -48.402494)
		(width 0.1524)
		(layer "F.Cu")
		(net "M_A_DQ34")
	)
	(segment
		(start 145.450052 -63.282068)
		(end 144.8943 -63.83782)
		(width 0.1778)
		(layer "F.Cu")
		(net "M_A_DQ34")
	)
	(segment
		(start 97.106486 -48.402494)
		(end 97.366328 -48.402494)
		(width 0.1524)
		(layer "F.Cu")
		(net "M_A_DQ34")
	)
	(segment
		(start 145.450052 -62.59322)
		(end 145.450052 -63.282068)
		(width 0.1778)
		(layer "F.Cu")
		(net "M_A_DQ34")
	)
	(segment
		(start 144.8943 -64.330072)
		(end 145.254218 -64.68999)
		(width 0.1778)
		(layer "F.Cu")
		(net "M_A_DQ34")
	)
	(segment
		(start 144.8943 -63.83782)
		(end 144.8943 -64.330072)
		(width 0.1778)
		(layer "F.Cu")
		(net "M_A_DQ34")
	)
	(via
		(at 96.84512 -48.6537)
		(size 0.4318)
		(drill 0.2032)
		(layers "F.Cu" "B.Cu")
		(net "M_A_DQ34")
	)
	(via
		(at 145.254218 -64.68999)
		(size 0.4318)
		(drill 0.2032)
		(layers "F.Cu" "B.Cu")
		(net "M_A_DQ34")
	)
	(segment
		(start 144.8054 -63.922656)
		(end 144.8054 -64.241172)
		(width 0.1778)
		(layer "B.Cu")
		(net "M_A_DQ34")
	)
	(segment
		(start 144.8054 -64.241172)
		(end 145.254218 -64.68999)
		(width 0.1778)
		(layer "B.Cu")
		(net "M_A_DQ34")
	)
	(segment
		(start 144.55013 -62.599824)
		(end 144.55013 -63.667386)
		(width 0.1778)
		(layer "B.Cu")
		(net "M_A_DQ34")
	)
	(segment
		(start 144.55013 -63.667386)
		(end 144.8054 -63.922656)
		(width 0.1778)
		(layer "B.Cu")
		(net "M_A_DQ34")
	)
	(segment
		(start 144.1196 -61.1124)
		(end 143.9672 -61.2648)
		(width 0.1524)
		(layer "In4.Cu")
		(net "M_A_DQ34")
	)
	(segment
		(start 100.203 -52.4256)
		(end 99.4918 -52.4256)
		(width 0.1524)
		(layer "In4.Cu")
		(net "M_A_DQ34")
	)
	(segment
		(start 143.0528 -61.0108)
		(end 142.3924 -61.0108)
		(width 0.1524)
		(layer "In4.Cu")
		(net "M_A_DQ34")
	)
	(segment
		(start 135.3566 -57.7596)
		(end 135.3566 -57.4294)
		(width 0.1524)
		(layer "In4.Cu")
		(net "M_A_DQ34")
	)
	(segment
		(start 98.817938 -50.8)
		(end 98.817938 -50.203608)
		(width 0.1016)
		(layer "In4.Cu")
		(net "M_A_DQ34")
	)
	(segment
		(start 143.2052 -63.3476)
		(end 143.2052 -61.1632)
		(width 0.1524)
		(layer "In4.Cu")
		(net "M_A_DQ34")
	)
	(segment
		(start 99.4918 -52.4256)
		(end 99.3394 -52.2732)
		(width 0.1524)
		(layer "In4.Cu")
		(net "M_A_DQ34")
	)
	(segment
		(start 139.254484 -58.992516)
		(end 139.051284 -58.789316)
		(width 0.1524)
		(layer "In4.Cu")
		(net "M_A_DQ34")
	)
	(segment
		(start 134.747 -57.277)
		(end 134.112 -57.912)
		(width 0.1524)
		(layer "In4.Cu")
		(net "M_A_DQ34")
	)
	(segment
		(start 144.596104 -61.1124)
		(end 144.1196 -61.1124)
		(width 0.1524)
		(layer "In4.Cu")
		(net "M_A_DQ34")
	)
	(segment
		(start 143.3576 -63.5)
		(end 143.2052 -63.3476)
		(width 0.1524)
		(layer "In4.Cu")
		(net "M_A_DQ34")
	)
	(segment
		(start 140.9319 -61.90869)
		(end 140.9319 -61.2775)
		(width 0.1524)
		(layer "In4.Cu")
		(net "M_A_DQ34")
	)
	(segment
		(start 106.1085 -57.2897)
		(end 106.1085 -54.5592)
		(width 0.1524)
		(layer "In4.Cu")
		(net "M_A_DQ34")
	)
	(segment
		(start 143.2052 -61.1632)
		(end 143.0528 -61.0108)
		(width 0.1524)
		(layer "In4.Cu")
		(net "M_A_DQ34")
	)
	(segment
		(start 144.8943 -63.7667)
		(end 145.1102 -63.5508)
		(width 0.1524)
		(layer "In4.Cu")
		(net "M_A_DQ34")
	)
	(segment
		(start 106.2736 -57.4548)
		(end 106.1085 -57.2897)
		(width 0.1524)
		(layer "In4.Cu")
		(net "M_A_DQ34")
	)
	(segment
		(start 142.0876 -62.0776)
		(end 141.10081 -62.0776)
		(width 0.1524)
		(layer "In4.Cu")
		(net "M_A_DQ34")
	)
	(segment
		(start 105.7656 -54.2163)
		(end 105.2195 -54.2163)
		(width 0.1524)
		(layer "In4.Cu")
		(net "M_A_DQ34")
	)
	(segment
		(start 137.1092 -57.4294)
		(end 136.9568 -57.277)
		(width 0.1524)
		(layer "In4.Cu")
		(net "M_A_DQ34")
	)
	(segment
		(start 140.16355 -60.45835)
		(end 139.254484 -59.549284)
		(width 0.1524)
		(layer "In4.Cu")
		(net "M_A_DQ34")
	)
	(segment
		(start 141.0208 -59.944)
		(end 140.50645 -60.45835)
		(width 0.1524)
		(layer "In4.Cu")
		(net "M_A_DQ34")
	)
	(segment
		(start 101.654356 -51.9684)
		(end 100.5078 -51.9684)
		(width 0.1524)
		(layer "In4.Cu")
		(net "M_A_DQ34")
	)
	(segment
		(start 137.795 -58.0898)
		(end 137.2616 -58.0898)
		(width 0.1524)
		(layer "In4.Cu")
		(net "M_A_DQ34")
	)
	(segment
		(start 96.8502 -48.65878)
		(end 96.84512 -48.6537)
		(width 0.1016)
		(layer "In4.Cu")
		(net "M_A_DQ34")
	)
	(segment
		(start 137.1092 -57.9374)
		(end 137.1092 -57.4294)
		(width 0.1524)
		(layer "In4.Cu")
		(net "M_A_DQ34")
	)
	(segment
		(start 104.1908 -53.1876)
		(end 103.884222 -52.881022)
		(width 0.1524)
		(layer "In4.Cu")
		(net "M_A_DQ34")
	)
	(segment
		(start 104.521 -53.8734)
		(end 104.1908 -53.5432)
		(width 0.1524)
		(layer "In4.Cu")
		(net "M_A_DQ34")
	)
	(segment
		(start 135.2042 -57.277)
		(end 134.747 -57.277)
		(width 0.1524)
		(layer "In4.Cu")
		(net "M_A_DQ34")
	)
	(segment
		(start 100.3554 -52.1208)
		(end 100.3554 -52.2732)
		(width 0.1524)
		(layer "In4.Cu")
		(net "M_A_DQ34")
	)
	(segment
		(start 145.1102 -63.2968)
		(end 144.7419 -62.9285)
		(width 0.1524)
		(layer "In4.Cu")
		(net "M_A_DQ34")
	)
	(segment
		(start 141.6304 -60.579)
		(end 141.6304 -60.198)
		(width 0.1524)
		(layer "In4.Cu")
		(net "M_A_DQ34")
	)
	(segment
		(start 144.8943 -64.330072)
		(end 144.8943 -63.7667)
		(width 0.1524)
		(layer "In4.Cu")
		(net "M_A_DQ34")
	)
	(segment
		(start 135.3566 -57.4294)
		(end 135.2042 -57.277)
		(width 0.1524)
		(layer "In4.Cu")
		(net "M_A_DQ34")
	)
	(segment
		(start 142.24 -61.9252)
		(end 142.0876 -62.0776)
		(width 0.1524)
		(layer "In4.Cu")
		(net "M_A_DQ34")
	)
	(segment
		(start 100.5078 -51.9684)
		(end 100.3554 -52.1208)
		(width 0.1524)
		(layer "In4.Cu")
		(net "M_A_DQ34")
	)
	(segment
		(start 143.9672 -61.2648)
		(end 143.9672 -63.3476)
		(width 0.1524)
		(layer "In4.Cu")
		(net "M_A_DQ34")
	)
	(segment
		(start 98.817938 -50.203608)
		(end 97.76333 -49.149)
		(width 0.1016)
		(layer "In4.Cu")
		(net "M_A_DQ34")
	)
	(segment
		(start 97.546414 -49.149)
		(end 97.056194 -48.65878)
		(width 0.1016)
		(layer "In4.Cu")
		(net "M_A_DQ34")
	)
	(segment
		(start 100.3554 -52.2732)
		(end 100.203 -52.4256)
		(width 0.1524)
		(layer "In4.Cu")
		(net "M_A_DQ34")
	)
	(segment
		(start 139.254484 -59.549284)
		(end 139.254484 -58.992516)
		(width 0.1524)
		(layer "In4.Cu")
		(net "M_A_DQ34")
	)
	(segment
		(start 143.9672 -63.3476)
		(end 143.8148 -63.5)
		(width 0.1524)
		(layer "In4.Cu")
		(net "M_A_DQ34")
	)
	(segment
		(start 138.494516 -58.789316)
		(end 137.795 -58.0898)
		(width 0.1524)
		(layer "In4.Cu")
		(net "M_A_DQ34")
	)
	(segment
		(start 102.566978 -52.881022)
		(end 101.654356 -51.9684)
		(width 0.1524)
		(layer "In4.Cu")
		(net "M_A_DQ34")
	)
	(segment
		(start 106.8324 -57.277)
		(end 106.6546 -57.4548)
		(width 0.1524)
		(layer "In4.Cu")
		(net "M_A_DQ34")
	)
	(segment
		(start 145.254218 -64.68999)
		(end 144.8943 -64.330072)
		(width 0.1524)
		(layer "In4.Cu")
		(net "M_A_DQ34")
	)
	(segment
		(start 134.112 -57.912)
		(end 133.4008 -57.912)
		(width 0.1524)
		(layer "In4.Cu")
		(net "M_A_DQ34")
	)
	(segment
		(start 106.1085 -54.5592)
		(end 105.7656 -54.2163)
		(width 0.1524)
		(layer "In4.Cu")
		(net "M_A_DQ34")
	)
	(segment
		(start 98.817938 -51.040538)
		(end 98.817938 -50.8)
		(width 0.1524)
		(layer "In4.Cu")
		(net "M_A_DQ34")
	)
	(segment
		(start 108.6866 -57.277)
		(end 108.331 -56.9214)
		(width 0.1524)
		(layer "In4.Cu")
		(net "M_A_DQ34")
	)
	(segment
		(start 142.24 -61.1632)
		(end 142.24 -61.9252)
		(width 0.1524)
		(layer "In4.Cu")
		(net "M_A_DQ34")
	)
	(segment
		(start 136.398 -57.277)
		(end 136.2456 -57.4294)
		(width 0.1524)
		(layer "In4.Cu")
		(net "M_A_DQ34")
	)
	(segment
		(start 144.7419 -62.3443)
		(end 145.1102 -61.976)
		(width 0.1524)
		(layer "In4.Cu")
		(net "M_A_DQ34")
	)
	(segment
		(start 133.2484 -57.7596)
		(end 133.2484 -57.4294)
		(width 0.1524)
		(layer "In4.Cu")
		(net "M_A_DQ34")
	)
	(segment
		(start 104.8766 -53.8734)
		(end 104.521 -53.8734)
		(width 0.1524)
		(layer "In4.Cu")
		(net "M_A_DQ34")
	)
	(segment
		(start 137.2616 -58.0898)
		(end 137.1092 -57.9374)
		(width 0.1524)
		(layer "In4.Cu")
		(net "M_A_DQ34")
	)
	(segment
		(start 135.509 -57.912)
		(end 135.3566 -57.7596)
		(width 0.1524)
		(layer "In4.Cu")
		(net "M_A_DQ34")
	)
	(segment
		(start 140.9319 -61.2775)
		(end 141.6304 -60.579)
		(width 0.1524)
		(layer "In4.Cu")
		(net "M_A_DQ34")
	)
	(segment
		(start 107.3658 -57.277)
		(end 106.8324 -57.277)
		(width 0.1524)
		(layer "In4.Cu")
		(net "M_A_DQ34")
	)
	(segment
		(start 133.4008 -57.912)
		(end 133.2484 -57.7596)
		(width 0.1524)
		(layer "In4.Cu")
		(net "M_A_DQ34")
	)
	(segment
		(start 97.056194 -48.65878)
		(end 96.8502 -48.65878)
		(width 0.1016)
		(layer "In4.Cu")
		(net "M_A_DQ34")
	)
	(segment
		(start 143.8148 -63.5)
		(end 143.3576 -63.5)
		(width 0.1524)
		(layer "In4.Cu")
		(net "M_A_DQ34")
	)
	(segment
		(start 136.2456 -57.4294)
		(end 136.2456 -57.7596)
		(width 0.1524)
		(layer "In4.Cu")
		(net "M_A_DQ34")
	)
	(segment
		(start 136.2456 -57.7596)
		(end 136.0932 -57.912)
		(width 0.1524)
		(layer "In4.Cu")
		(net "M_A_DQ34")
	)
	(segment
		(start 108.331 -56.9214)
		(end 107.7214 -56.9214)
		(width 0.1524)
		(layer "In4.Cu")
		(net "M_A_DQ34")
	)
	(segment
		(start 141.10081 -62.0776)
		(end 140.9319 -61.90869)
		(width 0.1524)
		(layer "In4.Cu")
		(net "M_A_DQ34")
	)
	(segment
		(start 145.1102 -61.976)
		(end 145.1102 -61.626496)
		(width 0.1524)
		(layer "In4.Cu")
		(net "M_A_DQ34")
	)
	(segment
		(start 142.3924 -61.0108)
		(end 142.24 -61.1632)
		(width 0.1524)
		(layer "In4.Cu")
		(net "M_A_DQ34")
	)
	(segment
		(start 133.096 -57.277)
		(end 108.6866 -57.277)
		(width 0.1524)
		(layer "In4.Cu")
		(net "M_A_DQ34")
	)
	(segment
		(start 136.0932 -57.912)
		(end 135.509 -57.912)
		(width 0.1524)
		(layer "In4.Cu")
		(net "M_A_DQ34")
	)
	(segment
		(start 99.3394 -51.562)
		(end 98.817938 -51.040538)
		(width 0.1524)
		(layer "In4.Cu")
		(net "M_A_DQ34")
	)
	(segment
		(start 144.7419 -62.9285)
		(end 144.7419 -62.3443)
		(width 0.1524)
		(layer "In4.Cu")
		(net "M_A_DQ34")
	)
	(segment
		(start 107.7214 -56.9214)
		(end 107.3658 -57.277)
		(width 0.1524)
		(layer "In4.Cu")
		(net "M_A_DQ34")
	)
	(segment
		(start 136.9568 -57.277)
		(end 136.398 -57.277)
		(width 0.1524)
		(layer "In4.Cu")
		(net "M_A_DQ34")
	)
	(segment
		(start 104.1908 -53.5432)
		(end 104.1908 -53.1876)
		(width 0.1524)
		(layer "In4.Cu")
		(net "M_A_DQ34")
	)
	(segment
		(start 133.2484 -57.4294)
		(end 133.096 -57.277)
		(width 0.1524)
		(layer "In4.Cu")
		(net "M_A_DQ34")
	)
	(segment
		(start 106.6546 -57.4548)
		(end 106.2736 -57.4548)
		(width 0.1524)
		(layer "In4.Cu")
		(net "M_A_DQ34")
	)
	(segment
		(start 97.76333 -49.149)
		(end 97.546414 -49.149)
		(width 0.1016)
		(layer "In4.Cu")
		(net "M_A_DQ34")
	)
	(segment
		(start 145.1102 -63.5508)
		(end 145.1102 -63.2968)
		(width 0.1524)
		(layer "In4.Cu")
		(net "M_A_DQ34")
	)
	(segment
		(start 139.051284 -58.789316)
		(end 138.494516 -58.789316)
		(width 0.1524)
		(layer "In4.Cu")
		(net "M_A_DQ34")
	)
	(segment
		(start 141.6304 -60.198)
		(end 141.3764 -59.944)
		(width 0.1524)
		(layer "In4.Cu")
		(net "M_A_DQ34")
	)
	(segment
		(start 105.2195 -54.2163)
		(end 104.8766 -53.8734)
		(width 0.1524)
		(layer "In4.Cu")
		(net "M_A_DQ34")
	)
	(segment
		(start 99.3394 -52.2732)
		(end 99.3394 -51.562)
		(width 0.1524)
		(layer "In4.Cu")
		(net "M_A_DQ34")
	)
	(segment
		(start 141.3764 -59.944)
		(end 141.0208 -59.944)
		(width 0.1524)
		(layer "In4.Cu")
		(net "M_A_DQ34")
	)
	(segment
		(start 145.1102 -61.626496)
		(end 144.596104 -61.1124)
		(width 0.1524)
		(layer "In4.Cu")
		(net "M_A_DQ34")
	)
	(segment
		(start 103.884222 -52.881022)
		(end 102.566978 -52.881022)
		(width 0.1524)
		(layer "In4.Cu")
		(net "M_A_DQ34")
	)
	(segment
		(start 140.50645 -60.45835)
		(end 140.16355 -60.45835)
		(width 0.1524)
		(layer "In4.Cu")
		(net "M_A_DQ34")
	)
	(segment
		(start 47.9552 -54.6481)
		(end 49.0474 -54.6481)
		(width 0.508)
		(layer "F.Cu")
		(net "P3V3_CLK_R_VDD25")
	)
	(segment
		(start 103.6574 -49.1744)
		(end 103.4542 -49.1744)
		(width 0.1016)
		(layer "F.Cu")
		(net "M_A_CK_DN2")
	)
	(segment
		(start 154.22626 -69.85)
		(end 154.22626 -69.091048)
		(width 0.2159)
		(layer "F.Cu")
		(net "M_A_CK_DN2")
	)
	(segment
		(start 103.4542 -49.1744)
		(end 103.325168 -49.303432)
		(width 0.1016)
		(layer "F.Cu")
		(net "M_A_CK_DN2")
	)
	(segment
		(start 154.22626 -69.091048)
		(end 154.684984 -68.632324)
		(width 0.2159)
		(layer "F.Cu")
		(net "M_A_CK_DN2")
	)
	(segment
		(start 103.325168 -49.303432)
		(end 103.325168 -49.545494)
		(width 0.1016)
		(layer "F.Cu")
		(net "M_A_CK_DN2")
	)
	(segment
		(start 154.15006 -69.9262)
		(end 154.22626 -69.85)
		(width 0.2159)
		(layer "F.Cu")
		(net "M_A_CK_DN2")
	)
	(segment
		(start 154.15006 -70.806564)
		(end 154.15006 -69.9262)
		(width 0.2159)
		(layer "F.Cu")
		(net "M_A_CK_DN2")
	)
	(via
		(at 154.684984 -68.632324)
		(size 0.4318)
		(drill 0.2032)
		(layers "F.Cu" "B.Cu")
		(net "M_A_CK_DN2")
	)
	(via
		(at 103.6574 -49.1744)
		(size 0.4318)
		(drill 0.2032)
		(layers "F.Cu" "B.Cu")
		(net "M_A_CK_DN2")
	)
	(segment
		(start 130.225546 -52.196746)
		(end 128.269238 -52.196746)
		(width 0.1905)
		(layer "In7.Cu")
		(net "M_A_CK_DN2")
	)
	(segment
		(start 109.645196 -53.78704)
		(end 109.073696 -53.78704)
		(width 0.1905)
		(layer "In7.Cu")
		(net "M_A_CK_DN2")
	)
	(segment
		(start 115.20805 -54.0131)
		(end 114.63655 -54.0131)
		(width 0.1905)
		(layer "In7.Cu")
		(net "M_A_CK_DN2")
	)
	(segment
		(start 150.014432 -55.2069)
		(end 148.949156 -55.2069)
		(width 0.1905)
		(layer "In7.Cu")
		(net "M_A_CK_DN2")
	)
	(segment
		(start 108.847636 -54.0131)
		(end 108.276136 -54.0131)
		(width 0.1905)
		(layer "In7.Cu")
		(net "M_A_CK_DN2")
	)
	(segment
		(start 123.544838 -52.196746)
		(end 123.271534 -52.47005)
		(width 0.1905)
		(layer "In7.Cu")
		(net "M_A_CK_DN2")
	)
	(segment
		(start 108.276136 -54.0131)
		(end 107.865418 -53.602382)
		(width 0.1905)
		(layer "In7.Cu")
		(net "M_A_CK_DN2")
	)
	(segment
		(start 109.871256 -54.0131)
		(end 109.645196 -53.78704)
		(width 0.1905)
		(layer "In7.Cu")
		(net "M_A_CK_DN2")
	)
	(segment
		(start 153.420318 -57.154318)
		(end 151.96185 -57.154318)
		(width 0.1905)
		(layer "In7.Cu")
		(net "M_A_CK_DN2")
	)
	(segment
		(start 135.057642 -52.422806)
		(end 134.080758 -52.422806)
		(width 0.1905)
		(layer "In7.Cu")
		(net "M_A_CK_DN2")
	)
	(segment
		(start 103.559864 -49.551336)
		(end 103.7336 -49.725072)
		(width 0.1016)
		(layer "In7.Cu")
		(net "M_A_CK_DN2")
	)
	(segment
		(start 119.343678 -52.885086)
		(end 119.023892 -52.885086)
		(width 0.1905)
		(layer "In7.Cu")
		(net "M_A_CK_DN2")
	)
	(segment
		(start 135.485886 -52.85105)
		(end 135.057642 -52.422806)
		(width 0.1905)
		(layer "In7.Cu")
		(net "M_A_CK_DN2")
	)
	(segment
		(start 113.83899 -53.78704)
		(end 113.61293 -54.0131)
		(width 0.1905)
		(layer "In7.Cu")
		(net "M_A_CK_DN2")
	)
	(segment
		(start 118.215664 -54.0131)
		(end 116.23167 -54.0131)
		(width 0.1905)
		(layer "In7.Cu")
		(net "M_A_CK_DN2")
	)
	(segment
		(start 147.3708 -54.9148)
		(end 146.7866 -54.3306)
		(width 0.1905)
		(layer "In7.Cu")
		(net "M_A_CK_DN2")
	)
	(segment
		(start 132.9563 -52.422806)
		(end 131.904994 -52.422806)
		(width 0.1905)
		(layer "In7.Cu")
		(net "M_A_CK_DN2")
	)
	(segment
		(start 113.61293 -54.0131)
		(end 113.04143 -54.0131)
		(width 0.1905)
		(layer "In7.Cu")
		(net "M_A_CK_DN2")
	)
	(segment
		(start 120.032018 -52.196746)
		(end 119.343678 -52.885086)
		(width 0.1905)
		(layer "In7.Cu")
		(net "M_A_CK_DN2")
	)
	(segment
		(start 154.33421 -59.21121)
		(end 154.33421 -58.63971)
		(width 0.1905)
		(layer "In7.Cu")
		(net "M_A_CK_DN2")
	)
	(segment
		(start 148.287486 -55.86857)
		(end 147.594066 -55.86857)
		(width 0.1905)
		(layer "In7.Cu")
		(net "M_A_CK_DN2")
	)
	(segment
		(start 114.63655 -54.0131)
		(end 114.41049 -53.78704)
		(width 0.1905)
		(layer "In7.Cu")
		(net "M_A_CK_DN2")
	)
	(segment
		(start 154.684984 -68.632324)
		(end 154.684984 -68.615052)
		(width 0.1905)
		(layer "In7.Cu")
		(net "M_A_CK_DN2")
	)
	(segment
		(start 148.949156 -55.2069)
		(end 148.287486 -55.86857)
		(width 0.1905)
		(layer "In7.Cu")
		(net "M_A_CK_DN2")
	)
	(segment
		(start 151.96185 -57.154318)
		(end 150.014432 -55.2069)
		(width 0.1905)
		(layer "In7.Cu")
		(net "M_A_CK_DN2")
	)
	(segment
		(start 154.33421 -58.63971)
		(end 154.10815 -58.41365)
		(width 0.1905)
		(layer "In7.Cu")
		(net "M_A_CK_DN2")
	)
	(segment
		(start 152.74925 -64.588644)
		(end 152.74925 -62.219586)
		(width 0.1905)
		(layer "In7.Cu")
		(net "M_A_CK_DN2")
	)
	(segment
		(start 124.46381 -52.196746)
		(end 123.544838 -52.196746)
		(width 0.1905)
		(layer "In7.Cu")
		(net "M_A_CK_DN2")
	)
	(segment
		(start 147.3708 -55.645304)
		(end 147.3708 -54.9148)
		(width 0.1905)
		(layer "In7.Cu")
		(net "M_A_CK_DN2")
	)
	(segment
		(start 144.576546 -52.85105)
		(end 142.81404 -52.85105)
		(width 0.1905)
		(layer "In7.Cu")
		(net "M_A_CK_DN2")
	)
	(segment
		(start 115.43411 -53.78704)
		(end 115.20805 -54.0131)
		(width 0.1905)
		(layer "In7.Cu")
		(net "M_A_CK_DN2")
	)
	(segment
		(start 154.10815 -59.43727)
		(end 154.33421 -59.21121)
		(width 0.1905)
		(layer "In7.Cu")
		(net "M_A_CK_DN2")
	)
	(segment
		(start 113.04143 -54.0131)
		(end 112.81537 -53.78704)
		(width 0.1905)
		(layer "In7.Cu")
		(net "M_A_CK_DN2")
	)
	(segment
		(start 123.271534 -52.47005)
		(end 122.374914 -52.47005)
		(width 0.1905)
		(layer "In7.Cu")
		(net "M_A_CK_DN2")
	)
	(segment
		(start 118.619778 -53.608986)
		(end 118.215664 -54.0131)
		(width 0.1905)
		(layer "In7.Cu")
		(net "M_A_CK_DN2")
	)
	(segment
		(start 146.7866 -54.3306)
		(end 146.056096 -54.3306)
		(width 0.1905)
		(layer "In7.Cu")
		(net "M_A_CK_DN2")
	)
	(segment
		(start 133.722364 -52.7812)
		(end 133.314694 -52.7812)
		(width 0.1905)
		(layer "In7.Cu")
		(net "M_A_CK_DN2")
	)
	(segment
		(start 112.01781 -54.0131)
		(end 109.871256 -54.0131)
		(width 0.1905)
		(layer "In7.Cu")
		(net "M_A_CK_DN2")
	)
	(segment
		(start 152.74925 -62.219586)
		(end 154.10815 -60.860686)
		(width 0.1905)
		(layer "In7.Cu")
		(net "M_A_CK_DN2")
	)
	(segment
		(start 118.619778 -53.2892)
		(end 118.619778 -53.608986)
		(width 0.1905)
		(layer "In7.Cu")
		(net "M_A_CK_DN2")
	)
	(segment
		(start 154.10815 -60.860686)
		(end 154.10815 -59.43727)
		(width 0.1905)
		(layer "In7.Cu")
		(net "M_A_CK_DN2")
	)
	(segment
		(start 122.10161 -52.196746)
		(end 120.032018 -52.196746)
		(width 0.1905)
		(layer "In7.Cu")
		(net "M_A_CK_DN2")
	)
	(segment
		(start 103.7336 -49.725072)
		(end 103.7336 -51.477672)
		(width 0.1016)
		(layer "In7.Cu")
		(net "M_A_CK_DN2")
	)
	(segment
		(start 154.10815 -57.84215)
		(end 153.420318 -57.154318)
		(width 0.1905)
		(layer "In7.Cu")
		(net "M_A_CK_DN2")
	)
	(segment
		(start 107.678982 -53.602382)
		(end 107.865418 -53.602382)
		(width 0.1016)
		(layer "In7.Cu")
		(net "M_A_CK_DN2")
	)
	(segment
		(start 154.684984 -68.615052)
		(end 154.879294 -68.420742)
		(width 0.1905)
		(layer "In7.Cu")
		(net "M_A_CK_DN2")
	)
	(segment
		(start 114.41049 -53.78704)
		(end 113.83899 -53.78704)
		(width 0.1905)
		(layer "In7.Cu")
		(net "M_A_CK_DN2")
	)
	(segment
		(start 154.879294 -66.207894)
		(end 154.432 -65.7606)
		(width 0.1905)
		(layer "In7.Cu")
		(net "M_A_CK_DN2")
	)
	(segment
		(start 112.24387 -53.78704)
		(end 112.01781 -54.0131)
		(width 0.1905)
		(layer "In7.Cu")
		(net "M_A_CK_DN2")
	)
	(segment
		(start 146.056096 -54.3306)
		(end 144.576546 -52.85105)
		(width 0.1905)
		(layer "In7.Cu")
		(net "M_A_CK_DN2")
	)
	(segment
		(start 142.81404 -52.85105)
		(end 142.159736 -52.196746)
		(width 0.1905)
		(layer "In7.Cu")
		(net "M_A_CK_DN2")
	)
	(segment
		(start 154.879294 -68.420742)
		(end 154.879294 -66.207894)
		(width 0.1905)
		(layer "In7.Cu")
		(net "M_A_CK_DN2")
	)
	(segment
		(start 138.44905 -52.196746)
		(end 137.794746 -52.85105)
		(width 0.1905)
		(layer "In7.Cu")
		(net "M_A_CK_DN2")
	)
	(segment
		(start 116.23167 -54.0131)
		(end 116.00561 -53.78704)
		(width 0.1905)
		(layer "In7.Cu")
		(net "M_A_CK_DN2")
	)
	(segment
		(start 127.099314 -52.47005)
		(end 126.82601 -52.196746)
		(width 0.1905)
		(layer "In7.Cu")
		(net "M_A_CK_DN2")
	)
	(segment
		(start 119.023892 -52.885086)
		(end 118.619778 -53.2892)
		(width 0.1905)
		(layer "In7.Cu")
		(net "M_A_CK_DN2")
	)
	(segment
		(start 122.374914 -52.47005)
		(end 122.10161 -52.196746)
		(width 0.1905)
		(layer "In7.Cu")
		(net "M_A_CK_DN2")
	)
	(segment
		(start 131.904994 -52.422806)
		(end 131.47675 -52.85105)
		(width 0.1905)
		(layer "In7.Cu")
		(net "M_A_CK_DN2")
	)
	(segment
		(start 147.594066 -55.86857)
		(end 147.3708 -55.645304)
		(width 0.1905)
		(layer "In7.Cu")
		(net "M_A_CK_DN2")
	)
	(segment
		(start 128.269238 -52.196746)
		(end 127.995934 -52.47005)
		(width 0.1905)
		(layer "In7.Cu")
		(net "M_A_CK_DN2")
	)
	(segment
		(start 126.82601 -52.196746)
		(end 125.907038 -52.196746)
		(width 0.1905)
		(layer "In7.Cu")
		(net "M_A_CK_DN2")
	)
	(segment
		(start 124.737114 -52.47005)
		(end 124.46381 -52.196746)
		(width 0.1905)
		(layer "In7.Cu")
		(net "M_A_CK_DN2")
	)
	(segment
		(start 125.633734 -52.47005)
		(end 124.737114 -52.47005)
		(width 0.1905)
		(layer "In7.Cu")
		(net "M_A_CK_DN2")
	)
	(segment
		(start 154.432 -65.7606)
		(end 153.921206 -65.7606)
		(width 0.1905)
		(layer "In7.Cu")
		(net "M_A_CK_DN2")
	)
	(segment
		(start 154.10815 -58.41365)
		(end 154.10815 -57.84215)
		(width 0.1905)
		(layer "In7.Cu")
		(net "M_A_CK_DN2")
	)
	(segment
		(start 105.265474 -53.009546)
		(end 107.086146 -53.009546)
		(width 0.1016)
		(layer "In7.Cu")
		(net "M_A_CK_DN2")
	)
	(segment
		(start 103.6574 -49.1744)
		(end 103.559864 -49.271936)
		(width 0.1016)
		(layer "In7.Cu")
		(net "M_A_CK_DN2")
	)
	(segment
		(start 109.073696 -53.78704)
		(end 108.847636 -54.0131)
		(width 0.1905)
		(layer "In7.Cu")
		(net "M_A_CK_DN2")
	)
	(segment
		(start 112.81537 -53.78704)
		(end 112.24387 -53.78704)
		(width 0.1905)
		(layer "In7.Cu")
		(net "M_A_CK_DN2")
	)
	(segment
		(start 116.00561 -53.78704)
		(end 115.43411 -53.78704)
		(width 0.1905)
		(layer "In7.Cu")
		(net "M_A_CK_DN2")
	)
	(segment
		(start 130.87985 -52.85105)
		(end 130.225546 -52.196746)
		(width 0.1905)
		(layer "In7.Cu")
		(net "M_A_CK_DN2")
	)
	(segment
		(start 134.080758 -52.422806)
		(end 133.722364 -52.7812)
		(width 0.1905)
		(layer "In7.Cu")
		(net "M_A_CK_DN2")
	)
	(segment
		(start 103.7336 -51.477672)
		(end 105.265474 -53.009546)
		(width 0.1016)
		(layer "In7.Cu")
		(net "M_A_CK_DN2")
	)
	(segment
		(start 127.995934 -52.47005)
		(end 127.099314 -52.47005)
		(width 0.1905)
		(layer "In7.Cu")
		(net "M_A_CK_DN2")
	)
	(segment
		(start 103.559864 -49.271936)
		(end 103.559864 -49.551336)
		(width 0.1016)
		(layer "In7.Cu")
		(net "M_A_CK_DN2")
	)
	(segment
		(start 131.47675 -52.85105)
		(end 130.87985 -52.85105)
		(width 0.1905)
		(layer "In7.Cu")
		(net "M_A_CK_DN2")
	)
	(segment
		(start 125.907038 -52.196746)
		(end 125.633734 -52.47005)
		(width 0.1905)
		(layer "In7.Cu")
		(net "M_A_CK_DN2")
	)
	(segment
		(start 107.086146 -53.009546)
		(end 107.678982 -53.602382)
		(width 0.1016)
		(layer "In7.Cu")
		(net "M_A_CK_DN2")
	)
	(segment
		(start 153.921206 -65.7606)
		(end 152.74925 -64.588644)
		(width 0.1905)
		(layer "In7.Cu")
		(net "M_A_CK_DN2")
	)
	(segment
		(start 137.794746 -52.85105)
		(end 135.485886 -52.85105)
		(width 0.1905)
		(layer "In7.Cu")
		(net "M_A_CK_DN2")
	)
	(segment
		(start 142.159736 -52.196746)
		(end 138.44905 -52.196746)
		(width 0.1905)
		(layer "In7.Cu")
		(net "M_A_CK_DN2")
	)
	(segment
		(start 133.314694 -52.7812)
		(end 132.9563 -52.422806)
		(width 0.1905)
		(layer "In7.Cu")
		(net "M_A_CK_DN2")
	)
	(via
		(at 49.192688 -44.845224)
		(size 0.7112)
		(drill 0.3556)
		(layers "F.Cu" "B.Cu")
		(net "CLKGEN_DIF_STOP#")
	)
	(segment
		(start 49.53 -44.507912)
		(end 49.192688 -44.845224)
		(width 0.1143)
		(layer "B.Cu")
		(net "CLKGEN_DIF_STOP#")
	)
	(segment
		(start 49.53 -43.8658)
		(end 49.53 -44.507912)
		(width 0.1143)
		(layer "B.Cu")
		(net "CLKGEN_DIF_STOP#")
	)
	(segment
		(start 48.84801 -45.189902)
		(end 49.192688 -44.845224)
		(width 0.1143)
		(layer "B.Cu")
		(net "CLKGEN_DIF_STOP#")
	)
	(segment
		(start 48.058578 -45.642022)
		(end 48.510698 -45.189902)
		(width 0.1143)
		(layer "B.Cu")
		(net "CLKGEN_DIF_STOP#")
	)
	(segment
		(start 48.510698 -45.189902)
		(end 48.84801 -45.189902)
		(width 0.1143)
		(layer "B.Cu")
		(net "CLKGEN_DIF_STOP#")
	)
	(segment
		(start 48.058578 -46.087792)
		(end 48.058578 -45.642022)
		(width 0.1143)
		(layer "B.Cu")
		(net "CLKGEN_DIF_STOP#")
	)
	(segment
		(start 132.550154 -70.116446)
		(end 133.0579 -69.6087)
		(width 0.1778)
		(layer "F.Cu")
		(net "M_A_DQ61")
	)
	(segment
		(start 97.1804 -56.5404)
		(end 97.1804 -53.5686)
		(width 0.1016)
		(layer "F.Cu")
		(net "M_A_DQ61")
	)
	(segment
		(start 96.703388 -53.091588)
		(end 96.703388 -52.148486)
		(width 0.1016)
		(layer "F.Cu")
		(net "M_A_DQ61")
	)
	(segment
		(start 96.703388 -52.148486)
		(end 96.771968 -52.079906)
		(width 0.1016)
		(layer "F.Cu")
		(net "M_A_DQ61")
	)
	(segment
		(start 96.771968 -52.079906)
		(end 96.771968 -51.780186)
		(width 0.1016)
		(layer "F.Cu")
		(net "M_A_DQ61")
	)
	(segment
		(start 97.1804 -53.5686)
		(end 96.703388 -53.091588)
		(width 0.1016)
		(layer "F.Cu")
		(net "M_A_DQ61")
	)
	(segment
		(start 96.771968 -51.780186)
		(end 96.413828 -51.422046)
		(width 0.1016)
		(layer "F.Cu")
		(net "M_A_DQ61")
	)
	(segment
		(start 133.0579 -69.6087)
		(end 133.0579 -69.026278)
		(width 0.1778)
		(layer "F.Cu")
		(net "M_A_DQ61")
	)
	(segment
		(start 96.413828 -51.422046)
		(end 96.413828 -50.995834)
		(width 0.1016)
		(layer "F.Cu")
		(net "M_A_DQ61")
	)
	(segment
		(start 132.550154 -70.806564)
		(end 132.550154 -70.116446)
		(width 0.1778)
		(layer "F.Cu")
		(net "M_A_DQ61")
	)
	(segment
		(start 132.839968 -68.8086)
		(end 132.839968 -68.7578)
		(width 0.1778)
		(layer "F.Cu")
		(net "M_A_DQ61")
	)
	(segment
		(start 133.0579 -69.026278)
		(end 132.839968 -68.8086)
		(width 0.1778)
		(layer "F.Cu")
		(net "M_A_DQ61")
	)
	(via
		(at 97.1804 -56.5404)
		(size 0.4318)
		(drill 0.2032)
		(layers "F.Cu" "B.Cu")
		(net "M_A_DQ61")
	)
	(via
		(at 132.839968 -68.7578)
		(size 0.4318)
		(drill 0.2032)
		(layers "F.Cu" "B.Cu")
		(net "M_A_DQ61")
	)
	(segment
		(start 133.450076 -69.950076)
		(end 133.0579 -69.5579)
		(width 0.1778)
		(layer "B.Cu")
		(net "M_A_DQ61")
	)
	(segment
		(start 133.450076 -70.79996)
		(end 133.450076 -69.950076)
		(width 0.1778)
		(layer "B.Cu")
		(net "M_A_DQ61")
	)
	(segment
		(start 133.0579 -69.026278)
		(end 132.839968 -68.8086)
		(width 0.1778)
		(layer "B.Cu")
		(net "M_A_DQ61")
	)
	(segment
		(start 133.0579 -69.5579)
		(end 133.0579 -69.026278)
		(width 0.1778)
		(layer "B.Cu")
		(net "M_A_DQ61")
	)
	(segment
		(start 132.839968 -68.8086)
		(end 132.839968 -68.7578)
		(width 0.1778)
		(layer "B.Cu")
		(net "M_A_DQ61")
	)
	(segment
		(start 134.20471 -64.57569)
		(end 134.3787 -64.4017)
		(width 0.1524)
		(layer "In7.Cu")
		(net "M_A_DQ61")
	)
	(segment
		(start 132.839968 -68.7578)
		(end 133.2992 -68.298568)
		(width 0.1524)
		(layer "In7.Cu")
		(net "M_A_DQ61")
	)
	(segment
		(start 125.489716 -63.0682)
		(end 120.234964 -63.0682)
		(width 0.1524)
		(layer "In7.Cu")
		(net "M_A_DQ61")
	)
	(segment
		(start 134.20471 -64.90589)
		(end 134.20471 -64.57569)
		(width 0.1524)
		(layer "In7.Cu")
		(net "M_A_DQ61")
	)
	(segment
		(start 126.200916 -62.357)
		(end 125.489716 -63.0682)
		(width 0.1524)
		(layer "In7.Cu")
		(net "M_A_DQ61")
	)
	(segment
		(start 105.279444 -63.329058)
		(end 104.057196 -63.329058)
		(width 0.1524)
		(layer "In7.Cu")
		(net "M_A_DQ61")
	)
	(segment
		(start 117.829076 -63.0428)
		(end 113.881662 -63.0428)
		(width 0.1524)
		(layer "In7.Cu")
		(net "M_A_DQ61")
	)
	(segment
		(start 98.447352 -61.097414)
		(end 98.447352 -59.966352)
		(width 0.1524)
		(layer "In7.Cu")
		(net "M_A_DQ61")
	)
	(segment
		(start 113.881662 -63.0428)
		(end 113.19256 -63.731902)
		(width 0.1524)
		(layer "In7.Cu")
		(net "M_A_DQ61")
	)
	(segment
		(start 133.2992 -68.298568)
		(end 133.2992 -65.8114)
		(width 0.1524)
		(layer "In7.Cu")
		(net "M_A_DQ61")
	)
	(segment
		(start 98.447352 -59.966352)
		(end 96.7994 -58.3184)
		(width 0.1016)
		(layer "In7.Cu")
		(net "M_A_DQ61")
	)
	(segment
		(start 134.3787 -64.4017)
		(end 134.3787 -62.9285)
		(width 0.1524)
		(layer "In7.Cu")
		(net "M_A_DQ61")
	)
	(segment
		(start 118.518178 -63.731902)
		(end 117.829076 -63.0428)
		(width 0.1524)
		(layer "In7.Cu")
		(net "M_A_DQ61")
	)
	(segment
		(start 113.19256 -63.731902)
		(end 105.682288 -63.731902)
		(width 0.1524)
		(layer "In7.Cu")
		(net "M_A_DQ61")
	)
	(segment
		(start 101.027738 -63.6778)
		(end 98.447352 -61.097414)
		(width 0.1524)
		(layer "In7.Cu")
		(net "M_A_DQ61")
	)
	(segment
		(start 133.8072 -62.357)
		(end 126.200916 -62.357)
		(width 0.1524)
		(layer "In7.Cu")
		(net "M_A_DQ61")
	)
	(segment
		(start 133.2992 -65.8114)
		(end 134.20471 -64.90589)
		(width 0.1524)
		(layer "In7.Cu")
		(net "M_A_DQ61")
	)
	(segment
		(start 119.571262 -63.731902)
		(end 118.518178 -63.731902)
		(width 0.1524)
		(layer "In7.Cu")
		(net "M_A_DQ61")
	)
	(segment
		(start 134.3787 -62.9285)
		(end 133.8072 -62.357)
		(width 0.1524)
		(layer "In7.Cu")
		(net "M_A_DQ61")
	)
	(segment
		(start 120.234964 -63.0682)
		(end 119.571262 -63.731902)
		(width 0.1524)
		(layer "In7.Cu")
		(net "M_A_DQ61")
	)
	(segment
		(start 104.057196 -63.329058)
		(end 103.708454 -63.6778)
		(width 0.1524)
		(layer "In7.Cu")
		(net "M_A_DQ61")
	)
	(segment
		(start 96.7994 -56.9214)
		(end 97.1804 -56.5404)
		(width 0.1016)
		(layer "In7.Cu")
		(net "M_A_DQ61")
	)
	(segment
		(start 96.7994 -58.3184)
		(end 96.7994 -56.9214)
		(width 0.1016)
		(layer "In7.Cu")
		(net "M_A_DQ61")
	)
	(segment
		(start 103.708454 -63.6778)
		(end 101.027738 -63.6778)
		(width 0.1524)
		(layer "In7.Cu")
		(net "M_A_DQ61")
	)
	(segment
		(start 105.682288 -63.731902)
		(end 105.279444 -63.329058)
		(width 0.1524)
		(layer "In7.Cu")
		(net "M_A_DQ61")
	)
	(segment
		(start 106.16946 -53.180996)
		(end 106.16946 -53.767228)
		(width 0.1016)
		(layer "F.Cu")
		(net "CLK_100M_CPU_MPLL0_DN")
	)
	(segment
		(start 107.154472 -54.3306)
		(end 107.5055 -54.681628)
		(width 0.1016)
		(layer "F.Cu")
		(net "CLK_100M_CPU_MPLL0_DN")
	)
	(segment
		(start 101.226112 -59.02833)
		(end 100.929694 -59.324748)
		(width 0.1397)
		(layer "F.Cu")
		(net "CLK_100M_CPU_MPLL0_DN")
	)
	(segment
		(start 101.50983 -59.02833)
		(end 101.226112 -59.02833)
		(width 0.1397)
		(layer "F.Cu")
		(net "CLK_100M_CPU_MPLL0_DN")
	)
	(segment
		(start 106.469688 -52.28844)
		(end 106.469688 -52.880768)
		(width 0.1016)
		(layer "F.Cu")
		(net "CLK_100M_CPU_MPLL0_DN")
	)
	(segment
		(start 100.929694 -59.608466)
		(end 99.89312 -60.64504)
		(width 0.1397)
		(layer "F.Cu")
		(net "CLK_100M_CPU_MPLL0_DN")
	)
	(segment
		(start 107.5055 -56.7817)
		(end 105.41635 -58.87085)
		(width 0.1016)
		(layer "F.Cu")
		(net "CLK_100M_CPU_MPLL0_DN")
	)
	(segment
		(start 105.961688 -51.442874)
		(end 105.961688 -51.78044)
		(width 0.1016)
		(layer "F.Cu")
		(net "CLK_100M_CPU_MPLL0_DN")
	)
	(segment
		(start 106.16946 -53.767228)
		(end 106.732832 -54.3306)
		(width 0.1016)
		(layer "F.Cu")
		(net "CLK_100M_CPU_MPLL0_DN")
	)
	(segment
		(start 103.7463 -58.801)
		(end 103.7209 -58.801)
		(width 0.1016)
		(layer "F.Cu")
		(net "CLK_100M_CPU_MPLL0_DN")
	)
	(segment
		(start 107.5055 -54.681628)
		(end 107.5055 -56.7817)
		(width 0.1016)
		(layer "F.Cu")
		(net "CLK_100M_CPU_MPLL0_DN")
	)
	(segment
		(start 105.41635 -58.87085)
		(end 103.81615 -58.87085)
		(width 0.1016)
		(layer "F.Cu")
		(net "CLK_100M_CPU_MPLL0_DN")
	)
	(segment
		(start 99.89312 -60.64504)
		(end 99.514152 -60.64504)
		(width 0.1397)
		(layer "F.Cu")
		(net "CLK_100M_CPU_MPLL0_DN")
	)
	(segment
		(start 105.961688 -51.78044)
		(end 106.469688 -52.28844)
		(width 0.1016)
		(layer "F.Cu")
		(net "CLK_100M_CPU_MPLL0_DN")
	)
	(segment
		(start 101.73716 -58.801)
		(end 101.50983 -59.02833)
		(width 0.1397)
		(layer "F.Cu")
		(net "CLK_100M_CPU_MPLL0_DN")
	)
	(segment
		(start 106.732832 -54.3306)
		(end 107.154472 -54.3306)
		(width 0.1016)
		(layer "F.Cu")
		(net "CLK_100M_CPU_MPLL0_DN")
	)
	(segment
		(start 103.81615 -58.87085)
		(end 103.7463 -58.801)
		(width 0.1016)
		(layer "F.Cu")
		(net "CLK_100M_CPU_MPLL0_DN")
	)
	(segment
		(start 103.7209 -58.801)
		(end 101.73716 -58.801)
		(width 0.1397)
		(layer "F.Cu")
		(net "CLK_100M_CPU_MPLL0_DN")
	)
	(segment
		(start 100.929694 -59.324748)
		(end 100.929694 -59.608466)
		(width 0.1397)
		(layer "F.Cu")
		(net "CLK_100M_CPU_MPLL0_DN")
	)
	(segment
		(start 106.469688 -52.880768)
		(end 106.16946 -53.180996)
		(width 0.1016)
		(layer "F.Cu")
		(net "CLK_100M_CPU_MPLL0_DN")
	)
	(via
		(at 50.645568 -48.500538)
		(size 0.508)
		(drill 0.254)
		(layers "F.Cu" "B.Cu")
		(net "CLK_100M_CPU_MPLL0_DN")
	)
	(via
		(at 99.514152 -60.64504)
		(size 0.508)
		(drill 0.254)
		(layers "F.Cu" "B.Cu")
		(net "CLK_100M_CPU_MPLL0_DN")
	)
	(segment
		(start 48.699928 -48.265588)
		(end 50.410618 -48.265588)
		(width 0.1397)
		(layer "B.Cu")
		(net "CLK_100M_CPU_MPLL0_DN")
	)
	(segment
		(start 48.668178 -48.297338)
		(end 48.699928 -48.265588)
		(width 0.1397)
		(layer "B.Cu")
		(net "CLK_100M_CPU_MPLL0_DN")
	)
	(segment
		(start 50.410618 -48.265588)
		(end 50.645568 -48.500538)
		(width 0.1397)
		(layer "B.Cu")
		(net "CLK_100M_CPU_MPLL0_DN")
	)
	(segment
		(start 61.181742 -57.82945)
		(end 58.551572 -55.19928)
		(width 0.1143)
		(layer "In9.Cu")
		(net "CLK_100M_CPU_MPLL0_DN")
	)
	(segment
		(start 57.295542 -53.94325)
		(end 56.10225 -53.94325)
		(width 0.1143)
		(layer "In9.Cu")
		(net "CLK_100M_CPU_MPLL0_DN")
	)
	(segment
		(start 97.46742 -61.17844)
		(end 97.12452 -61.17844)
		(width 0.1143)
		(layer "In9.Cu")
		(net "CLK_100M_CPU_MPLL0_DN")
	)
	(segment
		(start 97.12452 -61.17844)
		(end 96.91116 -61.3918)
		(width 0.1143)
		(layer "In9.Cu")
		(net "CLK_100M_CPU_MPLL0_DN")
	)
	(segment
		(start 94.742 -58.166)
		(end 93.4593 -58.166)
		(width 0.1143)
		(layer "In9.Cu")
		(net "CLK_100M_CPU_MPLL0_DN")
	)
	(segment
		(start 50.410618 -48.265588)
		(end 50.645568 -48.500538)
		(width 0.1143)
		(layer "In9.Cu")
		(net "CLK_100M_CPU_MPLL0_DN")
	)
	(segment
		(start 49.651412 -48.265588)
		(end 50.410618 -48.265588)
		(width 0.1143)
		(layer "In9.Cu")
		(net "CLK_100M_CPU_MPLL0_DN")
	)
	(segment
		(start 96.56826 -61.3918)
		(end 95.885 -60.70854)
		(width 0.1143)
		(layer "In9.Cu")
		(net "CLK_100M_CPU_MPLL0_DN")
	)
	(segment
		(start 56.10225 -53.94325)
		(end 55.85968 -53.70068)
		(width 0.1143)
		(layer "In9.Cu")
		(net "CLK_100M_CPU_MPLL0_DN")
	)
	(segment
		(start 96.91116 -61.3918)
		(end 96.56826 -61.3918)
		(width 0.1143)
		(layer "In9.Cu")
		(net "CLK_100M_CPU_MPLL0_DN")
	)
	(segment
		(start 99.1362 -61.3918)
		(end 98.7933 -61.3918)
		(width 0.1143)
		(layer "In9.Cu")
		(net "CLK_100M_CPU_MPLL0_DN")
	)
	(segment
		(start 55.617364 -53.156612)
		(end 55.315612 -53.156612)
		(width 0.1143)
		(layer "In9.Cu")
		(net "CLK_100M_CPU_MPLL0_DN")
	)
	(segment
		(start 98.23704 -61.17844)
		(end 98.02368 -61.3918)
		(width 0.1143)
		(layer "In9.Cu")
		(net "CLK_100M_CPU_MPLL0_DN")
	)
	(segment
		(start 49.16805 -49.24425)
		(end 49.16805 -48.74895)
		(width 0.1143)
		(layer "In9.Cu")
		(net "CLK_100M_CPU_MPLL0_DN")
	)
	(segment
		(start 65.264538 -57.82945)
		(end 61.181742 -57.82945)
		(width 0.1143)
		(layer "In9.Cu")
		(net "CLK_100M_CPU_MPLL0_DN")
	)
	(segment
		(start 99.514152 -60.64504)
		(end 99.514152 -61.013848)
		(width 0.1143)
		(layer "In9.Cu")
		(net "CLK_100M_CPU_MPLL0_DN")
	)
	(segment
		(start 49.16805 -48.74895)
		(end 49.651412 -48.265588)
		(width 0.1143)
		(layer "In9.Cu")
		(net "CLK_100M_CPU_MPLL0_DN")
	)
	(segment
		(start 58.551572 -54.897528)
		(end 58.309002 -54.654958)
		(width 0.1143)
		(layer "In9.Cu")
		(net "CLK_100M_CPU_MPLL0_DN")
	)
	(segment
		(start 49.9618 -50.038)
		(end 49.16805 -49.24425)
		(width 0.1143)
		(layer "In9.Cu")
		(net "CLK_100M_CPU_MPLL0_DN")
	)
	(segment
		(start 95.885 -59.309)
		(end 94.742 -58.166)
		(width 0.1143)
		(layer "In9.Cu")
		(net "CLK_100M_CPU_MPLL0_DN")
	)
	(segment
		(start 55.85968 -53.398928)
		(end 55.617364 -53.156612)
		(width 0.1143)
		(layer "In9.Cu")
		(net "CLK_100M_CPU_MPLL0_DN")
	)
	(segment
		(start 52.197 -50.038)
		(end 49.9618 -50.038)
		(width 0.1143)
		(layer "In9.Cu")
		(net "CLK_100M_CPU_MPLL0_DN")
	)
	(segment
		(start 93.4593 -58.166)
		(end 89.6112 -62.0141)
		(width 0.1143)
		(layer "In9.Cu")
		(net "CLK_100M_CPU_MPLL0_DN")
	)
	(segment
		(start 58.551572 -55.19928)
		(end 58.551572 -54.897528)
		(width 0.1143)
		(layer "In9.Cu")
		(net "CLK_100M_CPU_MPLL0_DN")
	)
	(segment
		(start 97.68078 -61.3918)
		(end 97.46742 -61.17844)
		(width 0.1143)
		(layer "In9.Cu")
		(net "CLK_100M_CPU_MPLL0_DN")
	)
	(segment
		(start 99.514152 -61.013848)
		(end 99.1362 -61.3918)
		(width 0.1143)
		(layer "In9.Cu")
		(net "CLK_100M_CPU_MPLL0_DN")
	)
	(segment
		(start 89.6112 -62.0141)
		(end 69.449188 -62.0141)
		(width 0.1143)
		(layer "In9.Cu")
		(net "CLK_100M_CPU_MPLL0_DN")
	)
	(segment
		(start 58.309002 -54.654958)
		(end 58.00725 -54.654958)
		(width 0.1143)
		(layer "In9.Cu")
		(net "CLK_100M_CPU_MPLL0_DN")
	)
	(segment
		(start 95.885 -60.70854)
		(end 95.885 -59.309)
		(width 0.1143)
		(layer "In9.Cu")
		(net "CLK_100M_CPU_MPLL0_DN")
	)
	(segment
		(start 69.449188 -62.0141)
		(end 65.264538 -57.82945)
		(width 0.1143)
		(layer "In9.Cu")
		(net "CLK_100M_CPU_MPLL0_DN")
	)
	(segment
		(start 98.57994 -61.17844)
		(end 98.23704 -61.17844)
		(width 0.1143)
		(layer "In9.Cu")
		(net "CLK_100M_CPU_MPLL0_DN")
	)
	(segment
		(start 98.7933 -61.3918)
		(end 98.57994 -61.17844)
		(width 0.1143)
		(layer "In9.Cu")
		(net "CLK_100M_CPU_MPLL0_DN")
	)
	(segment
		(start 55.85968 -53.70068)
		(end 55.85968 -53.398928)
		(width 0.1143)
		(layer "In9.Cu")
		(net "CLK_100M_CPU_MPLL0_DN")
	)
	(segment
		(start 55.315612 -53.156612)
		(end 52.197 -50.038)
		(width 0.1143)
		(layer "In9.Cu")
		(net "CLK_100M_CPU_MPLL0_DN")
	)
	(segment
		(start 98.02368 -61.3918)
		(end 97.68078 -61.3918)
		(width 0.1143)
		(layer "In9.Cu")
		(net "CLK_100M_CPU_MPLL0_DN")
	)
	(segment
		(start 58.00725 -54.654958)
		(end 57.295542 -53.94325)
		(width 0.1143)
		(layer "In9.Cu")
		(net "CLK_100M_CPU_MPLL0_DN")
	)
	(segment
		(start 112.098328 -44.043346)
		(end 112.098328 -43.807634)
		(width 0.1016)
		(layer "F.Cu")
		(net "M_A_DQ26")
	)
	(segment
		(start 117.9322 -46.1772)
		(end 114.232182 -46.1772)
		(width 0.1016)
		(layer "F.Cu")
		(net "M_A_DQ26")
	)
	(segment
		(start 170.650154 -62.59322)
		(end 170.650154 -63.335154)
		(width 0.1778)
		(layer "F.Cu")
		(net "M_A_DQ26")
	)
	(segment
		(start 170.87342 -64.442848)
		(end 171.13758 -64.707008)
		(width 0.1778)
		(layer "F.Cu")
		(net "M_A_DQ26")
	)
	(segment
		(start 170.650154 -63.335154)
		(end 170.87342 -63.55842)
		(width 0.1778)
		(layer "F.Cu")
		(net "M_A_DQ26")
	)
	(segment
		(start 114.232182 -46.1772)
		(end 112.098328 -44.043346)
		(width 0.1016)
		(layer "F.Cu")
		(net "M_A_DQ26")
	)
	(segment
		(start 170.87342 -63.55842)
		(end 170.87342 -64.442848)
		(width 0.1778)
		(layer "F.Cu")
		(net "M_A_DQ26")
	)
	(via
		(at 117.9322 -46.1772)
		(size 0.4318)
		(drill 0.2032)
		(layers "F.Cu" "B.Cu")
		(net "M_A_DQ26")
	)
	(via
		(at 171.13758 -64.707008)
		(size 0.4318)
		(drill 0.2032)
		(layers "F.Cu" "B.Cu")
		(net "M_A_DQ26")
	)
	(segment
		(start 171.550076 -63.307214)
		(end 170.87342 -63.98387)
		(width 0.1778)
		(layer "B.Cu")
		(net "M_A_DQ26")
	)
	(segment
		(start 170.87342 -63.98387)
		(end 170.87342 -64.47282)
		(width 0.1778)
		(layer "B.Cu")
		(net "M_A_DQ26")
	)
	(segment
		(start 171.107608 -64.707008)
		(end 171.13758 -64.707008)
		(width 0.1778)
		(layer "B.Cu")
		(net "M_A_DQ26")
	)
	(segment
		(start 170.87342 -64.47282)
		(end 171.107608 -64.707008)
		(width 0.1778)
		(layer "B.Cu")
		(net "M_A_DQ26")
	)
	(segment
		(start 171.550076 -62.599824)
		(end 171.550076 -63.307214)
		(width 0.1778)
		(layer "B.Cu")
		(net "M_A_DQ26")
	)
	(segment
		(start 155.321 -49.491138)
		(end 155.155138 -49.657)
		(width 0.1524)
		(layer "In2.Cu")
		(net "M_A_DQ26")
	)
	(segment
		(start 162.866578 -51.460146)
		(end 162.866578 -49.368964)
		(width 0.1524)
		(layer "In2.Cu")
		(net "M_A_DQ26")
	)
	(segment
		(start 157.5816 -49.3522)
		(end 157.5816 -47.9806)
		(width 0.1524)
		(layer "In2.Cu")
		(net "M_A_DQ26")
	)
	(segment
		(start 155.4734 -47.8282)
		(end 155.321 -47.9806)
		(width 0.1524)
		(layer "In2.Cu")
		(net "M_A_DQ26")
	)
	(segment
		(start 157.734 -49.5046)
		(end 157.5816 -49.3522)
		(width 0.1524)
		(layer "In2.Cu")
		(net "M_A_DQ26")
	)
	(segment
		(start 153.158444 -47.164244)
		(end 152.9588 -46.9646)
		(width 0.1524)
		(layer "In2.Cu")
		(net "M_A_DQ26")
	)
	(segment
		(start 162.1536 -48.9966)
		(end 161.925 -49.2252)
		(width 0.1524)
		(layer "In2.Cu")
		(net "M_A_DQ26")
	)
	(segment
		(start 121.3866 -45.4406)
		(end 121.1072 -45.72)
		(width 0.1016)
		(layer "In2.Cu")
		(net "M_A_DQ26")
	)
	(segment
		(start 159.163258 -49.2252)
		(end 159.010858 -49.0728)
		(width 0.1524)
		(layer "In2.Cu")
		(net "M_A_DQ26")
	)
	(segment
		(start 170.9166 -64.486028)
		(end 170.9166 -62.3062)
		(width 0.1524)
		(layer "In2.Cu")
		(net "M_A_DQ26")
	)
	(segment
		(start 156.845 -48.9966)
		(end 156.5402 -48.9966)
		(width 0.1524)
		(layer "In2.Cu")
		(net "M_A_DQ26")
	)
	(segment
		(start 171.13758 -64.707008)
		(end 170.9166 -64.486028)
		(width 0.1524)
		(layer "In2.Cu")
		(net "M_A_DQ26")
	)
	(segment
		(start 161.925 -49.2252)
		(end 161.6202 -49.2252)
		(width 0.1524)
		(layer "In2.Cu")
		(net "M_A_DQ26")
	)
	(segment
		(start 156.3878 -48.8442)
		(end 156.3878 -47.9806)
		(width 0.1524)
		(layer "In2.Cu")
		(net "M_A_DQ26")
	)
	(segment
		(start 151.9936 -46.6344)
		(end 151.9936 -46.2788)
		(width 0.1524)
		(layer "In2.Cu")
		(net "M_A_DQ26")
	)
	(segment
		(start 158.3182 -47.8282)
		(end 158.1658 -47.9806)
		(width 0.1524)
		(layer "In2.Cu")
		(net "M_A_DQ26")
	)
	(segment
		(start 156.3878 -47.9806)
		(end 156.2354 -47.8282)
		(width 0.1524)
		(layer "In2.Cu")
		(net "M_A_DQ26")
	)
	(segment
		(start 158.1658 -47.9806)
		(end 158.1658 -49.3522)
		(width 0.1524)
		(layer "In2.Cu")
		(net "M_A_DQ26")
	)
	(segment
		(start 170.9166 -62.3062)
		(end 170.4594 -61.849)
		(width 0.1524)
		(layer "In2.Cu")
		(net "M_A_DQ26")
	)
	(segment
		(start 158.858458 -47.8282)
		(end 158.3182 -47.8282)
		(width 0.1524)
		(layer "In2.Cu")
		(net "M_A_DQ26")
	)
	(segment
		(start 161.4678 -48.006)
		(end 161.3154 -47.8536)
		(width 0.1524)
		(layer "In2.Cu")
		(net "M_A_DQ26")
	)
	(segment
		(start 155.321 -47.9806)
		(end 155.321 -49.491138)
		(width 0.1524)
		(layer "In2.Cu")
		(net "M_A_DQ26")
	)
	(segment
		(start 157.4292 -47.8282)
		(end 157.1498 -47.8282)
		(width 0.1524)
		(layer "In2.Cu")
		(net "M_A_DQ26")
	)
	(segment
		(start 160.839658 -49.0728)
		(end 160.687258 -49.2252)
		(width 0.1524)
		(layer "In2.Cu")
		(net "M_A_DQ26")
	)
	(segment
		(start 153.158444 -47.951644)
		(end 153.158444 -47.164244)
		(width 0.1524)
		(layer "In2.Cu")
		(net "M_A_DQ26")
	)
	(segment
		(start 160.687258 -49.2252)
		(end 160.382458 -49.2252)
		(width 0.1524)
		(layer "In2.Cu")
		(net "M_A_DQ26")
	)
	(segment
		(start 160.992058 -47.8536)
		(end 160.839658 -48.006)
		(width 0.1524)
		(layer "In2.Cu")
		(net "M_A_DQ26")
	)
	(segment
		(start 162.866578 -49.368964)
		(end 162.494214 -48.9966)
		(width 0.1524)
		(layer "In2.Cu")
		(net "M_A_DQ26")
	)
	(segment
		(start 156.9974 -48.8442)
		(end 156.845 -48.9966)
		(width 0.1524)
		(layer "In2.Cu")
		(net "M_A_DQ26")
	)
	(segment
		(start 154.02052 -48.509174)
		(end 153.785316 -48.27397)
		(width 0.1524)
		(layer "In2.Cu")
		(net "M_A_DQ26")
	)
	(segment
		(start 155.155138 -49.657)
		(end 154.305 -49.657)
		(width 0.1524)
		(layer "In2.Cu")
		(net "M_A_DQ26")
	)
	(segment
		(start 153.48077 -48.27397)
		(end 153.158444 -47.951644)
		(width 0.1524)
		(layer "In2.Cu")
		(net "M_A_DQ26")
	)
	(segment
		(start 118.3894 -45.72)
		(end 117.9322 -46.1772)
		(width 0.1016)
		(layer "In2.Cu")
		(net "M_A_DQ26")
	)
	(segment
		(start 154.02052 -49.37252)
		(end 154.02052 -48.509174)
		(width 0.1524)
		(layer "In2.Cu")
		(net "M_A_DQ26")
	)
	(segment
		(start 121.1072 -45.72)
		(end 118.3894 -45.72)
		(width 0.1016)
		(layer "In2.Cu")
		(net "M_A_DQ26")
	)
	(segment
		(start 152.9588 -46.9646)
		(end 152.3238 -46.9646)
		(width 0.1524)
		(layer "In2.Cu")
		(net "M_A_DQ26")
	)
	(segment
		(start 170.4594 -61.849)
		(end 170.4594 -59.052968)
		(width 0.1524)
		(layer "In2.Cu")
		(net "M_A_DQ26")
	)
	(segment
		(start 151.9936 -46.2788)
		(end 151.1554 -45.4406)
		(width 0.1524)
		(layer "In2.Cu")
		(net "M_A_DQ26")
	)
	(segment
		(start 159.468058 -49.2252)
		(end 159.163258 -49.2252)
		(width 0.1524)
		(layer "In2.Cu")
		(net "M_A_DQ26")
	)
	(segment
		(start 159.620458 -47.9806)
		(end 159.620458 -49.0728)
		(width 0.1524)
		(layer "In2.Cu")
		(net "M_A_DQ26")
	)
	(segment
		(start 159.010858 -49.0728)
		(end 159.010858 -47.9806)
		(width 0.1524)
		(layer "In2.Cu")
		(net "M_A_DQ26")
	)
	(segment
		(start 159.772858 -47.8282)
		(end 159.620458 -47.9806)
		(width 0.1524)
		(layer "In2.Cu")
		(net "M_A_DQ26")
	)
	(segment
		(start 160.230058 -47.9806)
		(end 160.077658 -47.8282)
		(width 0.1524)
		(layer "In2.Cu")
		(net "M_A_DQ26")
	)
	(segment
		(start 156.9974 -47.9806)
		(end 156.9974 -48.8442)
		(width 0.1524)
		(layer "In2.Cu")
		(net "M_A_DQ26")
	)
	(segment
		(start 157.5816 -47.9806)
		(end 157.4292 -47.8282)
		(width 0.1524)
		(layer "In2.Cu")
		(net "M_A_DQ26")
	)
	(segment
		(start 161.6202 -49.2252)
		(end 161.4678 -49.0728)
		(width 0.1524)
		(layer "In2.Cu")
		(net "M_A_DQ26")
	)
	(segment
		(start 156.2354 -47.8282)
		(end 155.4734 -47.8282)
		(width 0.1524)
		(layer "In2.Cu")
		(net "M_A_DQ26")
	)
	(segment
		(start 161.4678 -49.0728)
		(end 161.4678 -48.006)
		(width 0.1524)
		(layer "In2.Cu")
		(net "M_A_DQ26")
	)
	(segment
		(start 160.839658 -48.006)
		(end 160.839658 -49.0728)
		(width 0.1524)
		(layer "In2.Cu")
		(net "M_A_DQ26")
	)
	(segment
		(start 158.1658 -49.3522)
		(end 158.0134 -49.5046)
		(width 0.1524)
		(layer "In2.Cu")
		(net "M_A_DQ26")
	)
	(segment
		(start 170.4594 -59.052968)
		(end 162.866578 -51.460146)
		(width 0.1524)
		(layer "In2.Cu")
		(net "M_A_DQ26")
	)
	(segment
		(start 153.785316 -48.27397)
		(end 153.48077 -48.27397)
		(width 0.1524)
		(layer "In2.Cu")
		(net "M_A_DQ26")
	)
	(segment
		(start 159.620458 -49.0728)
		(end 159.468058 -49.2252)
		(width 0.1524)
		(layer "In2.Cu")
		(net "M_A_DQ26")
	)
	(segment
		(start 160.230058 -49.0728)
		(end 160.230058 -47.9806)
		(width 0.1524)
		(layer "In2.Cu")
		(net "M_A_DQ26")
	)
	(segment
		(start 151.1554 -45.4406)
		(end 121.3866 -45.4406)
		(width 0.1524)
		(layer "In2.Cu")
		(net "M_A_DQ26")
	)
	(segment
		(start 161.3154 -47.8536)
		(end 160.992058 -47.8536)
		(width 0.1524)
		(layer "In2.Cu")
		(net "M_A_DQ26")
	)
	(segment
		(start 154.305 -49.657)
		(end 154.02052 -49.37252)
		(width 0.1524)
		(layer "In2.Cu")
		(net "M_A_DQ26")
	)
	(segment
		(start 152.3238 -46.9646)
		(end 151.9936 -46.6344)
		(width 0.1524)
		(layer "In2.Cu")
		(net "M_A_DQ26")
	)
	(segment
		(start 158.0134 -49.5046)
		(end 157.734 -49.5046)
		(width 0.1524)
		(layer "In2.Cu")
		(net "M_A_DQ26")
	)
	(segment
		(start 156.5402 -48.9966)
		(end 156.3878 -48.8442)
		(width 0.1524)
		(layer "In2.Cu")
		(net "M_A_DQ26")
	)
	(segment
		(start 159.010858 -47.9806)
		(end 158.858458 -47.8282)
		(width 0.1524)
		(layer "In2.Cu")
		(net "M_A_DQ26")
	)
	(segment
		(start 157.1498 -47.8282)
		(end 156.9974 -47.9806)
		(width 0.1524)
		(layer "In2.Cu")
		(net "M_A_DQ26")
	)
	(segment
		(start 162.494214 -48.9966)
		(end 162.1536 -48.9966)
		(width 0.1524)
		(layer "In2.Cu")
		(net "M_A_DQ26")
	)
	(segment
		(start 160.077658 -47.8282)
		(end 159.772858 -47.8282)
		(width 0.1524)
		(layer "In2.Cu")
		(net "M_A_DQ26")
	)
	(segment
		(start 160.382458 -49.2252)
		(end 160.230058 -49.0728)
		(width 0.1524)
		(layer "In2.Cu")
		(net "M_A_DQ26")
	)
	(via
		(at 52.52466 -35.31616)
		(size 0.508)
		(drill 0.254)
		(layers "F.Cu" "B.Cu")
		(net "CLK_100M_CLKBUFF_DP")
	)
	(via
		(at 50.25263 -20.41144)
		(size 0.508)
		(drill 0.254)
		(layers "F.Cu" "B.Cu")
		(net "CLK_100M_CLKBUFF_DP")
	)
	(segment
		(start 52.832 -35.7886)
		(end 52.832 -35.6235)
		(width 0.1397)
		(layer "B.Cu")
		(net "CLK_100M_CLKBUFF_DP")
	)
	(segment
		(start 53.7337 -49.03216)
		(end 54.3052 -48.46066)
		(width 0.1397)
		(layer "B.Cu")
		(net "CLK_100M_CLKBUFF_DP")
	)
	(segment
		(start 52.832 -35.6235)
		(end 52.52466 -35.31616)
		(width 0.1397)
		(layer "B.Cu")
		(net "CLK_100M_CLKBUFF_DP")
	)
	(segment
		(start 52.6923 -45.40885)
		(end 52.6923 -40.978582)
		(width 0.1397)
		(layer "B.Cu")
		(net "CLK_100M_CLKBUFF_DP")
	)
	(segment
		(start 52.2478 -36.3728)
		(end 52.832 -35.7886)
		(width 0.1397)
		(layer "B.Cu")
		(net "CLK_100M_CLKBUFF_DP")
	)
	(segment
		(start 52.6923 -40.978582)
		(end 52.2478 -40.534082)
		(width 0.1397)
		(layer "B.Cu")
		(net "CLK_100M_CLKBUFF_DP")
	)
	(segment
		(start 50.02403 -19.31797)
		(end 49.94529 -19.39671)
		(width 0.1397)
		(layer "B.Cu")
		(net "CLK_100M_CLKBUFF_DP")
	)
	(segment
		(start 52.2478 -40.534082)
		(end 52.2478 -36.3728)
		(width 0.1397)
		(layer "B.Cu")
		(net "CLK_100M_CLKBUFF_DP")
	)
	(segment
		(start 54.3052 -48.46066)
		(end 54.3052 -47.02175)
		(width 0.1397)
		(layer "B.Cu")
		(net "CLK_100M_CLKBUFF_DP")
	)
	(segment
		(start 52.2478 -51.3715)
		(end 53.7337 -49.8856)
		(width 0.1397)
		(layer "B.Cu")
		(net "CLK_100M_CLKBUFF_DP")
	)
	(segment
		(start 49.94529 -19.39671)
		(end 49.94529 -20.1041)
		(width 0.1397)
		(layer "B.Cu")
		(net "CLK_100M_CLKBUFF_DP")
	)
	(segment
		(start 48.668178 -50.297334)
		(end 49.224438 -50.297334)
		(width 0.1397)
		(layer "B.Cu")
		(net "CLK_100M_CLKBUFF_DP")
	)
	(segment
		(start 54.3052 -47.02175)
		(end 52.6923 -45.40885)
		(width 0.1397)
		(layer "B.Cu")
		(net "CLK_100M_CLKBUFF_DP")
	)
	(segment
		(start 49.94529 -20.1041)
		(end 50.25263 -20.41144)
		(width 0.1397)
		(layer "B.Cu")
		(net "CLK_100M_CLKBUFF_DP")
	)
	(segment
		(start 50.298604 -51.3715)
		(end 52.2478 -51.3715)
		(width 0.1397)
		(layer "B.Cu")
		(net "CLK_100M_CLKBUFF_DP")
	)
	(segment
		(start 49.224438 -50.297334)
		(end 50.298604 -51.3715)
		(width 0.1397)
		(layer "B.Cu")
		(net "CLK_100M_CLKBUFF_DP")
	)
	(segment
		(start 53.7337 -49.8856)
		(end 53.7337 -49.03216)
		(width 0.1397)
		(layer "B.Cu")
		(net "CLK_100M_CLKBUFF_DP")
	)
	(segment
		(start 50.02403 -18.6563)
		(end 50.02403 -19.31797)
		(width 0.1397)
		(layer "B.Cu")
		(net "CLK_100M_CLKBUFF_DP")
	)
	(segment
		(start 50.654458 -24.251158)
		(end 50.654458 -23.908258)
		(width 0.1143)
		(layer "In2.Cu")
		(net "CLK_100M_CLKBUFF_DP")
	)
	(segment
		(start 50.654458 -33.095438)
		(end 50.867818 -32.882078)
		(width 0.1143)
		(layer "In2.Cu")
		(net "CLK_100M_CLKBUFF_DP")
	)
	(segment
		(start 52.838096 -35.797998)
		(end 52.704492 -35.931602)
		(width 0.1143)
		(layer "In2.Cu")
		(net "CLK_100M_CLKBUFF_DP")
	)
	(segment
		(start 50.654458 -26.476198)
		(end 50.654458 -26.133298)
		(width 0.1143)
		(layer "In2.Cu")
		(net "CLK_100M_CLKBUFF_DP")
	)
	(segment
		(start 52.838096 -35.629596)
		(end 52.838096 -35.797998)
		(width 0.1143)
		(layer "In2.Cu")
		(net "CLK_100M_CLKBUFF_DP")
	)
	(segment
		(start 50.654458 -25.363678)
		(end 50.654458 -25.020778)
		(width 0.1143)
		(layer "In2.Cu")
		(net "CLK_100M_CLKBUFF_DP")
	)
	(segment
		(start 50.1523 -22.489922)
		(end 50.1523 -22.147022)
		(width 0.1143)
		(layer "In2.Cu")
		(net "CLK_100M_CLKBUFF_DP")
	)
	(segment
		(start 50.654458 -31.213298)
		(end 50.654458 -30.870398)
		(width 0.1143)
		(layer "In2.Cu")
		(net "CLK_100M_CLKBUFF_DP")
	)
	(segment
		(start 50.867818 -31.426658)
		(end 50.654458 -31.213298)
		(width 0.1143)
		(layer "In2.Cu")
		(net "CLK_100M_CLKBUFF_DP")
	)
	(segment
		(start 50.867818 -25.919938)
		(end 50.867818 -25.577038)
		(width 0.1143)
		(layer "In2.Cu")
		(net "CLK_100M_CLKBUFF_DP")
	)
	(segment
		(start 50.867818 -24.807418)
		(end 50.867818 -24.464518)
		(width 0.1143)
		(layer "In2.Cu")
		(net "CLK_100M_CLKBUFF_DP")
	)
	(segment
		(start 50.654458 -29.757878)
		(end 50.867818 -29.544518)
		(width 0.1143)
		(layer "In2.Cu")
		(net "CLK_100M_CLKBUFF_DP")
	)
	(segment
		(start 50.654458 -32.325818)
		(end 50.654458 -31.982918)
		(width 0.1143)
		(layer "In2.Cu")
		(net "CLK_100M_CLKBUFF_DP")
	)
	(segment
		(start 52.071778 -35.718242)
		(end 51.728878 -35.718242)
		(width 0.1143)
		(layer "In2.Cu")
		(net "CLK_100M_CLKBUFF_DP")
	)
	(segment
		(start 49.93894 -21.933662)
		(end 49.93894 -20.72513)
		(width 0.1143)
		(layer "In2.Cu")
		(net "CLK_100M_CLKBUFF_DP")
	)
	(segment
		(start 50.654458 -26.133298)
		(end 50.867818 -25.919938)
		(width 0.1143)
		(layer "In2.Cu")
		(net "CLK_100M_CLKBUFF_DP")
	)
	(segment
		(start 50.867818 -29.544518)
		(end 50.867818 -29.201618)
		(width 0.1143)
		(layer "In2.Cu")
		(net "CLK_100M_CLKBUFF_DP")
	)
	(segment
		(start 50.867818 -30.314138)
		(end 50.654458 -30.100778)
		(width 0.1143)
		(layer "In2.Cu")
		(net "CLK_100M_CLKBUFF_DP")
	)
	(segment
		(start 50.1523 -22.147022)
		(end 49.93894 -21.933662)
		(width 0.1143)
		(layer "In2.Cu")
		(net "CLK_100M_CLKBUFF_DP")
	)
	(segment
		(start 50.654458 -23.908258)
		(end 49.93894 -23.19274)
		(width 0.1143)
		(layer "In2.Cu")
		(net "CLK_100M_CLKBUFF_DP")
	)
	(segment
		(start 50.654458 -27.245818)
		(end 50.867818 -27.032458)
		(width 0.1143)
		(layer "In2.Cu")
		(net "CLK_100M_CLKBUFF_DP")
	)
	(segment
		(start 51.728878 -35.718242)
		(end 51.515518 -35.931602)
		(width 0.1143)
		(layer "In2.Cu")
		(net "CLK_100M_CLKBUFF_DP")
	)
	(segment
		(start 52.704492 -35.931602)
		(end 52.285138 -35.931602)
		(width 0.1143)
		(layer "In2.Cu")
		(net "CLK_100M_CLKBUFF_DP")
	)
	(segment
		(start 50.867818 -32.539178)
		(end 50.654458 -32.325818)
		(width 0.1143)
		(layer "In2.Cu")
		(net "CLK_100M_CLKBUFF_DP")
	)
	(segment
		(start 51.172618 -35.931602)
		(end 50.654458 -35.413442)
		(width 0.1143)
		(layer "In2.Cu")
		(net "CLK_100M_CLKBUFF_DP")
	)
	(segment
		(start 50.867818 -24.464518)
		(end 50.654458 -24.251158)
		(width 0.1143)
		(layer "In2.Cu")
		(net "CLK_100M_CLKBUFF_DP")
	)
	(segment
		(start 50.654458 -30.870398)
		(end 50.867818 -30.657038)
		(width 0.1143)
		(layer "In2.Cu")
		(net "CLK_100M_CLKBUFF_DP")
	)
	(segment
		(start 49.93894 -23.19274)
		(end 49.93894 -22.703282)
		(width 0.1143)
		(layer "In2.Cu")
		(net "CLK_100M_CLKBUFF_DP")
	)
	(segment
		(start 50.867818 -30.657038)
		(end 50.867818 -30.314138)
		(width 0.1143)
		(layer "In2.Cu")
		(net "CLK_100M_CLKBUFF_DP")
	)
	(segment
		(start 52.285138 -35.931602)
		(end 52.071778 -35.718242)
		(width 0.1143)
		(layer "In2.Cu")
		(net "CLK_100M_CLKBUFF_DP")
	)
	(segment
		(start 51.515518 -35.931602)
		(end 51.172618 -35.931602)
		(width 0.1143)
		(layer "In2.Cu")
		(net "CLK_100M_CLKBUFF_DP")
	)
	(segment
		(start 50.867818 -31.769558)
		(end 50.867818 -31.426658)
		(width 0.1143)
		(layer "In2.Cu")
		(net "CLK_100M_CLKBUFF_DP")
	)
	(segment
		(start 50.654458 -30.100778)
		(end 50.654458 -29.757878)
		(width 0.1143)
		(layer "In2.Cu")
		(net "CLK_100M_CLKBUFF_DP")
	)
	(segment
		(start 52.52466 -35.31616)
		(end 52.838096 -35.629596)
		(width 0.1143)
		(layer "In2.Cu")
		(net "CLK_100M_CLKBUFF_DP")
	)
	(segment
		(start 50.654458 -35.413442)
		(end 50.654458 -33.095438)
		(width 0.1143)
		(layer "In2.Cu")
		(net "CLK_100M_CLKBUFF_DP")
	)
	(segment
		(start 49.93894 -22.703282)
		(end 50.1523 -22.489922)
		(width 0.1143)
		(layer "In2.Cu")
		(net "CLK_100M_CLKBUFF_DP")
	)
	(segment
		(start 50.867818 -32.882078)
		(end 50.867818 -32.539178)
		(width 0.1143)
		(layer "In2.Cu")
		(net "CLK_100M_CLKBUFF_DP")
	)
	(segment
		(start 50.867818 -29.201618)
		(end 50.654458 -28.988258)
		(width 0.1143)
		(layer "In2.Cu")
		(net "CLK_100M_CLKBUFF_DP")
	)
	(segment
		(start 50.867818 -26.689558)
		(end 50.654458 -26.476198)
		(width 0.1143)
		(layer "In2.Cu")
		(net "CLK_100M_CLKBUFF_DP")
	)
	(segment
		(start 50.867818 -27.032458)
		(end 50.867818 -26.689558)
		(width 0.1143)
		(layer "In2.Cu")
		(net "CLK_100M_CLKBUFF_DP")
	)
	(segment
		(start 50.654458 -28.988258)
		(end 50.654458 -27.245818)
		(width 0.1143)
		(layer "In2.Cu")
		(net "CLK_100M_CLKBUFF_DP")
	)
	(segment
		(start 50.654458 -31.982918)
		(end 50.867818 -31.769558)
		(width 0.1143)
		(layer "In2.Cu")
		(net "CLK_100M_CLKBUFF_DP")
	)
	(segment
		(start 50.654458 -25.020778)
		(end 50.867818 -24.807418)
		(width 0.1143)
		(layer "In2.Cu")
		(net "CLK_100M_CLKBUFF_DP")
	)
	(segment
		(start 49.93894 -20.72513)
		(end 50.25263 -20.41144)
		(width 0.1143)
		(layer "In2.Cu")
		(net "CLK_100M_CLKBUFF_DP")
	)
	(segment
		(start 50.867818 -25.577038)
		(end 50.654458 -25.363678)
		(width 0.1143)
		(layer "In2.Cu")
		(net "CLK_100M_CLKBUFF_DP")
	)
	(segment
		(start 100.6348 -49.4538)
		(end 100.6094 -49.4538)
		(width 0.1016)
		(layer "F.Cu")
		(net "M_A_ODT2")
	)
	(segment
		(start 150.6474 -63.842138)
		(end 150.6474 -64.31534)
		(width 0.1778)
		(layer "F.Cu")
		(net "M_A_ODT2")
	)
	(segment
		(start 150.250144 -63.444882)
		(end 150.6474 -63.842138)
		(width 0.1778)
		(layer "F.Cu")
		(net "M_A_ODT2")
	)
	(segment
		(start 100.5332 -49.3776)
		(end 100.221542 -49.3776)
		(width 0.1016)
		(layer "F.Cu")
		(net "M_A_ODT2")
	)
	(segment
		(start 100.6094 -49.4538)
		(end 100.5332 -49.3776)
		(width 0.1016)
		(layer "F.Cu")
		(net "M_A_ODT2")
	)
	(segment
		(start 150.250144 -62.59322)
		(end 150.250144 -63.444882)
		(width 0.1778)
		(layer "F.Cu")
		(net "M_A_ODT2")
	)
	(segment
		(start 100.221542 -49.3776)
		(end 100.053648 -49.545494)
		(width 0.1016)
		(layer "F.Cu")
		(net "M_A_ODT2")
	)
	(segment
		(start 150.6474 -64.31534)
		(end 150.1902 -64.77254)
		(width 0.1778)
		(layer "F.Cu")
		(net "M_A_ODT2")
	)
	(via
		(at 150.1902 -64.77254)
		(size 0.4318)
		(drill 0.2032)
		(layers "F.Cu" "B.Cu")
		(net "M_A_ODT2")
	)
	(via
		(at 100.6348 -49.4538)
		(size 0.4318)
		(drill 0.2032)
		(layers "F.Cu" "B.Cu")
		(net "M_A_ODT2")
	)
	(segment
		(start 145.0594 -60.1472)
		(end 145.0594 -61.2648)
		(width 0.1524)
		(layer "In7.Cu")
		(net "M_A_ODT2")
	)
	(segment
		(start 103.1748 -54.1274)
		(end 102.616 -53.5686)
		(width 0.1524)
		(layer "In7.Cu")
		(net "M_A_ODT2")
	)
	(segment
		(start 103.54945 -58.15965)
		(end 103.1748 -57.785)
		(width 0.1524)
		(layer "In7.Cu")
		(net "M_A_ODT2")
	)
	(segment
		(start 120.803924 -57.912)
		(end 120.556274 -58.15965)
		(width 0.1524)
		(layer "In7.Cu")
		(net "M_A_ODT2")
	)
	(segment
		(start 103.1748 -57.785)
		(end 103.1748 -54.1274)
		(width 0.1524)
		(layer "In7.Cu")
		(net "M_A_ODT2")
	)
	(segment
		(start 141.031722 -60.183522)
		(end 140.815822 -59.967622)
		(width 0.1524)
		(layer "In7.Cu")
		(net "M_A_ODT2")
	)
	(segment
		(start 143.9926 -59.9948)
		(end 143.8402 -60.1472)
		(width 0.1524)
		(layer "In7.Cu")
		(net "M_A_ODT2")
	)
	(segment
		(start 136.12495 -57.912)
		(end 135.7122 -57.912)
		(width 0.1524)
		(layer "In7.Cu")
		(net "M_A_ODT2")
	)
	(segment
		(start 124.740924 -57.912)
		(end 124.588524 -57.7596)
		(width 0.1524)
		(layer "In7.Cu")
		(net "M_A_ODT2")
	)
	(segment
		(start 142.2654 -60.1218)
		(end 142.113 -60.2742)
		(width 0.1524)
		(layer "In7.Cu")
		(net "M_A_ODT2")
	)
	(segment
		(start 121.388124 -57.912)
		(end 120.803924 -57.912)
		(width 0.1524)
		(layer "In7.Cu")
		(net "M_A_ODT2")
	)
	(segment
		(start 100.6348 -49.4538)
		(end 100.6348 -49.5046)
		(width 0.1016)
		(layer "In7.Cu")
		(net "M_A_ODT2")
	)
	(segment
		(start 150.1902 -64.77254)
		(end 149.718268 -64.300608)
		(width 0.1524)
		(layer "In7.Cu")
		(net "M_A_ODT2")
	)
	(segment
		(start 122.759724 -57.2008)
		(end 122.759724 -57.7596)
		(width 0.1524)
		(layer "In7.Cu")
		(net "M_A_ODT2")
	)
	(segment
		(start 141.224 -61.4172)
		(end 140.726414 -60.919614)
		(width 0.1524)
		(layer "In7.Cu")
		(net "M_A_ODT2")
	)
	(segment
		(start 121.540524 -57.2008)
		(end 121.540524 -57.7596)
		(width 0.1524)
		(layer "In7.Cu")
		(net "M_A_ODT2")
	)
	(segment
		(start 140.815822 -59.967622)
		(end 140.60043 -59.967622)
		(width 0.1524)
		(layer "In7.Cu")
		(net "M_A_ODT2")
	)
	(segment
		(start 135.7122 -57.912)
		(end 135.5852 -57.785)
		(width 0.1524)
		(layer "In7.Cu")
		(net "M_A_ODT2")
	)
	(segment
		(start 144.4498 -61.2648)
		(end 144.4498 -60.1472)
		(width 0.1524)
		(layer "In7.Cu")
		(net "M_A_ODT2")
	)
	(segment
		(start 143.8402 -60.1472)
		(end 143.8402 -61.2648)
		(width 0.1524)
		(layer "In7.Cu")
		(net "M_A_ODT2")
	)
	(segment
		(start 135.5852 -57.785)
		(end 135.5852 -57.658)
		(width 0.1524)
		(layer "In7.Cu")
		(net "M_A_ODT2")
	)
	(segment
		(start 145.5166 -59.9948)
		(end 145.2118 -59.9948)
		(width 0.1524)
		(layer "In7.Cu")
		(net "M_A_ODT2")
	)
	(segment
		(start 142.113 -61.214)
		(end 141.9098 -61.4172)
		(width 0.1524)
		(layer "In7.Cu")
		(net "M_A_ODT2")
	)
	(segment
		(start 141.031722 -60.398914)
		(end 141.031722 -60.183522)
		(width 0.1524)
		(layer "In7.Cu")
		(net "M_A_ODT2")
	)
	(segment
		(start 124.588524 -57.7596)
		(end 124.588524 -57.2008)
		(width 0.1524)
		(layer "In7.Cu")
		(net "M_A_ODT2")
	)
	(segment
		(start 121.997724 -57.0484)
		(end 121.692924 -57.0484)
		(width 0.1524)
		(layer "In7.Cu")
		(net "M_A_ODT2")
	)
	(segment
		(start 136.27735 -57.7596)
		(end 136.12495 -57.912)
		(width 0.1524)
		(layer "In7.Cu")
		(net "M_A_ODT2")
	)
	(segment
		(start 149.718268 -63.87084)
		(end 147.264628 -61.4172)
		(width 0.1524)
		(layer "In7.Cu")
		(net "M_A_ODT2")
	)
	(segment
		(start 123.978924 -57.7596)
		(end 123.826524 -57.912)
		(width 0.1524)
		(layer "In7.Cu")
		(net "M_A_ODT2")
	)
	(segment
		(start 142.6464 -61.1378)
		(end 142.6464 -60.2742)
		(width 0.1524)
		(layer "In7.Cu")
		(net "M_A_ODT2")
	)
	(segment
		(start 140.60043 -59.967622)
		(end 140.295122 -60.27293)
		(width 0.1524)
		(layer "In7.Cu")
		(net "M_A_ODT2")
	)
	(segment
		(start 124.436124 -57.0484)
		(end 124.131324 -57.0484)
		(width 0.1524)
		(layer "In7.Cu")
		(net "M_A_ODT2")
	)
	(segment
		(start 145.2118 -59.9948)
		(end 145.0594 -60.1472)
		(width 0.1524)
		(layer "In7.Cu")
		(net "M_A_ODT2")
	)
	(segment
		(start 122.607324 -57.912)
		(end 122.302524 -57.912)
		(width 0.1524)
		(layer "In7.Cu")
		(net "M_A_ODT2")
	)
	(segment
		(start 147.264628 -61.4172)
		(end 145.8214 -61.4172)
		(width 0.1524)
		(layer "In7.Cu")
		(net "M_A_ODT2")
	)
	(segment
		(start 124.131324 -57.0484)
		(end 123.978924 -57.2008)
		(width 0.1524)
		(layer "In7.Cu")
		(net "M_A_ODT2")
	)
	(segment
		(start 144.6022 -61.4172)
		(end 144.4498 -61.2648)
		(width 0.1524)
		(layer "In7.Cu")
		(net "M_A_ODT2")
	)
	(segment
		(start 135.5852 -57.658)
		(end 135.3312 -57.404)
		(width 0.1524)
		(layer "In7.Cu")
		(net "M_A_ODT2")
	)
	(segment
		(start 135.3312 -57.404)
		(end 134.557262 -57.404)
		(width 0.1524)
		(layer "In7.Cu")
		(net "M_A_ODT2")
	)
	(segment
		(start 140.726414 -60.919614)
		(end 140.726414 -60.704222)
		(width 0.1524)
		(layer "In7.Cu")
		(net "M_A_ODT2")
	)
	(segment
		(start 145.669 -60.1472)
		(end 145.5166 -59.9948)
		(width 0.1524)
		(layer "In7.Cu")
		(net "M_A_ODT2")
	)
	(segment
		(start 143.6878 -61.4172)
		(end 142.9258 -61.4172)
		(width 0.1524)
		(layer "In7.Cu")
		(net "M_A_ODT2")
	)
	(segment
		(start 100.7364 -51.689)
		(end 102.616 -53.5686)
		(width 0.1016)
		(layer "In7.Cu")
		(net "M_A_ODT2")
	)
	(segment
		(start 100.7364 -49.6062)
		(end 100.7364 -51.689)
		(width 0.1016)
		(layer "In7.Cu")
		(net "M_A_ODT2")
	)
	(segment
		(start 142.9258 -61.4172)
		(end 142.6464 -61.1378)
		(width 0.1524)
		(layer "In7.Cu")
		(net "M_A_ODT2")
	)
	(segment
		(start 123.978924 -57.2008)
		(end 123.978924 -57.7596)
		(width 0.1524)
		(layer "In7.Cu")
		(net "M_A_ODT2")
	)
	(segment
		(start 122.759724 -57.7596)
		(end 122.607324 -57.912)
		(width 0.1524)
		(layer "In7.Cu")
		(net "M_A_ODT2")
	)
	(segment
		(start 140.726414 -60.704222)
		(end 141.031722 -60.398914)
		(width 0.1524)
		(layer "In7.Cu")
		(net "M_A_ODT2")
	)
	(segment
		(start 121.692924 -57.0484)
		(end 121.540524 -57.2008)
		(width 0.1524)
		(layer "In7.Cu")
		(net "M_A_ODT2")
	)
	(segment
		(start 142.494 -60.1218)
		(end 142.2654 -60.1218)
		(width 0.1524)
		(layer "In7.Cu")
		(net "M_A_ODT2")
	)
	(segment
		(start 122.912124 -57.0484)
		(end 122.759724 -57.2008)
		(width 0.1524)
		(layer "In7.Cu")
		(net "M_A_ODT2")
	)
	(segment
		(start 145.8214 -61.4172)
		(end 145.669 -61.2648)
		(width 0.1524)
		(layer "In7.Cu")
		(net "M_A_ODT2")
	)
	(segment
		(start 141.9098 -61.4172)
		(end 141.224 -61.4172)
		(width 0.1524)
		(layer "In7.Cu")
		(net "M_A_ODT2")
	)
	(segment
		(start 123.521724 -57.912)
		(end 123.369324 -57.7596)
		(width 0.1524)
		(layer "In7.Cu")
		(net "M_A_ODT2")
	)
	(segment
		(start 134.557262 -57.404)
		(end 134.049262 -57.912)
		(width 0.1524)
		(layer "In7.Cu")
		(net "M_A_ODT2")
	)
	(segment
		(start 144.4498 -60.1472)
		(end 144.2974 -59.9948)
		(width 0.1524)
		(layer "In7.Cu")
		(net "M_A_ODT2")
	)
	(segment
		(start 122.150124 -57.7596)
		(end 122.150124 -57.2008)
		(width 0.1524)
		(layer "In7.Cu")
		(net "M_A_ODT2")
	)
	(segment
		(start 123.216924 -57.0484)
		(end 122.912124 -57.0484)
		(width 0.1524)
		(layer "In7.Cu")
		(net "M_A_ODT2")
	)
	(segment
		(start 120.556274 -58.15965)
		(end 103.54945 -58.15965)
		(width 0.1524)
		(layer "In7.Cu")
		(net "M_A_ODT2")
	)
	(segment
		(start 143.8402 -61.2648)
		(end 143.6878 -61.4172)
		(width 0.1524)
		(layer "In7.Cu")
		(net "M_A_ODT2")
	)
	(segment
		(start 123.369324 -57.7596)
		(end 123.369324 -57.2008)
		(width 0.1524)
		(layer "In7.Cu")
		(net "M_A_ODT2")
	)
	(segment
		(start 144.907 -61.4172)
		(end 144.6022 -61.4172)
		(width 0.1524)
		(layer "In7.Cu")
		(net "M_A_ODT2")
	)
	(segment
		(start 149.718268 -64.300608)
		(end 149.718268 -63.87084)
		(width 0.1524)
		(layer "In7.Cu")
		(net "M_A_ODT2")
	)
	(segment
		(start 123.826524 -57.912)
		(end 123.521724 -57.912)
		(width 0.1524)
		(layer "In7.Cu")
		(net "M_A_ODT2")
	)
	(segment
		(start 121.540524 -57.7596)
		(end 121.388124 -57.912)
		(width 0.1524)
		(layer "In7.Cu")
		(net "M_A_ODT2")
	)
	(segment
		(start 134.049262 -57.912)
		(end 124.740924 -57.912)
		(width 0.1524)
		(layer "In7.Cu")
		(net "M_A_ODT2")
	)
	(segment
		(start 142.113 -60.2742)
		(end 142.113 -61.214)
		(width 0.1524)
		(layer "In7.Cu")
		(net "M_A_ODT2")
	)
	(segment
		(start 123.369324 -57.2008)
		(end 123.216924 -57.0484)
		(width 0.1524)
		(layer "In7.Cu")
		(net "M_A_ODT2")
	)
	(segment
		(start 136.27735 -57.19445)
		(end 136.27735 -57.7596)
		(width 0.1524)
		(layer "In7.Cu")
		(net "M_A_ODT2")
	)
	(segment
		(start 124.588524 -57.2008)
		(end 124.436124 -57.0484)
		(width 0.1524)
		(layer "In7.Cu")
		(net "M_A_ODT2")
	)
	(segment
		(start 142.6464 -60.2742)
		(end 142.494 -60.1218)
		(width 0.1524)
		(layer "In7.Cu")
		(net "M_A_ODT2")
	)
	(segment
		(start 140.295122 -60.27293)
		(end 140.07973 -60.27293)
		(width 0.1524)
		(layer "In7.Cu")
		(net "M_A_ODT2")
	)
	(segment
		(start 140.07973 -60.27293)
		(end 136.8806 -57.0738)
		(width 0.1524)
		(layer "In7.Cu")
		(net "M_A_ODT2")
	)
	(segment
		(start 122.150124 -57.2008)
		(end 121.997724 -57.0484)
		(width 0.1524)
		(layer "In7.Cu")
		(net "M_A_ODT2")
	)
	(segment
		(start 145.0594 -61.2648)
		(end 144.907 -61.4172)
		(width 0.1524)
		(layer "In7.Cu")
		(net "M_A_ODT2")
	)
	(segment
		(start 136.8806 -57.0738)
		(end 136.398 -57.0738)
		(width 0.1524)
		(layer "In7.Cu")
		(net "M_A_ODT2")
	)
	(segment
		(start 144.2974 -59.9948)
		(end 143.9926 -59.9948)
		(width 0.1524)
		(layer "In7.Cu")
		(net "M_A_ODT2")
	)
	(segment
		(start 136.398 -57.0738)
		(end 136.27735 -57.19445)
		(width 0.1524)
		(layer "In7.Cu")
		(net "M_A_ODT2")
	)
	(segment
		(start 100.6348 -49.5046)
		(end 100.7364 -49.6062)
		(width 0.1016)
		(layer "In7.Cu")
		(net "M_A_ODT2")
	)
	(segment
		(start 145.669 -61.2648)
		(end 145.669 -60.1472)
		(width 0.1524)
		(layer "In7.Cu")
		(net "M_A_ODT2")
	)
	(segment
		(start 122.302524 -57.912)
		(end 122.150124 -57.7596)
		(width 0.1524)
		(layer "In7.Cu")
		(net "M_A_ODT2")
	)
	(via
		(at 49.29505 -20.41144)
		(size 0.508)
		(drill 0.254)
		(layers "F.Cu" "B.Cu")
		(net "CLK_100M_CLKBUFF_DN")
	)
	(via
		(at 53.478938 -35.313112)
		(size 0.508)
		(drill 0.254)
		(layers "F.Cu" "B.Cu")
		(net "CLK_100M_CLKBUFF_DN")
	)
	(segment
		(start 52.5907 -40.391842)
		(end 52.5907 -36.51504)
		(width 0.1397)
		(layer "B.Cu")
		(net "CLK_100M_CLKBUFF_DN")
	)
	(segment
		(start 53.0352 -45.26661)
		(end 53.0352 -40.836342)
		(width 0.1397)
		(layer "B.Cu")
		(net "CLK_100M_CLKBUFF_DN")
	)
	(segment
		(start 49.52365 -19.29765)
		(end 49.60239 -19.37639)
		(width 0.1397)
		(layer "B.Cu")
		(net "CLK_100M_CLKBUFF_DN")
	)
	(segment
		(start 52.5907 -36.51504)
		(end 53.1749 -35.93084)
		(width 0.1397)
		(layer "B.Cu")
		(net "CLK_100M_CLKBUFF_DN")
	)
	(segment
		(start 54.6481 -48.6029)
		(end 54.6481 -46.87951)
		(width 0.1397)
		(layer "B.Cu")
		(net "CLK_100M_CLKBUFF_DN")
	)
	(segment
		(start 49.139348 -50.697384)
		(end 50.156364 -51.7144)
		(width 0.1397)
		(layer "B.Cu")
		(net "CLK_100M_CLKBUFF_DN")
	)
	(segment
		(start 50.156364 -51.7144)
		(end 52.39004 -51.7144)
		(width 0.1397)
		(layer "B.Cu")
		(net "CLK_100M_CLKBUFF_DN")
	)
	(segment
		(start 54.6481 -46.87951)
		(end 53.0352 -45.26661)
		(width 0.1397)
		(layer "B.Cu")
		(net "CLK_100M_CLKBUFF_DN")
	)
	(segment
		(start 54.0766 -49.1744)
		(end 54.6481 -48.6029)
		(width 0.1397)
		(layer "B.Cu")
		(net "CLK_100M_CLKBUFF_DN")
	)
	(segment
		(start 53.1749 -35.61715)
		(end 53.478938 -35.313112)
		(width 0.1397)
		(layer "B.Cu")
		(net "CLK_100M_CLKBUFF_DN")
	)
	(segment
		(start 49.52365 -18.6563)
		(end 49.52365 -19.29765)
		(width 0.1397)
		(layer "B.Cu")
		(net "CLK_100M_CLKBUFF_DN")
	)
	(segment
		(start 49.60239 -19.37639)
		(end 49.60239 -20.1041)
		(width 0.1397)
		(layer "B.Cu")
		(net "CLK_100M_CLKBUFF_DN")
	)
	(segment
		(start 52.39004 -51.7144)
		(end 54.0766 -50.02784)
		(width 0.1397)
		(layer "B.Cu")
		(net "CLK_100M_CLKBUFF_DN")
	)
	(segment
		(start 53.1749 -35.93084)
		(end 53.1749 -35.61715)
		(width 0.1397)
		(layer "B.Cu")
		(net "CLK_100M_CLKBUFF_DN")
	)
	(segment
		(start 54.0766 -50.02784)
		(end 54.0766 -49.1744)
		(width 0.1397)
		(layer "B.Cu")
		(net "CLK_100M_CLKBUFF_DN")
	)
	(segment
		(start 49.60239 -20.1041)
		(end 49.29505 -20.41144)
		(width 0.1397)
		(layer "B.Cu")
		(net "CLK_100M_CLKBUFF_DN")
	)
	(segment
		(start 48.668178 -50.697384)
		(end 49.139348 -50.697384)
		(width 0.1397)
		(layer "B.Cu")
		(net "CLK_100M_CLKBUFF_DN")
	)
	(segment
		(start 53.0352 -40.836342)
		(end 52.5907 -40.391842)
		(width 0.1397)
		(layer "B.Cu")
		(net "CLK_100M_CLKBUFF_DN")
	)
	(segment
		(start 51.035712 -36.261802)
		(end 52.841398 -36.261802)
		(width 0.1143)
		(layer "In2.Cu")
		(net "CLK_100M_CLKBUFF_DN")
	)
	(segment
		(start 49.60874 -23.329646)
		(end 50.324258 -24.045164)
		(width 0.1143)
		(layer "In2.Cu")
		(net "CLK_100M_CLKBUFF_DN")
	)
	(segment
		(start 49.29505 -20.41144)
		(end 49.60874 -20.72513)
		(width 0.1143)
		(layer "In2.Cu")
		(net "CLK_100M_CLKBUFF_DN")
	)
	(segment
		(start 50.324258 -35.550348)
		(end 51.035712 -36.261802)
		(width 0.1143)
		(layer "In2.Cu")
		(net "CLK_100M_CLKBUFF_DN")
	)
	(segment
		(start 52.841398 -36.261802)
		(end 53.168296 -35.934904)
		(width 0.1143)
		(layer "In2.Cu")
		(net "CLK_100M_CLKBUFF_DN")
	)
	(segment
		(start 49.60874 -20.72513)
		(end 49.60874 -23.329646)
		(width 0.1143)
		(layer "In2.Cu")
		(net "CLK_100M_CLKBUFF_DN")
	)
	(segment
		(start 53.168296 -35.934904)
		(end 53.168296 -35.623754)
		(width 0.1143)
		(layer "In2.Cu")
		(net "CLK_100M_CLKBUFF_DN")
	)
	(segment
		(start 50.324258 -24.045164)
		(end 50.324258 -35.550348)
		(width 0.1143)
		(layer "In2.Cu")
		(net "CLK_100M_CLKBUFF_DN")
	)
	(segment
		(start 53.168296 -35.623754)
		(end 53.478938 -35.313112)
		(width 0.1143)
		(layer "In2.Cu")
		(net "CLK_100M_CLKBUFF_DN")
	)
	(segment
		(start 162.05962 -66.12636)
		(end 162.060128 -66.126868)
		(width 0.2413)
		(layer "F.Cu")
		(net "M_A_MA14")
	)
	(segment
		(start 161.04997 -63.35903)
		(end 160.823148 -63.585852)
		(width 0.2413)
		(layer "F.Cu")
		(net "M_A_MA14")
	)
	(segment
		(start 162.05962 -65.79362)
		(end 162.05962 -66.12636)
		(width 0.2413)
		(layer "F.Cu")
		(net "M_A_MA14")
	)
	(segment
		(start 106.807254 -46.914054)
		(end 106.3244 -46.4312)
		(width 0.1016)
		(layer "F.Cu")
		(net "M_A_MA14")
	)
	(segment
		(start 106.909108 -46.914054)
		(end 106.807254 -46.914054)
		(width 0.1016)
		(layer "F.Cu")
		(net "M_A_MA14")
	)
	(segment
		(start 161.398458 -65.132458)
		(end 162.05962 -65.79362)
		(width 0.2413)
		(layer "F.Cu")
		(net "M_A_MA14")
	)
	(segment
		(start 160.823148 -64.807846)
		(end 161.14776 -65.132458)
		(width 0.2413)
		(layer "F.Cu")
		(net "M_A_MA14")
	)
	(segment
		(start 161.04997 -62.59322)
		(end 161.04997 -63.35903)
		(width 0.2413)
		(layer "F.Cu")
		(net "M_A_MA14")
	)
	(segment
		(start 161.14776 -65.132458)
		(end 161.398458 -65.132458)
		(width 0.2413)
		(layer "F.Cu")
		(net "M_A_MA14")
	)
	(segment
		(start 160.823148 -63.585852)
		(end 160.823148 -64.807846)
		(width 0.2413)
		(layer "F.Cu")
		(net "M_A_MA14")
	)
	(via
		(at 106.3244 -46.4312)
		(size 0.4318)
		(drill 0.2032)
		(layers "F.Cu" "B.Cu")
		(net "M_A_MA14")
	)
	(via
		(at 162.060128 -66.126868)
		(size 0.4318)
		(drill 0.2032)
		(layers "F.Cu" "B.Cu")
		(net "M_A_MA14")
	)
	(segment
		(start 161.58337 -66.564002)
		(end 162.020504 -66.126868)
		(width 0.2413)
		(layer "B.Cu")
		(net "M_A_MA14")
	)
	(segment
		(start 161.04997 -68.13423)
		(end 161.58337 -67.60083)
		(width 0.2413)
		(layer "B.Cu")
		(net "M_A_MA14")
	)
	(segment
		(start 161.04997 -70.79996)
		(end 161.04997 -68.13423)
		(width 0.2413)
		(layer "B.Cu")
		(net "M_A_MA14")
	)
	(segment
		(start 161.58337 -67.60083)
		(end 161.58337 -66.564002)
		(width 0.2413)
		(layer "B.Cu")
		(net "M_A_MA14")
	)
	(segment
		(start 162.020504 -66.126868)
		(end 162.060128 -66.126868)
		(width 0.2413)
		(layer "B.Cu")
		(net "M_A_MA14")
	)
	(segment
		(start 162.060128 -66.126868)
		(end 162.05962 -66.12636)
		(width 0.1905)
		(layer "In9.Cu")
		(net "M_A_MA14")
	)
	(segment
		(start 106.330496 -46.437296)
		(end 106.3244 -46.4312)
		(width 0.1016)
		(layer "In9.Cu")
		(net "M_A_MA14")
	)
	(segment
		(start 162.05962 -65.458848)
		(end 161.802572 -65.2018)
		(width 0.1905)
		(layer "In9.Cu")
		(net "M_A_MA14")
	)
	(segment
		(start 110.661704 -46.437296)
		(end 106.330496 -46.437296)
		(width 0.1016)
		(layer "In9.Cu")
		(net "M_A_MA14")
	)
	(segment
		(start 150.979632 -46.0756)
		(end 125.0696 -46.0756)
		(width 0.1905)
		(layer "In9.Cu")
		(net "M_A_MA14")
	)
	(segment
		(start 117.4115 -45.9232)
		(end 111.1758 -45.9232)
		(width 0.1016)
		(layer "In9.Cu")
		(net "M_A_MA14")
	)
	(segment
		(start 162.1536 -57.249568)
		(end 150.979632 -46.0756)
		(width 0.1905)
		(layer "In9.Cu")
		(net "M_A_MA14")
	)
	(segment
		(start 124.7394 -45.7454)
		(end 117.5893 -45.7454)
		(width 0.1905)
		(layer "In9.Cu")
		(net "M_A_MA14")
	)
	(segment
		(start 125.0696 -46.0756)
		(end 124.7394 -45.7454)
		(width 0.1905)
		(layer "In9.Cu")
		(net "M_A_MA14")
	)
	(segment
		(start 161.802572 -65.2018)
		(end 161.802572 -63.862966)
		(width 0.1905)
		(layer "In9.Cu")
		(net "M_A_MA14")
	)
	(segment
		(start 162.05962 -66.12636)
		(end 162.05962 -65.458848)
		(width 0.1905)
		(layer "In9.Cu")
		(net "M_A_MA14")
	)
	(segment
		(start 117.5893 -45.7454)
		(end 117.4115 -45.9232)
		(width 0.1016)
		(layer "In9.Cu")
		(net "M_A_MA14")
	)
	(segment
		(start 111.1758 -45.9232)
		(end 110.661704 -46.437296)
		(width 0.1016)
		(layer "In9.Cu")
		(net "M_A_MA14")
	)
	(segment
		(start 162.1536 -63.511938)
		(end 162.1536 -57.249568)
		(width 0.1905)
		(layer "In9.Cu")
		(net "M_A_MA14")
	)
	(segment
		(start 161.802572 -63.862966)
		(end 162.1536 -63.511938)
		(width 0.1905)
		(layer "In9.Cu")
		(net "M_A_MA14")
	)
	(segment
		(start 87.434928 -46.497494)
		(end 87.303102 -46.62932)
		(width 0.1397)
		(layer "F.Cu")
		(net "CLK_96M_CPU_USB_DP")
	)
	(segment
		(start 87.303102 -46.62932)
		(end 87.303102 -46.776386)
		(width 0.1397)
		(layer "F.Cu")
		(net "CLK_96M_CPU_USB_DP")
	)
	(segment
		(start 87.303102 -46.776386)
		(end 86.927182 -47.152306)
		(width 0.1397)
		(layer "F.Cu")
		(net "CLK_96M_CPU_USB_DP")
	)
	(via
		(at 60.990226 -46.734222)
		(size 0.508)
		(drill 0.254)
		(layers "F.Cu" "B.Cu")
		(net "CLK_96M_CPU_USB_DP")
	)
	(via
		(at 86.927182 -47.152306)
		(size 0.4318)
		(drill 0.2032)
		(layers "F.Cu" "B.Cu")
		(net "CLK_96M_CPU_USB_DP")
	)
	(segment
		(start 47.93996 -54.8513)
		(end 56.22544 -54.8513)
		(width 0.1397)
		(layer "B.Cu")
		(net "CLK_96M_CPU_USB_DP")
	)
	(segment
		(start 56.22544 -54.8513)
		(end 57.9374 -53.13934)
		(width 0.1397)
		(layer "B.Cu")
		(net "CLK_96M_CPU_USB_DP")
	)
	(segment
		(start 59.9313 -46.4947)
		(end 60.750704 -46.4947)
		(width 0.1397)
		(layer "B.Cu")
		(net "CLK_96M_CPU_USB_DP")
	)
	(segment
		(start 46.058582 -51.70678)
		(end 46.058582 -52.400962)
		(width 0.1397)
		(layer "B.Cu")
		(net "CLK_96M_CPU_USB_DP")
	)
	(segment
		(start 46.70425 -53.04663)
		(end 46.70425 -53.61559)
		(width 0.1397)
		(layer "B.Cu")
		(net "CLK_96M_CPU_USB_DP")
	)
	(segment
		(start 57.9374 -48.4886)
		(end 59.9313 -46.4947)
		(width 0.1397)
		(layer "B.Cu")
		(net "CLK_96M_CPU_USB_DP")
	)
	(segment
		(start 46.70425 -53.61559)
		(end 47.93996 -54.8513)
		(width 0.1397)
		(layer "B.Cu")
		(net "CLK_96M_CPU_USB_DP")
	)
	(segment
		(start 57.9374 -53.13934)
		(end 57.9374 -48.4886)
		(width 0.1397)
		(layer "B.Cu")
		(net "CLK_96M_CPU_USB_DP")
	)
	(segment
		(start 46.058582 -52.400962)
		(end 46.70425 -53.04663)
		(width 0.1397)
		(layer "B.Cu")
		(net "CLK_96M_CPU_USB_DP")
	)
	(segment
		(start 60.750704 -46.4947)
		(end 60.990226 -46.734222)
		(width 0.1397)
		(layer "B.Cu")
		(net "CLK_96M_CPU_USB_DP")
	)
	(segment
		(start 61.53023 -46.480222)
		(end 62.401958 -47.35195)
		(width 0.1143)
		(layer "In7.Cu")
		(net "CLK_96M_CPU_USB_DP")
	)
	(segment
		(start 68.76415 -47.35195)
		(end 68.961 -47.5488)
		(width 0.1143)
		(layer "In7.Cu")
		(net "CLK_96M_CPU_USB_DP")
	)
	(segment
		(start 86.915752 -47.152306)
		(end 86.927182 -47.152306)
		(width 0.1016)
		(layer "In7.Cu")
		(net "CLK_96M_CPU_USB_DP")
	)
	(segment
		(start 73.323704 -47.5488)
		(end 73.581006 -47.806102)
		(width 0.1143)
		(layer "In7.Cu")
		(net "CLK_96M_CPU_USB_DP")
	)
	(segment
		(start 82.3849 -47.2694)
		(end 82.478118 -47.2694)
		(width 0.1016)
		(layer "In7.Cu")
		(net "CLK_96M_CPU_USB_DP")
	)
	(segment
		(start 82.478118 -47.2694)
		(end 82.541618 -47.2059)
		(width 0.1016)
		(layer "In7.Cu")
		(net "CLK_96M_CPU_USB_DP")
	)
	(segment
		(start 60.990226 -46.734222)
		(end 61.244226 -46.480222)
		(width 0.1143)
		(layer "In7.Cu")
		(net "CLK_96M_CPU_USB_DP")
	)
	(segment
		(start 68.961 -47.5488)
		(end 73.323704 -47.5488)
		(width 0.1143)
		(layer "In7.Cu")
		(net "CLK_96M_CPU_USB_DP")
	)
	(segment
		(start 62.401958 -47.35195)
		(end 68.76415 -47.35195)
		(width 0.1143)
		(layer "In7.Cu")
		(net "CLK_96M_CPU_USB_DP")
	)
	(segment
		(start 73.581006 -47.806102)
		(end 74.962004 -47.806102)
		(width 0.1143)
		(layer "In7.Cu")
		(net "CLK_96M_CPU_USB_DP")
	)
	(segment
		(start 86.1314 -46.6598)
		(end 86.4362 -46.9646)
		(width 0.1016)
		(layer "In7.Cu")
		(net "CLK_96M_CPU_USB_DP")
	)
	(segment
		(start 79.365094 -47.3202)
		(end 79.746094 -47.7012)
		(width 0.1143)
		(layer "In7.Cu")
		(net "CLK_96M_CPU_USB_DP")
	)
	(segment
		(start 83.548728 -46.6598)
		(end 86.1314 -46.6598)
		(width 0.1016)
		(layer "In7.Cu")
		(net "CLK_96M_CPU_USB_DP")
	)
	(segment
		(start 79.746094 -47.7012)
		(end 81.782412 -47.7012)
		(width 0.1143)
		(layer "In7.Cu")
		(net "CLK_96M_CPU_USB_DP")
	)
	(segment
		(start 82.541618 -47.2059)
		(end 83.002628 -47.2059)
		(width 0.1016)
		(layer "In7.Cu")
		(net "CLK_96M_CPU_USB_DP")
	)
	(segment
		(start 81.782412 -47.7012)
		(end 82.214212 -47.2694)
		(width 0.1143)
		(layer "In7.Cu")
		(net "CLK_96M_CPU_USB_DP")
	)
	(segment
		(start 83.002628 -47.2059)
		(end 83.548728 -46.6598)
		(width 0.1016)
		(layer "In7.Cu")
		(net "CLK_96M_CPU_USB_DP")
	)
	(segment
		(start 82.214212 -47.2694)
		(end 82.3849 -47.2694)
		(width 0.1143)
		(layer "In7.Cu")
		(net "CLK_96M_CPU_USB_DP")
	)
	(segment
		(start 61.244226 -46.480222)
		(end 61.53023 -46.480222)
		(width 0.1143)
		(layer "In7.Cu")
		(net "CLK_96M_CPU_USB_DP")
	)
	(segment
		(start 74.962004 -47.806102)
		(end 75.447906 -47.3202)
		(width 0.1143)
		(layer "In7.Cu")
		(net "CLK_96M_CPU_USB_DP")
	)
	(segment
		(start 86.4362 -46.9646)
		(end 86.728046 -46.9646)
		(width 0.1016)
		(layer "In7.Cu")
		(net "CLK_96M_CPU_USB_DP")
	)
	(segment
		(start 75.447906 -47.3202)
		(end 79.365094 -47.3202)
		(width 0.1143)
		(layer "In7.Cu")
		(net "CLK_96M_CPU_USB_DP")
	)
	(segment
		(start 86.728046 -46.9646)
		(end 86.915752 -47.152306)
		(width 0.1016)
		(layer "In7.Cu")
		(net "CLK_96M_CPU_USB_DP")
	)
	(segment
		(start 182.49773 -66.937128)
		(end 182.232808 -66.672206)
		(width 0.1778)
		(layer "F.Cu")
		(net "M_A_DQS_DP1")
	)
	(segment
		(start 109.195108 -43.642534)
		(end 108.82884 -43.276266)
		(width 0.1016)
		(layer "F.Cu")
		(net "M_A_DQS_DP1")
	)
	(segment
		(start 108.82884 -43.276266)
		(end 108.82884 -43.254422)
		(width 0.1016)
		(layer "F.Cu")
		(net "M_A_DQS_DP1")
	)
	(segment
		(start 182.49773 -69.906134)
		(end 182.49773 -66.937128)
		(width 0.1778)
		(layer "F.Cu")
		(net "M_A_DQS_DP1")
	)
	(segment
		(start 108.82884 -43.254422)
		(end 108.821474 -43.247056)
		(width 0.1016)
		(layer "F.Cu")
		(net "M_A_DQS_DP1")
	)
	(segment
		(start 182.350156 -70.053708)
		(end 182.49773 -69.906134)
		(width 0.1778)
		(layer "F.Cu")
		(net "M_A_DQS_DP1")
	)
	(segment
		(start 182.350156 -70.806564)
		(end 182.350156 -70.053708)
		(width 0.1778)
		(layer "F.Cu")
		(net "M_A_DQS_DP1")
	)
	(via
		(at 182.232808 -66.672206)
		(size 0.4318)
		(drill 0.2032)
		(layers "F.Cu" "B.Cu")
		(net "M_A_DQS_DP1")
	)
	(via
		(at 108.821474 -43.247056)
		(size 0.4318)
		(drill 0.2032)
		(layers "F.Cu" "B.Cu")
		(net "M_A_DQS_DP1")
	)
	(segment
		(start 182.350156 -62.599824)
		(end 182.350156 -63.364364)
		(width 0.1778)
		(layer "B.Cu")
		(net "M_A_DQS_DP1")
	)
	(segment
		(start 182.49773 -63.511938)
		(end 182.49773 -66.407284)
		(width 0.1778)
		(layer "B.Cu")
		(net "M_A_DQS_DP1")
	)
	(segment
		(start 182.49773 -66.407284)
		(end 182.232808 -66.672206)
		(width 0.1778)
		(layer "B.Cu")
		(net "M_A_DQS_DP1")
	)
	(segment
		(start 182.350156 -63.364364)
		(end 182.49773 -63.511938)
		(width 0.1778)
		(layer "B.Cu")
		(net "M_A_DQS_DP1")
	)
	(segment
		(start 109.626654 -43.112182)
		(end 108.956348 -43.112182)
		(width 0.1016)
		(layer "In4.Cu")
		(net "M_A_DQS_DP1")
	)
	(segment
		(start 182.5244 -63.206376)
		(end 182.39994 -63.330836)
		(width 0.1524)
		(layer "In4.Cu")
		(net "M_A_DQS_DP1")
	)
	(segment
		(start 155.094686 -45.10786)
		(end 155.219146 -44.9834)
		(width 0.1524)
		(layer "In4.Cu")
		(net "M_A_DQS_DP1")
	)
	(segment
		(start 154.637486 -45.10786)
		(end 155.094686 -45.10786)
		(width 0.1524)
		(layer "In4.Cu")
		(net "M_A_DQS_DP1")
	)
	(segment
		(start 108.956348 -43.112182)
		(end 108.821474 -43.247056)
		(width 0.1016)
		(layer "In4.Cu")
		(net "M_A_DQS_DP1")
	)
	(segment
		(start 182.39994 -63.788036)
		(end 182.5244 -63.912496)
		(width 0.1524)
		(layer "In4.Cu")
		(net "M_A_DQS_DP1")
	)
	(segment
		(start 176.10709 -53.980842)
		(end 180.086 -57.959752)
		(width 0.1524)
		(layer "In4.Cu")
		(net "M_A_DQS_DP1")
	)
	(segment
		(start 154.513026 -44.9834)
		(end 154.637486 -45.10786)
		(width 0.1524)
		(layer "In4.Cu")
		(net "M_A_DQS_DP1")
	)
	(segment
		(start 157.440376 -44.9834)
		(end 157.7086 -45.251624)
		(width 0.1524)
		(layer "In4.Cu")
		(net "M_A_DQS_DP1")
	)
	(segment
		(start 180.086 -57.959752)
		(end 180.086 -59.3852)
		(width 0.1524)
		(layer "In4.Cu")
		(net "M_A_DQS_DP1")
	)
	(segment
		(start 182.5244 -65.075816)
		(end 182.5244 -66.380614)
		(width 0.1524)
		(layer "In4.Cu")
		(net "M_A_DQS_DP1")
	)
	(segment
		(start 151.661876 -43.7642)
		(end 152.881076 -44.9834)
		(width 0.1524)
		(layer "In4.Cu")
		(net "M_A_DQS_DP1")
	)
	(segment
		(start 182.5244 -63.912496)
		(end 182.5244 -64.369696)
		(width 0.1524)
		(layer "In4.Cu")
		(net "M_A_DQS_DP1")
	)
	(segment
		(start 153.474166 -45.10786)
		(end 153.931366 -45.10786)
		(width 0.1524)
		(layer "In4.Cu")
		(net "M_A_DQS_DP1")
	)
	(segment
		(start 182.39994 -64.951356)
		(end 182.5244 -65.075816)
		(width 0.1524)
		(layer "In4.Cu")
		(net "M_A_DQS_DP1")
	)
	(segment
		(start 172.649642 -53.980842)
		(end 176.10709 -53.980842)
		(width 0.1524)
		(layer "In4.Cu")
		(net "M_A_DQS_DP1")
	)
	(segment
		(start 157.7086 -45.251624)
		(end 157.7086 -47.791624)
		(width 0.1524)
		(layer "In4.Cu")
		(net "M_A_DQS_DP1")
	)
	(segment
		(start 111.506 -43.18)
		(end 109.694472 -43.18)
		(width 0.1016)
		(layer "In4.Cu")
		(net "M_A_DQS_DP1")
	)
	(segment
		(start 181.555136 -61.030358)
		(end 181.731158 -61.030358)
		(width 0.1524)
		(layer "In4.Cu")
		(net "M_A_DQS_DP1")
	)
	(segment
		(start 159.893 -45.212)
		(end 159.893 -47.804324)
		(width 0.1524)
		(layer "In4.Cu")
		(net "M_A_DQS_DP1")
	)
	(segment
		(start 117.816376 -42.1132)
		(end 112.5728 -42.1132)
		(width 0.1016)
		(layer "In4.Cu")
		(net "M_A_DQS_DP1")
	)
	(segment
		(start 180.908706 -60.207906)
		(end 181.231794 -60.530994)
		(width 0.1524)
		(layer "In4.Cu")
		(net "M_A_DQS_DP1")
	)
	(segment
		(start 157.7086 -47.791624)
		(end 158.024576 -48.1076)
		(width 0.1524)
		(layer "In4.Cu")
		(net "M_A_DQS_DP1")
	)
	(segment
		(start 180.409342 -59.708542)
		(end 180.409342 -59.884564)
		(width 0.1524)
		(layer "In4.Cu")
		(net "M_A_DQS_DP1")
	)
	(segment
		(start 182.5244 -66.380614)
		(end 182.232808 -66.672206)
		(width 0.1524)
		(layer "In4.Cu")
		(net "M_A_DQS_DP1")
	)
	(segment
		(start 160.208976 -48.1203)
		(end 166.7891 -48.1203)
		(width 0.1524)
		(layer "In4.Cu")
		(net "M_A_DQS_DP1")
	)
	(segment
		(start 112.5728 -42.1132)
		(end 111.506 -43.18)
		(width 0.1016)
		(layer "In4.Cu")
		(net "M_A_DQS_DP1")
	)
	(segment
		(start 180.086 -59.3852)
		(end 180.409342 -59.708542)
		(width 0.1524)
		(layer "In4.Cu")
		(net "M_A_DQS_DP1")
	)
	(segment
		(start 118.086886 -42.38371)
		(end 117.816376 -42.1132)
		(width 0.1016)
		(layer "In4.Cu")
		(net "M_A_DQS_DP1")
	)
	(segment
		(start 109.694472 -43.18)
		(end 109.626654 -43.112182)
		(width 0.1016)
		(layer "In4.Cu")
		(net "M_A_DQS_DP1")
	)
	(segment
		(start 181.231794 -60.707016)
		(end 181.555136 -61.030358)
		(width 0.1524)
		(layer "In4.Cu")
		(net "M_A_DQS_DP1")
	)
	(segment
		(start 159.0802 -47.791624)
		(end 159.0802 -45.212)
		(width 0.1524)
		(layer "In4.Cu")
		(net "M_A_DQS_DP1")
	)
	(segment
		(start 182.39994 -63.330836)
		(end 182.39994 -63.788036)
		(width 0.1524)
		(layer "In4.Cu")
		(net "M_A_DQS_DP1")
	)
	(segment
		(start 159.0802 -45.212)
		(end 159.2326 -45.0596)
		(width 0.1524)
		(layer "In4.Cu")
		(net "M_A_DQS_DP1")
	)
	(segment
		(start 159.893 -47.804324)
		(end 160.208976 -48.1203)
		(width 0.1524)
		(layer "In4.Cu")
		(net "M_A_DQS_DP1")
	)
	(segment
		(start 180.732684 -60.207906)
		(end 180.908706 -60.207906)
		(width 0.1524)
		(layer "In4.Cu")
		(net "M_A_DQS_DP1")
	)
	(segment
		(start 180.409342 -59.884564)
		(end 180.732684 -60.207906)
		(width 0.1524)
		(layer "In4.Cu")
		(net "M_A_DQS_DP1")
	)
	(segment
		(start 152.881076 -44.9834)
		(end 153.349706 -44.9834)
		(width 0.1524)
		(layer "In4.Cu")
		(net "M_A_DQS_DP1")
	)
	(segment
		(start 159.2326 -45.0596)
		(end 159.7406 -45.0596)
		(width 0.1524)
		(layer "In4.Cu")
		(net "M_A_DQS_DP1")
	)
	(segment
		(start 181.231794 -60.530994)
		(end 181.231794 -60.707016)
		(width 0.1524)
		(layer "In4.Cu")
		(net "M_A_DQS_DP1")
	)
	(segment
		(start 166.7891 -48.1203)
		(end 172.649642 -53.980842)
		(width 0.1524)
		(layer "In4.Cu")
		(net "M_A_DQS_DP1")
	)
	(segment
		(start 153.931366 -45.10786)
		(end 154.055826 -44.9834)
		(width 0.1524)
		(layer "In4.Cu")
		(net "M_A_DQS_DP1")
	)
	(segment
		(start 153.349706 -44.9834)
		(end 153.474166 -45.10786)
		(width 0.1524)
		(layer "In4.Cu")
		(net "M_A_DQS_DP1")
	)
	(segment
		(start 159.7406 -45.0596)
		(end 159.893 -45.212)
		(width 0.1524)
		(layer "In4.Cu")
		(net "M_A_DQS_DP1")
	)
	(segment
		(start 122.743976 -43.7642)
		(end 151.661876 -43.7642)
		(width 0.1524)
		(layer "In4.Cu")
		(net "M_A_DQS_DP1")
	)
	(segment
		(start 182.39994 -64.494156)
		(end 182.39994 -64.951356)
		(width 0.1524)
		(layer "In4.Cu")
		(net "M_A_DQS_DP1")
	)
	(segment
		(start 155.219146 -44.9834)
		(end 157.440376 -44.9834)
		(width 0.1524)
		(layer "In4.Cu")
		(net "M_A_DQS_DP1")
	)
	(segment
		(start 182.5244 -64.369696)
		(end 182.39994 -64.494156)
		(width 0.1524)
		(layer "In4.Cu")
		(net "M_A_DQS_DP1")
	)
	(segment
		(start 158.024576 -48.1076)
		(end 158.764224 -48.1076)
		(width 0.1524)
		(layer "In4.Cu")
		(net "M_A_DQS_DP1")
	)
	(segment
		(start 182.5244 -61.8236)
		(end 182.5244 -63.206376)
		(width 0.1524)
		(layer "In4.Cu")
		(net "M_A_DQS_DP1")
	)
	(segment
		(start 118.959376 -43.2562)
		(end 122.235976 -43.2562)
		(width 0.1524)
		(layer "In4.Cu")
		(net "M_A_DQS_DP1")
	)
	(segment
		(start 118.086886 -42.38371)
		(end 118.959376 -43.2562)
		(width 0.1524)
		(layer "In4.Cu")
		(net "M_A_DQS_DP1")
	)
	(segment
		(start 181.731158 -61.030358)
		(end 182.5244 -61.8236)
		(width 0.1524)
		(layer "In4.Cu")
		(net "M_A_DQS_DP1")
	)
	(segment
		(start 158.764224 -48.1076)
		(end 159.0802 -47.791624)
		(width 0.1524)
		(layer "In4.Cu")
		(net "M_A_DQS_DP1")
	)
	(segment
		(start 122.235976 -43.2562)
		(end 122.743976 -43.7642)
		(width 0.1524)
		(layer "In4.Cu")
		(net "M_A_DQS_DP1")
	)
	(segment
		(start 154.055826 -44.9834)
		(end 154.513026 -44.9834)
		(width 0.1524)
		(layer "In4.Cu")
		(net "M_A_DQS_DP1")
	)
	(via
		(at 43.5102 -53.086)
		(size 0.7112)
		(drill 0.3556)
		(layers "F.Cu" "B.Cu")
		(net "CLKGEN_VSEL_PCI")
	)
	(segment
		(start 43.5102 -54.102)
		(end 43.5102 -53.086)
		(width 0.1143)
		(layer "B.Cu")
		(net "CLKGEN_VSEL_PCI")
	)
	(segment
		(start 43.5102 -53.0098)
		(end 43.5102 -53.086)
		(width 0.1143)
		(layer "B.Cu")
		(net "CLKGEN_VSEL_PCI")
	)
	(segment
		(start 43.65879 -51.70678)
		(end 43.65879 -52.86121)
		(width 0.1143)
		(layer "B.Cu")
		(net "CLKGEN_VSEL_PCI")
	)
	(segment
		(start 43.65879 -52.86121)
		(end 43.5102 -53.0098)
		(width 0.1143)
		(layer "B.Cu")
		(net "CLKGEN_VSEL_PCI")
	)
	(segment
		(start 109.605572 -49.12995)
		(end 109.54258 -49.12995)
		(width 0.1778)
		(layer "F.Cu")
		(net "M_A_CKE2")
	)
	(segment
		(start 161.950146 -69.394324)
		(end 161.883598 -69.327776)
		(width 0.1778)
		(layer "F.Cu")
		(net "M_A_CKE2")
	)
	(segment
		(start 109.913928 -48.821594)
		(end 109.605572 -49.12995)
		(width 0.1778)
		(layer "F.Cu")
		(net "M_A_CKE2")
	)
	(segment
		(start 161.950146 -70.806564)
		(end 161.950146 -69.394324)
		(width 0.1778)
		(layer "F.Cu")
		(net "M_A_CKE2")
	)
	(via
		(at 109.54258 -49.12995)
		(size 0.4318)
		(drill 0.2032)
		(layers "F.Cu" "B.Cu")
		(net "M_A_CKE2")
	)
	(via
		(at 161.883598 -69.327776)
		(size 0.4318)
		(drill 0.2032)
		(layers "F.Cu" "B.Cu")
		(net "M_A_CKE2")
	)
	(segment
		(start 165.1 -60.330588)
		(end 151.887174 -47.117762)
		(width 0.1524)
		(layer "In7.Cu")
		(net "M_A_CKE2")
	)
	(segment
		(start 162.015424 -69.327776)
		(end 162.992562 -68.350638)
		(width 0.1524)
		(layer "In7.Cu")
		(net "M_A_CKE2")
	)
	(segment
		(start 110.02645 -49.12995)
		(end 109.54258 -49.12995)
		(width 0.1524)
		(layer "In7.Cu")
		(net "M_A_CKE2")
	)
	(segment
		(start 161.883598 -69.327776)
		(end 162.015424 -69.327776)
		(width 0.1524)
		(layer "In7.Cu")
		(net "M_A_CKE2")
	)
	(segment
		(start 162.992562 -67.901058)
		(end 164.232082 -66.661538)
		(width 0.1524)
		(layer "In7.Cu")
		(net "M_A_CKE2")
	)
	(segment
		(start 164.232082 -66.661538)
		(end 164.232082 -66.374518)
		(width 0.1524)
		(layer "In7.Cu")
		(net "M_A_CKE2")
	)
	(segment
		(start 124.848874 -46.6344)
		(end 112.522 -46.6344)
		(width 0.1524)
		(layer "In7.Cu")
		(net "M_A_CKE2")
	)
	(segment
		(start 165.1 -65.5066)
		(end 165.1 -60.330588)
		(width 0.1524)
		(layer "In7.Cu")
		(net "M_A_CKE2")
	)
	(segment
		(start 151.887174 -47.117762)
		(end 125.332236 -47.117762)
		(width 0.1524)
		(layer "In7.Cu")
		(net "M_A_CKE2")
	)
	(segment
		(start 164.232082 -66.374518)
		(end 165.1 -65.5066)
		(width 0.1524)
		(layer "In7.Cu")
		(net "M_A_CKE2")
	)
	(segment
		(start 112.522 -46.6344)
		(end 110.02645 -49.12995)
		(width 0.1524)
		(layer "In7.Cu")
		(net "M_A_CKE2")
	)
	(segment
		(start 125.332236 -47.117762)
		(end 124.848874 -46.6344)
		(width 0.1524)
		(layer "In7.Cu")
		(net "M_A_CKE2")
	)
	(segment
		(start 162.992562 -68.350638)
		(end 162.992562 -67.901058)
		(width 0.1524)
		(layer "In7.Cu")
		(net "M_A_CKE2")
	)
	(segment
		(start 87.434928 -45.735494)
		(end 87.434928 -46.012354)
		(width 0.1397)
		(layer "F.Cu")
		(net "CLK_96M_CPU_USB_DN")
	)
	(segment
		(start 86.960202 -46.48708)
		(end 86.960202 -46.529244)
		(width 0.1397)
		(layer "F.Cu")
		(net "CLK_96M_CPU_USB_DN")
	)
	(segment
		(start 86.960202 -46.529244)
		(end 86.915752 -46.573694)
		(width 0.1397)
		(layer "F.Cu")
		(net "CLK_96M_CPU_USB_DN")
	)
	(segment
		(start 87.434928 -46.012354)
		(end 86.960202 -46.48708)
		(width 0.1397)
		(layer "F.Cu")
		(net "CLK_96M_CPU_USB_DN")
	)
	(via
		(at 60.9346 -45.8724)
		(size 0.508)
		(drill 0.254)
		(layers "F.Cu" "B.Cu")
		(net "CLK_96M_CPU_USB_DN")
	)
	(via
		(at 86.915752 -46.573694)
		(size 0.4318)
		(drill 0.2032)
		(layers "F.Cu" "B.Cu")
		(net "CLK_96M_CPU_USB_DN")
	)
	(segment
		(start 60.6552 -46.1518)
		(end 60.9346 -45.8724)
		(width 0.1397)
		(layer "B.Cu")
		(net "CLK_96M_CPU_USB_DN")
	)
	(segment
		(start 57.5945 -52.9971)
		(end 57.5945 -48.34636)
		(width 0.1397)
		(layer "B.Cu")
		(net "CLK_96M_CPU_USB_DN")
	)
	(segment
		(start 56.0832 -54.5084)
		(end 57.5945 -52.9971)
		(width 0.1397)
		(layer "B.Cu")
		(net "CLK_96M_CPU_USB_DN")
	)
	(segment
		(start 48.0822 -54.5084)
		(end 56.0832 -54.5084)
		(width 0.1397)
		(layer "B.Cu")
		(net "CLK_96M_CPU_USB_DN")
	)
	(segment
		(start 47.04715 -52.90439)
		(end 47.04715 -53.47335)
		(width 0.1397)
		(layer "B.Cu")
		(net "CLK_96M_CPU_USB_DN")
	)
	(segment
		(start 47.04715 -53.47335)
		(end 48.0822 -54.5084)
		(width 0.1397)
		(layer "B.Cu")
		(net "CLK_96M_CPU_USB_DN")
	)
	(segment
		(start 59.78906 -46.1518)
		(end 60.6552 -46.1518)
		(width 0.1397)
		(layer "B.Cu")
		(net "CLK_96M_CPU_USB_DN")
	)
	(segment
		(start 46.458632 -52.315872)
		(end 47.04715 -52.90439)
		(width 0.1397)
		(layer "B.Cu")
		(net "CLK_96M_CPU_USB_DN")
	)
	(segment
		(start 57.5945 -48.34636)
		(end 59.78906 -46.1518)
		(width 0.1397)
		(layer "B.Cu")
		(net "CLK_96M_CPU_USB_DN")
	)
	(segment
		(start 46.458632 -51.70678)
		(end 46.458632 -52.315872)
		(width 0.1397)
		(layer "B.Cu")
		(net "CLK_96M_CPU_USB_DN")
	)
	(segment
		(start 63.095124 -46.80839)
		(end 62.881764 -47.02175)
		(width 0.1143)
		(layer "In7.Cu")
		(net "CLK_96M_CPU_USB_DN")
	)
	(segment
		(start 79.502 -46.99)
		(end 75.311 -46.99)
		(width 0.1143)
		(layer "In7.Cu")
		(net "CLK_96M_CPU_USB_DN")
	)
	(segment
		(start 82.9183 -47.0027)
		(end 82.550762 -47.0027)
		(width 0.1016)
		(layer "In7.Cu")
		(net "CLK_96M_CPU_USB_DN")
	)
	(segment
		(start 75.311 -46.99)
		(end 74.825098 -47.475902)
		(width 0.1143)
		(layer "In7.Cu")
		(net "CLK_96M_CPU_USB_DN")
	)
	(segment
		(start 82.3849 -46.9392)
		(end 82.077306 -46.9392)
		(width 0.1143)
		(layer "In7.Cu")
		(net "CLK_96M_CPU_USB_DN")
	)
	(segment
		(start 82.077306 -46.9392)
		(end 81.645506 -47.371)
		(width 0.1143)
		(layer "In7.Cu")
		(net "CLK_96M_CPU_USB_DN")
	)
	(segment
		(start 73.717912 -47.475902)
		(end 73.46061 -47.2186)
		(width 0.1143)
		(layer "In7.Cu")
		(net "CLK_96M_CPU_USB_DN")
	)
	(segment
		(start 83.4644 -46.4566)
		(end 82.9183 -47.0027)
		(width 0.1016)
		(layer "In7.Cu")
		(net "CLK_96M_CPU_USB_DN")
	)
	(segment
		(start 81.645506 -47.371)
		(end 80.99552 -47.371)
		(width 0.1143)
		(layer "In7.Cu")
		(net "CLK_96M_CPU_USB_DN")
	)
	(segment
		(start 61.212222 -46.150022)
		(end 60.9346 -45.8724)
		(width 0.1143)
		(layer "In7.Cu")
		(net "CLK_96M_CPU_USB_DN")
	)
	(segment
		(start 80.2259 -47.371)
		(end 79.883 -47.371)
		(width 0.1143)
		(layer "In7.Cu")
		(net "CLK_96M_CPU_USB_DN")
	)
	(segment
		(start 86.215728 -46.4566)
		(end 83.4644 -46.4566)
		(width 0.1016)
		(layer "In7.Cu")
		(net "CLK_96M_CPU_USB_DN")
	)
	(segment
		(start 79.883 -47.371)
		(end 79.502 -46.99)
		(width 0.1143)
		(layer "In7.Cu")
		(net "CLK_96M_CPU_USB_DN")
	)
	(segment
		(start 86.915752 -46.573694)
		(end 86.728046 -46.7614)
		(width 0.1016)
		(layer "In7.Cu")
		(net "CLK_96M_CPU_USB_DN")
	)
	(segment
		(start 69.097906 -47.2186)
		(end 68.901056 -47.02175)
		(width 0.1143)
		(layer "In7.Cu")
		(net "CLK_96M_CPU_USB_DN")
	)
	(segment
		(start 74.825098 -47.475902)
		(end 73.717912 -47.475902)
		(width 0.1143)
		(layer "In7.Cu")
		(net "CLK_96M_CPU_USB_DN")
	)
	(segment
		(start 62.538864 -47.02175)
		(end 61.667136 -46.150022)
		(width 0.1143)
		(layer "In7.Cu")
		(net "CLK_96M_CPU_USB_DN")
	)
	(segment
		(start 86.728046 -46.7614)
		(end 86.520528 -46.7614)
		(width 0.1016)
		(layer "In7.Cu")
		(net "CLK_96M_CPU_USB_DN")
	)
	(segment
		(start 68.901056 -47.02175)
		(end 63.651384 -47.02175)
		(width 0.1143)
		(layer "In7.Cu")
		(net "CLK_96M_CPU_USB_DN")
	)
	(segment
		(start 63.438024 -46.80839)
		(end 63.095124 -46.80839)
		(width 0.1143)
		(layer "In7.Cu")
		(net "CLK_96M_CPU_USB_DN")
	)
	(segment
		(start 80.78216 -47.15764)
		(end 80.43926 -47.15764)
		(width 0.1143)
		(layer "In7.Cu")
		(net "CLK_96M_CPU_USB_DN")
	)
	(segment
		(start 82.550762 -47.0027)
		(end 82.487262 -46.9392)
		(width 0.1016)
		(layer "In7.Cu")
		(net "CLK_96M_CPU_USB_DN")
	)
	(segment
		(start 63.651384 -47.02175)
		(end 63.438024 -46.80839)
		(width 0.1143)
		(layer "In7.Cu")
		(net "CLK_96M_CPU_USB_DN")
	)
	(segment
		(start 61.667136 -46.150022)
		(end 61.212222 -46.150022)
		(width 0.1143)
		(layer "In7.Cu")
		(net "CLK_96M_CPU_USB_DN")
	)
	(segment
		(start 80.43926 -47.15764)
		(end 80.2259 -47.371)
		(width 0.1143)
		(layer "In7.Cu")
		(net "CLK_96M_CPU_USB_DN")
	)
	(segment
		(start 62.881764 -47.02175)
		(end 62.538864 -47.02175)
		(width 0.1143)
		(layer "In7.Cu")
		(net "CLK_96M_CPU_USB_DN")
	)
	(segment
		(start 80.99552 -47.371)
		(end 80.78216 -47.15764)
		(width 0.1143)
		(layer "In7.Cu")
		(net "CLK_96M_CPU_USB_DN")
	)
	(segment
		(start 86.520528 -46.7614)
		(end 86.215728 -46.4566)
		(width 0.1016)
		(layer "In7.Cu")
		(net "CLK_96M_CPU_USB_DN")
	)
	(segment
		(start 73.46061 -47.2186)
		(end 69.097906 -47.2186)
		(width 0.1143)
		(layer "In7.Cu")
		(net "CLK_96M_CPU_USB_DN")
	)
	(segment
		(start 82.487262 -46.9392)
		(end 82.3849 -46.9392)
		(width 0.1016)
		(layer "In7.Cu")
		(net "CLK_96M_CPU_USB_DN")
	)
	(segment
		(start 161.777172 -63.529972)
		(end 161.777172 -64.450214)
		(width 0.2413)
		(layer "F.Cu")
		(net "M_A_MA15")
	)
	(segment
		(start 105.311448 -48.402494)
		(end 105.32999 -48.402494)
		(width 0.1016)
		(layer "F.Cu")
		(net "M_A_MA15")
	)
	(segment
		(start 161.650172 -63.402972)
		(end 161.777172 -63.529972)
		(width 0.2413)
		(layer "F.Cu")
		(net "M_A_MA15")
	)
	(segment
		(start 162.53587 -65.632584)
		(end 162.53587 -66.958718)
		(width 0.2413)
		(layer "F.Cu")
		(net "M_A_MA15")
	)
	(segment
		(start 162.53587 -66.958718)
		(end 162.098228 -67.39636)
		(width 0.2413)
		(layer "F.Cu")
		(net "M_A_MA15")
	)
	(segment
		(start 161.650172 -62.59322)
		(end 161.650172 -63.402972)
		(width 0.2413)
		(layer "F.Cu")
		(net "M_A_MA15")
	)
	(segment
		(start 161.803588 -64.47663)
		(end 161.803588 -64.900302)
		(width 0.2413)
		(layer "F.Cu")
		(net "M_A_MA15")
	)
	(segment
		(start 105.32999 -48.402494)
		(end 105.661968 -48.070516)
		(width 0.1016)
		(layer "F.Cu")
		(net "M_A_MA15")
	)
	(segment
		(start 161.777172 -64.450214)
		(end 161.803588 -64.47663)
		(width 0.2413)
		(layer "F.Cu")
		(net "M_A_MA15")
	)
	(segment
		(start 161.803588 -64.900302)
		(end 162.53587 -65.632584)
		(width 0.2413)
		(layer "F.Cu")
		(net "M_A_MA15")
	)
	(segment
		(start 162.098228 -67.39636)
		(end 162.07486 -67.39636)
		(width 0.2413)
		(layer "F.Cu")
		(net "M_A_MA15")
	)
	(via
		(at 105.661968 -48.070516)
		(size 0.4318)
		(drill 0.2032)
		(layers "F.Cu" "B.Cu")
		(net "M_A_MA15")
	)
	(via
		(at 162.07486 -67.39636)
		(size 0.4318)
		(drill 0.2032)
		(layers "F.Cu" "B.Cu")
		(net "M_A_MA15")
	)
	(segment
		(start 161.650172 -70.79996)
		(end 161.650172 -70.057772)
		(width 0.2413)
		(layer "B.Cu")
		(net "M_A_MA15")
	)
	(segment
		(start 162.07359 -67.39763)
		(end 162.07486 -67.39636)
		(width 0.2413)
		(layer "B.Cu")
		(net "M_A_MA15")
	)
	(segment
		(start 161.650172 -70.057772)
		(end 161.394902 -69.802502)
		(width 0.2413)
		(layer "B.Cu")
		(net "M_A_MA15")
	)
	(segment
		(start 161.394902 -68.297298)
		(end 162.07359 -67.61861)
		(width 0.2413)
		(layer "B.Cu")
		(net "M_A_MA15")
	)
	(segment
		(start 161.394902 -69.802502)
		(end 161.394902 -68.297298)
		(width 0.2413)
		(layer "B.Cu")
		(net "M_A_MA15")
	)
	(segment
		(start 162.07359 -67.61861)
		(end 162.07359 -67.39763)
		(width 0.2413)
		(layer "B.Cu")
		(net "M_A_MA15")
	)
	(segment
		(start 105.304844 -47.566326)
		(end 105.2322 -47.3964)
		(width 0.1016)
		(layer "In9.Cu")
		(net "M_A_MA15")
	)
	(segment
		(start 151.185372 -47.16145)
		(end 161.52495 -57.501028)
		(width 0.1905)
		(layer "In9.Cu")
		(net "M_A_MA15")
	)
	(segment
		(start 120.6246 -46.6598)
		(end 125.349 -47.16145)
		(width 0.1905)
		(layer "In9.Cu")
		(net "M_A_MA15")
	)
	(segment
		(start 161.55797 -66.897504)
		(end 162.056826 -67.39636)
		(width 0.1905)
		(layer "In9.Cu")
		(net "M_A_MA15")
	)
	(segment
		(start 160.848548 -63.7794)
		(end 160.848548 -64.912748)
		(width 0.1905)
		(layer "In9.Cu")
		(net "M_A_MA15")
	)
	(segment
		(start 105.2322 -47.3964)
		(end 105.2322 -47.2186)
		(width 0.1016)
		(layer "In9.Cu")
		(net "M_A_MA15")
	)
	(segment
		(start 161.55797 -65.62217)
		(end 161.55797 -66.897504)
		(width 0.1905)
		(layer "In9.Cu")
		(net "M_A_MA15")
	)
	(segment
		(start 125.349 -47.16145)
		(end 151.185372 -47.16145)
		(width 0.1905)
		(layer "In9.Cu")
		(net "M_A_MA15")
	)
	(segment
		(start 105.34142 -46.97222)
		(end 105.537 -46.905926)
		(width 0.1016)
		(layer "In9.Cu")
		(net "M_A_MA15")
	)
	(segment
		(start 161.52495 -57.501028)
		(end 161.52495 -62.738)
		(width 0.1905)
		(layer "In9.Cu")
		(net "M_A_MA15")
	)
	(segment
		(start 161.52495 -62.738)
		(end 160.848548 -63.7794)
		(width 0.1905)
		(layer "In9.Cu")
		(net "M_A_MA15")
	)
	(segment
		(start 105.2322 -47.2186)
		(end 105.29062 -47.02302)
		(width 0.1016)
		(layer "In9.Cu")
		(net "M_A_MA15")
	)
	(segment
		(start 162.056826 -67.39636)
		(end 162.07486 -67.39636)
		(width 0.1905)
		(layer "In9.Cu")
		(net "M_A_MA15")
	)
	(segment
		(start 160.848548 -64.912748)
		(end 161.55797 -65.62217)
		(width 0.1905)
		(layer "In9.Cu")
		(net "M_A_MA15")
	)
	(segment
		(start 115.9256 -46.6598)
		(end 120.6246 -46.6598)
		(width 0.1905)
		(layer "In9.Cu")
		(net "M_A_MA15")
	)
	(segment
		(start 105.537 -46.905926)
		(end 106.2482 -46.905926)
		(width 0.1016)
		(layer "In9.Cu")
		(net "M_A_MA15")
	)
	(segment
		(start 105.29062 -47.02302)
		(end 105.34142 -46.97222)
		(width 0.1016)
		(layer "In9.Cu")
		(net "M_A_MA15")
	)
	(segment
		(start 105.661968 -48.070516)
		(end 105.304844 -47.566326)
		(width 0.1016)
		(layer "In9.Cu")
		(net "M_A_MA15")
	)
	(segment
		(start 106.2482 -46.905926)
		(end 110.5154 -46.6598)
		(width 0.1016)
		(layer "In9.Cu")
		(net "M_A_MA15")
	)
	(segment
		(start 110.5154 -46.6598)
		(end 115.9256 -46.6598)
		(width 0.1016)
		(layer "In9.Cu")
		(net "M_A_MA15")
	)
	(segment
		(start 83.727798 -31.086044)
		(end 83.644232 -31.086044)
		(width 0.1397)
		(layer "F.Cu")
		(net "CLK_100M_CPU_SATA3_DP")
	)
	(segment
		(start 84.028788 -30.785054)
		(end 83.727798 -31.086044)
		(width 0.1397)
		(layer "F.Cu")
		(net "CLK_100M_CPU_SATA3_DP")
	)
	(via
		(at 59.65825 -36.33724)
		(size 0.508)
		(drill 0.254)
		(layers "F.Cu" "B.Cu")
		(net "CLK_100M_CPU_SATA3_DP")
	)
	(via
		(at 83.644232 -31.086044)
		(size 0.4318)
		(drill 0.2032)
		(layers "F.Cu" "B.Cu")
		(net "CLK_100M_CPU_SATA3_DP")
	)
	(segment
		(start 58.340498 -36.98494)
		(end 58.340498 -36.327842)
		(width 0.1397)
		(layer "B.Cu")
		(net "CLK_100M_CPU_SATA3_DP")
	)
	(segment
		(start 48.8569 -53.8607)
		(end 55.814722 -53.8607)
		(width 0.1397)
		(layer "B.Cu")
		(net "CLK_100M_CPU_SATA3_DP")
	)
	(segment
		(start 56.007 -46.228)
		(end 56.007 -44.93514)
		(width 0.1397)
		(layer "B.Cu")
		(net "CLK_100M_CPU_SATA3_DP")
	)
	(segment
		(start 55.814722 -53.8607)
		(end 56.896 -52.779422)
		(width 0.1397)
		(layer "B.Cu")
		(net "CLK_100M_CPU_SATA3_DP")
	)
	(segment
		(start 47.258732 -52.262532)
		(end 48.8569 -53.8607)
		(width 0.1397)
		(layer "B.Cu")
		(net "CLK_100M_CPU_SATA3_DP")
	)
	(segment
		(start 58.340498 -36.327842)
		(end 58.63844 -36.0299)
		(width 0.1397)
		(layer "B.Cu")
		(net "CLK_100M_CPU_SATA3_DP")
	)
	(segment
		(start 47.258732 -51.70678)
		(end 47.258732 -52.262532)
		(width 0.1397)
		(layer "B.Cu")
		(net "CLK_100M_CPU_SATA3_DP")
	)
	(segment
		(start 58.528458 -41.920922)
		(end 58.528458 -37.1729)
		(width 0.1397)
		(layer "B.Cu")
		(net "CLK_100M_CPU_SATA3_DP")
	)
	(segment
		(start 56.896 -47.117)
		(end 56.007 -46.228)
		(width 0.1397)
		(layer "B.Cu")
		(net "CLK_100M_CPU_SATA3_DP")
	)
	(segment
		(start 57.296558 -43.152822)
		(end 58.528458 -41.920922)
		(width 0.1397)
		(layer "B.Cu")
		(net "CLK_100M_CPU_SATA3_DP")
	)
	(segment
		(start 57.296558 -43.645582)
		(end 57.296558 -43.152822)
		(width 0.1397)
		(layer "B.Cu")
		(net "CLK_100M_CPU_SATA3_DP")
	)
	(segment
		(start 56.007 -44.93514)
		(end 57.296558 -43.645582)
		(width 0.1397)
		(layer "B.Cu")
		(net "CLK_100M_CPU_SATA3_DP")
	)
	(segment
		(start 58.528458 -37.1729)
		(end 58.340498 -36.98494)
		(width 0.1397)
		(layer "B.Cu")
		(net "CLK_100M_CPU_SATA3_DP")
	)
	(segment
		(start 58.63844 -36.0299)
		(end 59.35091 -36.0299)
		(width 0.1397)
		(layer "B.Cu")
		(net "CLK_100M_CPU_SATA3_DP")
	)
	(segment
		(start 56.896 -52.779422)
		(end 56.896 -47.117)
		(width 0.1397)
		(layer "B.Cu")
		(net "CLK_100M_CPU_SATA3_DP")
	)
	(segment
		(start 59.35091 -36.0299)
		(end 59.65825 -36.33724)
		(width 0.1397)
		(layer "B.Cu")
		(net "CLK_100M_CPU_SATA3_DP")
	)
	(segment
		(start 72.49795 -29.96565)
		(end 72.0852 -30.3784)
		(width 0.1143)
		(layer "In4.Cu")
		(net "CLK_100M_CPU_SATA3_DP")
	)
	(segment
		(start 60.360306 -36.0426)
		(end 59.95289 -36.0426)
		(width 0.1143)
		(layer "In4.Cu")
		(net "CLK_100M_CPU_SATA3_DP")
	)
	(segment
		(start 59.95289 -36.0426)
		(end 59.65825 -36.33724)
		(width 0.1143)
		(layer "In4.Cu")
		(net "CLK_100M_CPU_SATA3_DP")
	)
	(segment
		(start 76.143612 -29.96565)
		(end 72.49795 -29.96565)
		(width 0.1143)
		(layer "In4.Cu")
		(net "CLK_100M_CPU_SATA3_DP")
	)
	(segment
		(start 76.888594 -29.220922)
		(end 76.870814 -29.238702)
		(width 0.1016)
		(layer "In4.Cu")
		(net "CLK_100M_CPU_SATA3_DP")
	)
	(segment
		(start 77.2668 -28.7528)
		(end 76.888594 -29.131006)
		(width 0.1016)
		(layer "In4.Cu")
		(net "CLK_100M_CPU_SATA3_DP")
	)
	(segment
		(start 76.888594 -29.131006)
		(end 76.888594 -29.220922)
		(width 0.1016)
		(layer "In4.Cu")
		(net "CLK_100M_CPU_SATA3_DP")
	)
	(segment
		(start 72.0852 -30.3784)
		(end 66.024506 -30.3784)
		(width 0.1143)
		(layer "In4.Cu")
		(net "CLK_100M_CPU_SATA3_DP")
	)
	(segment
		(start 76.87056 -29.238702)
		(end 76.143612 -29.96565)
		(width 0.1143)
		(layer "In4.Cu")
		(net "CLK_100M_CPU_SATA3_DP")
	)
	(segment
		(start 83.419188 -30.861)
		(end 83.180936 -30.861)
		(width 0.1016)
		(layer "In4.Cu")
		(net "CLK_100M_CPU_SATA3_DP")
	)
	(segment
		(start 66.024506 -30.3784)
		(end 60.360306 -36.0426)
		(width 0.1143)
		(layer "In4.Cu")
		(net "CLK_100M_CPU_SATA3_DP")
	)
	(segment
		(start 80.264 -29.6418)
		(end 79.375 -28.7528)
		(width 0.1016)
		(layer "In4.Cu")
		(net "CLK_100M_CPU_SATA3_DP")
	)
	(segment
		(start 79.375 -28.7528)
		(end 77.2668 -28.7528)
		(width 0.1016)
		(layer "In4.Cu")
		(net "CLK_100M_CPU_SATA3_DP")
	)
	(segment
		(start 83.180936 -30.861)
		(end 81.961736 -29.6418)
		(width 0.1016)
		(layer "In4.Cu")
		(net "CLK_100M_CPU_SATA3_DP")
	)
	(segment
		(start 83.644232 -31.086044)
		(end 83.419188 -30.861)
		(width 0.1016)
		(layer "In4.Cu")
		(net "CLK_100M_CPU_SATA3_DP")
	)
	(segment
		(start 81.961736 -29.6418)
		(end 80.264 -29.6418)
		(width 0.1016)
		(layer "In4.Cu")
		(net "CLK_100M_CPU_SATA3_DP")
	)
	(segment
		(start 76.870814 -29.238702)
		(end 76.87056 -29.238702)
		(width 0.1143)
		(layer "In4.Cu")
		(net "CLK_100M_CPU_SATA3_DP")
	)
	(segment
		(start 155.84297 -66.404744)
		(end 155.84297 -66.767964)
		(width 0.2413)
		(layer "F.Cu")
		(net "M_A_BS1")
	)
	(segment
		(start 155.458668 -67.152266)
		(end 155.331668 -67.152266)
		(width 0.2413)
		(layer "F.Cu")
		(net "M_A_BS1")
	)
	(segment
		(start 155.84297 -66.767964)
		(end 155.458668 -67.152266)
		(width 0.2413)
		(layer "F.Cu")
		(net "M_A_BS1")
	)
	(segment
		(start 155.956 -63.786258)
		(end 155.956 -65.5574)
		(width 0.2413)
		(layer "F.Cu")
		(net "M_A_BS1")
	)
	(segment
		(start 155.650184 -62.59322)
		(end 155.650184 -63.480442)
		(width 0.2413)
		(layer "F.Cu")
		(net "M_A_BS1")
	)
	(segment
		(start 107.139994 -51.420268)
		(end 107.139994 -51.461162)
		(width 0.1016)
		(layer "F.Cu")
		(net "M_A_BS1")
	)
	(segment
		(start 155.650184 -63.480442)
		(end 155.956 -63.786258)
		(width 0.2413)
		(layer "F.Cu")
		(net "M_A_BS1")
	)
	(segment
		(start 107.460288 -51.099974)
		(end 107.139994 -51.420268)
		(width 0.1016)
		(layer "F.Cu")
		(net "M_A_BS1")
	)
	(segment
		(start 155.845764 -66.40195)
		(end 155.84297 -66.404744)
		(width 0.2413)
		(layer "F.Cu")
		(net "M_A_BS1")
	)
	(segment
		(start 155.331668 -67.152266)
		(end 155.330144 -67.15379)
		(width 0.2413)
		(layer "F.Cu")
		(net "M_A_BS1")
	)
	(segment
		(start 155.956 -65.5574)
		(end 155.845764 -65.667636)
		(width 0.2413)
		(layer "F.Cu")
		(net "M_A_BS1")
	)
	(segment
		(start 155.845764 -65.667636)
		(end 155.845764 -66.40195)
		(width 0.2413)
		(layer "F.Cu")
		(net "M_A_BS1")
	)
	(via
		(at 107.139994 -51.461162)
		(size 0.4318)
		(drill 0.2032)
		(layers "F.Cu" "B.Cu")
		(net "M_A_BS1")
	)
	(via
		(at 155.330144 -67.15379)
		(size 0.4318)
		(drill 0.2032)
		(layers "F.Cu" "B.Cu")
		(net "M_A_BS1")
	)
	(segment
		(start 156.011372 -69.540882)
		(end 156.011372 -69.156326)
		(width 0.2413)
		(layer "B.Cu")
		(net "M_A_BS1")
	)
	(segment
		(start 155.7401 -68.885054)
		(end 155.739846 -68.885054)
		(width 0.2413)
		(layer "B.Cu")
		(net "M_A_BS1")
	)
	(segment
		(start 155.739846 -68.885054)
		(end 155.330144 -68.475352)
		(width 0.2413)
		(layer "B.Cu")
		(net "M_A_BS1")
	)
	(segment
		(start 156.011372 -69.156326)
		(end 155.7401 -68.885054)
		(width 0.2413)
		(layer "B.Cu")
		(net "M_A_BS1")
	)
	(segment
		(start 155.650184 -70.79996)
		(end 155.650184 -69.90207)
		(width 0.2413)
		(layer "B.Cu")
		(net "M_A_BS1")
	)
	(segment
		(start 155.330144 -68.475352)
		(end 155.330144 -67.15379)
		(width 0.2413)
		(layer "B.Cu")
		(net "M_A_BS1")
	)
	(segment
		(start 155.650184 -69.90207)
		(end 156.011372 -69.540882)
		(width 0.2413)
		(layer "B.Cu")
		(net "M_A_BS1")
	)
	(segment
		(start 119.177562 -54.726586)
		(end 118.987062 -54.917086)
		(width 0.1905)
		(layer "In9.Cu")
		(net "M_A_BS1")
	)
	(segment
		(start 121.273062 -54.917086)
		(end 121.082562 -54.726586)
		(width 0.1905)
		(layer "In9.Cu")
		(net "M_A_BS1")
	)
	(segment
		(start 155.31211 -67.15379)
		(end 154.4574 -66.29908)
		(width 0.1905)
		(layer "In9.Cu")
		(net "M_A_BS1")
	)
	(segment
		(start 155.8544 -63.973456)
		(end 155.10002 -63.219076)
		(width 0.1905)
		(layer "In9.Cu")
		(net "M_A_BS1")
	)
	(segment
		(start 150.908258 -59.432444)
		(end 149.227032 -57.751218)
		(width 0.1905)
		(layer "In9.Cu")
		(net "M_A_BS1")
	)
	(segment
		(start 119.749062 -54.917086)
		(end 119.558562 -54.726586)
		(width 0.1905)
		(layer "In9.Cu")
		(net "M_A_BS1")
	)
	(segment
		(start 147.886928 -57.751218)
		(end 145.38706 -55.25135)
		(width 0.1905)
		(layer "In9.Cu")
		(net "M_A_BS1")
	)
	(segment
		(start 120.701562 -54.726586)
		(end 120.511062 -54.917086)
		(width 0.1905)
		(layer "In9.Cu")
		(net "M_A_BS1")
	)
	(segment
		(start 118.796562 -55.25135)
		(end 110.16615 -55.25135)
		(width 0.1905)
		(layer "In9.Cu")
		(net "M_A_BS1")
	)
	(segment
		(start 108.9152 -54.0004)
		(end 108.502196 -53.587396)
		(width 0.1016)
		(layer "In9.Cu")
		(net "M_A_BS1")
	)
	(segment
		(start 108.502196 -53.587396)
		(end 107.960414 -53.587396)
		(width 0.1016)
		(layer "In9.Cu")
		(net "M_A_BS1")
	)
	(segment
		(start 118.987062 -55.06085)
		(end 118.796562 -55.25135)
		(width 0.1905)
		(layer "In9.Cu")
		(net "M_A_BS1")
	)
	(segment
		(start 107.139994 -52.766976)
		(end 107.139994 -51.461162)
		(width 0.1016)
		(layer "In9.Cu")
		(net "M_A_BS1")
	)
	(segment
		(start 154.83078 -63.219076)
		(end 154.422348 -63.627508)
		(width 0.1905)
		(layer "In9.Cu")
		(net "M_A_BS1")
	)
	(segment
		(start 153.61412 -63.08852)
		(end 153.61412 -62.81928)
		(width 0.1905)
		(layer "In9.Cu")
		(net "M_A_BS1")
	)
	(segment
		(start 150.908258 -59.432698)
		(end 150.908258 -59.432444)
		(width 0.1905)
		(layer "In9.Cu")
		(net "M_A_BS1")
	)
	(segment
		(start 120.511062 -54.917086)
		(end 120.511062 -55.06085)
		(width 0.1905)
		(layer "In9.Cu")
		(net "M_A_BS1")
	)
	(segment
		(start 155.178252 -65.446148)
		(end 155.406852 -65.446148)
		(width 0.1905)
		(layer "In9.Cu")
		(net "M_A_BS1")
	)
	(segment
		(start 154.022552 -62.410848)
		(end 154.022552 -62.074552)
		(width 0.1905)
		(layer "In9.Cu")
		(net "M_A_BS1")
	)
	(segment
		(start 155.406852 -65.446148)
		(end 155.8544 -64.9986)
		(width 0.1905)
		(layer "In9.Cu")
		(net "M_A_BS1")
	)
	(segment
		(start 121.082562 -54.726586)
		(end 120.701562 -54.726586)
		(width 0.1905)
		(layer "In9.Cu")
		(net "M_A_BS1")
	)
	(segment
		(start 155.330144 -67.15379)
		(end 155.31211 -67.15379)
		(width 0.1905)
		(layer "In9.Cu")
		(net "M_A_BS1")
	)
	(segment
		(start 118.987062 -54.917086)
		(end 118.987062 -55.06085)
		(width 0.1905)
		(layer "In9.Cu")
		(net "M_A_BS1")
	)
	(segment
		(start 121.273062 -55.06085)
		(end 121.273062 -54.917086)
		(width 0.1905)
		(layer "In9.Cu")
		(net "M_A_BS1")
	)
	(segment
		(start 120.320562 -55.25135)
		(end 119.939562 -55.25135)
		(width 0.1905)
		(layer "In9.Cu")
		(net "M_A_BS1")
	)
	(segment
		(start 154.153108 -63.627508)
		(end 153.61412 -63.08852)
		(width 0.1905)
		(layer "In9.Cu")
		(net "M_A_BS1")
	)
	(segment
		(start 110.16615 -55.25135)
		(end 108.9152 -54.0004)
		(width 0.1905)
		(layer "In9.Cu")
		(net "M_A_BS1")
	)
	(segment
		(start 151.85771 -60.38215)
		(end 150.908258 -59.432698)
		(width 0.1905)
		(layer "In9.Cu")
		(net "M_A_BS1")
	)
	(segment
		(start 154.4574 -66.29908)
		(end 154.4574 -66.167)
		(width 0.1905)
		(layer "In9.Cu")
		(net "M_A_BS1")
	)
	(segment
		(start 154.4574 -66.167)
		(end 155.178252 -65.446148)
		(width 0.1905)
		(layer "In9.Cu")
		(net "M_A_BS1")
	)
	(segment
		(start 154.022552 -62.074552)
		(end 152.33015 -60.38215)
		(width 0.1905)
		(layer "In9.Cu")
		(net "M_A_BS1")
	)
	(segment
		(start 153.61412 -62.81928)
		(end 154.022552 -62.410848)
		(width 0.1905)
		(layer "In9.Cu")
		(net "M_A_BS1")
	)
	(segment
		(start 121.463562 -55.25135)
		(end 121.273062 -55.06085)
		(width 0.1905)
		(layer "In9.Cu")
		(net "M_A_BS1")
	)
	(segment
		(start 152.33015 -60.38215)
		(end 151.85771 -60.38215)
		(width 0.1905)
		(layer "In9.Cu")
		(net "M_A_BS1")
	)
	(segment
		(start 120.511062 -55.06085)
		(end 120.320562 -55.25135)
		(width 0.1905)
		(layer "In9.Cu")
		(net "M_A_BS1")
	)
	(segment
		(start 119.939562 -55.25135)
		(end 119.749062 -55.06085)
		(width 0.1905)
		(layer "In9.Cu")
		(net "M_A_BS1")
	)
	(segment
		(start 155.10002 -63.219076)
		(end 154.83078 -63.219076)
		(width 0.1905)
		(layer "In9.Cu")
		(net "M_A_BS1")
	)
	(segment
		(start 119.558562 -54.726586)
		(end 119.177562 -54.726586)
		(width 0.1905)
		(layer "In9.Cu")
		(net "M_A_BS1")
	)
	(segment
		(start 155.8544 -64.9986)
		(end 155.8544 -63.973456)
		(width 0.1905)
		(layer "In9.Cu")
		(net "M_A_BS1")
	)
	(segment
		(start 154.422348 -63.627508)
		(end 154.153108 -63.627508)
		(width 0.1905)
		(layer "In9.Cu")
		(net "M_A_BS1")
	)
	(segment
		(start 149.227032 -57.751218)
		(end 147.886928 -57.751218)
		(width 0.1905)
		(layer "In9.Cu")
		(net "M_A_BS1")
	)
	(segment
		(start 107.960414 -53.587396)
		(end 107.139994 -52.766976)
		(width 0.1016)
		(layer "In9.Cu")
		(net "M_A_BS1")
	)
	(segment
		(start 145.38706 -55.25135)
		(end 121.463562 -55.25135)
		(width 0.1905)
		(layer "In9.Cu")
		(net "M_A_BS1")
	)
	(segment
		(start 119.749062 -55.06085)
		(end 119.749062 -54.917086)
		(width 0.1905)
		(layer "In9.Cu")
		(net "M_A_BS1")
	)
	(segment
		(start 83.266788 -30.785054)
		(end 83.5914 -30.460442)
		(width 0.1397)
		(layer "F.Cu")
		(net "CLK_100M_CPU_SATA3_DN")
	)
	(segment
		(start 83.5914 -30.460442)
		(end 83.67141 -30.460442)
		(width 0.1397)
		(layer "F.Cu")
		(net "CLK_100M_CPU_SATA3_DN")
	)
	(via
		(at 59.65825 -35.37966)
		(size 0.508)
		(drill 0.254)
		(layers "F.Cu" "B.Cu")
		(net "CLK_100M_CPU_SATA3_DN")
	)
	(via
		(at 83.67141 -30.460442)
		(size 0.4318)
		(drill 0.2032)
		(layers "F.Cu" "B.Cu")
		(net "CLK_100M_CPU_SATA3_DN")
	)
	(segment
		(start 58.185558 -37.31514)
		(end 57.997598 -37.12718)
		(width 0.1397)
		(layer "B.Cu")
		(net "CLK_100M_CPU_SATA3_DN")
	)
	(segment
		(start 56.5531 -52.637182)
		(end 56.5531 -47.25924)
		(width 0.1397)
		(layer "B.Cu")
		(net "CLK_100M_CPU_SATA3_DN")
	)
	(segment
		(start 58.185558 -41.778682)
		(end 58.185558 -37.31514)
		(width 0.1397)
		(layer "B.Cu")
		(net "CLK_100M_CPU_SATA3_DN")
	)
	(segment
		(start 58.4962 -35.687)
		(end 59.35091 -35.687)
		(width 0.1397)
		(layer "B.Cu")
		(net "CLK_100M_CPU_SATA3_DN")
	)
	(segment
		(start 56.953658 -43.010582)
		(end 58.185558 -41.778682)
		(width 0.1397)
		(layer "B.Cu")
		(net "CLK_100M_CPU_SATA3_DN")
	)
	(segment
		(start 47.658782 -52.177442)
		(end 48.99914 -53.5178)
		(width 0.1397)
		(layer "B.Cu")
		(net "CLK_100M_CPU_SATA3_DN")
	)
	(segment
		(start 56.5531 -47.25924)
		(end 55.6641 -46.37024)
		(width 0.1397)
		(layer "B.Cu")
		(net "CLK_100M_CPU_SATA3_DN")
	)
	(segment
		(start 55.6641 -46.37024)
		(end 55.6641 -44.7929)
		(width 0.1397)
		(layer "B.Cu")
		(net "CLK_100M_CPU_SATA3_DN")
	)
	(segment
		(start 56.953658 -43.503342)
		(end 56.953658 -43.010582)
		(width 0.1397)
		(layer "B.Cu")
		(net "CLK_100M_CPU_SATA3_DN")
	)
	(segment
		(start 57.997598 -37.12718)
		(end 57.997598 -36.185602)
		(width 0.1397)
		(layer "B.Cu")
		(net "CLK_100M_CPU_SATA3_DN")
	)
	(segment
		(start 55.672482 -53.5178)
		(end 56.5531 -52.637182)
		(width 0.1397)
		(layer "B.Cu")
		(net "CLK_100M_CPU_SATA3_DN")
	)
	(segment
		(start 55.6641 -44.7929)
		(end 56.953658 -43.503342)
		(width 0.1397)
		(layer "B.Cu")
		(net "CLK_100M_CPU_SATA3_DN")
	)
	(segment
		(start 47.658782 -51.70678)
		(end 47.658782 -52.177442)
		(width 0.1397)
		(layer "B.Cu")
		(net "CLK_100M_CPU_SATA3_DN")
	)
	(segment
		(start 48.99914 -53.5178)
		(end 55.672482 -53.5178)
		(width 0.1397)
		(layer "B.Cu")
		(net "CLK_100M_CPU_SATA3_DN")
	)
	(segment
		(start 57.997598 -36.185602)
		(end 58.4962 -35.687)
		(width 0.1397)
		(layer "B.Cu")
		(net "CLK_100M_CPU_SATA3_DN")
	)
	(segment
		(start 59.35091 -35.687)
		(end 59.65825 -35.37966)
		(width 0.1397)
		(layer "B.Cu")
		(net "CLK_100M_CPU_SATA3_DN")
	)
	(segment
		(start 81.642204 -29.33954)
		(end 81.337404 -29.33954)
		(width 0.1016)
		(layer "In4.Cu")
		(net "CLK_100M_CPU_SATA3_DN")
	)
	(segment
		(start 80.348328 -29.4386)
		(end 80.030574 -29.120846)
		(width 0.1016)
		(layer "In4.Cu")
		(net "CLK_100M_CPU_SATA3_DN")
	)
	(segment
		(start 61.506608 -34.429192)
		(end 61.264038 -34.671762)
		(width 0.1143)
		(layer "In4.Cu")
		(net "CLK_100M_CPU_SATA3_DN")
	)
	(segment
		(start 81.337404 -29.33954)
		(end 81.238344 -29.4386)
		(width 0.1016)
		(layer "In4.Cu")
		(net "CLK_100M_CPU_SATA3_DN")
	)
	(segment
		(start 60.2234 -35.7124)
		(end 59.99099 -35.7124)
		(width 0.1143)
		(layer "In4.Cu")
		(net "CLK_100M_CPU_SATA3_DN")
	)
	(segment
		(start 77.182472 -28.5496)
		(end 76.74483 -28.987242)
		(width 0.1016)
		(layer "In4.Cu")
		(net "CLK_100M_CPU_SATA3_DN")
	)
	(segment
		(start 60.71997 -34.914078)
		(end 60.71997 -35.21583)
		(width 0.1143)
		(layer "In4.Cu")
		(net "CLK_100M_CPU_SATA3_DN")
	)
	(segment
		(start 82.046064 -29.4386)
		(end 81.741264 -29.4386)
		(width 0.1016)
		(layer "In4.Cu")
		(net "CLK_100M_CPU_SATA3_DN")
	)
	(segment
		(start 79.459328 -28.5496)
		(end 77.182472 -28.5496)
		(width 0.1016)
		(layer "In4.Cu")
		(net "CLK_100M_CPU_SATA3_DN")
	)
	(segment
		(start 60.71997 -35.21583)
		(end 60.2234 -35.7124)
		(width 0.1143)
		(layer "In4.Cu")
		(net "CLK_100M_CPU_SATA3_DN")
	)
	(segment
		(start 61.506608 -34.12744)
		(end 61.506608 -34.429192)
		(width 0.1143)
		(layer "In4.Cu")
		(net "CLK_100M_CPU_SATA3_DN")
	)
	(segment
		(start 82.401664 -29.654246)
		(end 82.26171 -29.654246)
		(width 0.1016)
		(layer "In4.Cu")
		(net "CLK_100M_CPU_SATA3_DN")
	)
	(segment
		(start 80.030574 -28.980638)
		(end 79.814928 -28.765246)
		(width 0.1016)
		(layer "In4.Cu")
		(net "CLK_100M_CPU_SATA3_DN")
	)
	(segment
		(start 80.030574 -29.120846)
		(end 80.030574 -28.980638)
		(width 0.1016)
		(layer "In4.Cu")
		(net "CLK_100M_CPU_SATA3_DN")
	)
	(segment
		(start 61.748924 -33.885124)
		(end 61.506608 -34.12744)
		(width 0.1143)
		(layer "In4.Cu")
		(net "CLK_100M_CPU_SATA3_DN")
	)
	(segment
		(start 76.006706 -29.63545)
		(end 72.361044 -29.63545)
		(width 0.1143)
		(layer "In4.Cu")
		(net "CLK_100M_CPU_SATA3_DN")
	)
	(segment
		(start 79.814928 -28.765246)
		(end 79.674974 -28.765246)
		(width 0.1016)
		(layer "In4.Cu")
		(net "CLK_100M_CPU_SATA3_DN")
	)
	(segment
		(start 82.61731 -30.009846)
		(end 82.61731 -29.869638)
		(width 0.1016)
		(layer "In4.Cu")
		(net "CLK_100M_CPU_SATA3_DN")
	)
	(segment
		(start 61.264038 -34.671762)
		(end 60.962286 -34.671762)
		(width 0.1143)
		(layer "In4.Cu")
		(net "CLK_100M_CPU_SATA3_DN")
	)
	(segment
		(start 65.8876 -30.0482)
		(end 62.050676 -33.885124)
		(width 0.1143)
		(layer "In4.Cu")
		(net "CLK_100M_CPU_SATA3_DN")
	)
	(segment
		(start 81.741264 -29.4386)
		(end 81.642204 -29.33954)
		(width 0.1016)
		(layer "In4.Cu")
		(net "CLK_100M_CPU_SATA3_DN")
	)
	(segment
		(start 76.654914 -28.987242)
		(end 76.637134 -29.005022)
		(width 0.1016)
		(layer "In4.Cu")
		(net "CLK_100M_CPU_SATA3_DN")
	)
	(segment
		(start 62.050676 -33.885124)
		(end 61.748924 -33.885124)
		(width 0.1143)
		(layer "In4.Cu")
		(net "CLK_100M_CPU_SATA3_DN")
	)
	(segment
		(start 76.74483 -28.987242)
		(end 76.654914 -28.987242)
		(width 0.1016)
		(layer "In4.Cu")
		(net "CLK_100M_CPU_SATA3_DN")
	)
	(segment
		(start 81.238344 -29.4386)
		(end 80.348328 -29.4386)
		(width 0.1016)
		(layer "In4.Cu")
		(net "CLK_100M_CPU_SATA3_DN")
	)
	(segment
		(start 83.474052 -30.6578)
		(end 83.265264 -30.6578)
		(width 0.1016)
		(layer "In4.Cu")
		(net "CLK_100M_CPU_SATA3_DN")
	)
	(segment
		(start 71.948294 -30.0482)
		(end 65.8876 -30.0482)
		(width 0.1143)
		(layer "In4.Cu")
		(net "CLK_100M_CPU_SATA3_DN")
	)
	(segment
		(start 59.99099 -35.7124)
		(end 59.65825 -35.37966)
		(width 0.1143)
		(layer "In4.Cu")
		(net "CLK_100M_CPU_SATA3_DN")
	)
	(segment
		(start 83.265264 -30.6578)
		(end 82.61731 -30.009846)
		(width 0.1016)
		(layer "In4.Cu")
		(net "CLK_100M_CPU_SATA3_DN")
	)
	(segment
		(start 82.61731 -29.869638)
		(end 82.401664 -29.654246)
		(width 0.1016)
		(layer "In4.Cu")
		(net "CLK_100M_CPU_SATA3_DN")
	)
	(segment
		(start 82.26171 -29.654246)
		(end 82.046064 -29.4386)
		(width 0.1016)
		(layer "In4.Cu")
		(net "CLK_100M_CPU_SATA3_DN")
	)
	(segment
		(start 60.962286 -34.671762)
		(end 60.71997 -34.914078)
		(width 0.1143)
		(layer "In4.Cu")
		(net "CLK_100M_CPU_SATA3_DN")
	)
	(segment
		(start 79.674974 -28.765246)
		(end 79.459328 -28.5496)
		(width 0.1016)
		(layer "In4.Cu")
		(net "CLK_100M_CPU_SATA3_DN")
	)
	(segment
		(start 83.67141 -30.460442)
		(end 83.474052 -30.6578)
		(width 0.1016)
		(layer "In4.Cu")
		(net "CLK_100M_CPU_SATA3_DN")
	)
	(segment
		(start 72.361044 -29.63545)
		(end 71.948294 -30.0482)
		(width 0.1143)
		(layer "In4.Cu")
		(net "CLK_100M_CPU_SATA3_DN")
	)
	(segment
		(start 76.637134 -29.005022)
		(end 76.006706 -29.63545)
		(width 0.1143)
		(layer "In4.Cu")
		(net "CLK_100M_CPU_SATA3_DN")
	)
	(segment
		(start 156.550106 -70.806564)
		(end 156.550106 -68.882006)
		(width 0.2413)
		(layer "F.Cu")
		(net "M_A_MA1")
	)
	(segment
		(start 157.27172 -68.160392)
		(end 157.27172 -67.40652)
		(width 0.2413)
		(layer "F.Cu")
		(net "M_A_MA1")
	)
	(segment
		(start 157.27172 -67.40652)
		(end 157.2514 -67.3862)
		(width 0.2413)
		(layer "F.Cu")
		(net "M_A_MA1")
	)
	(segment
		(start 156.550106 -68.882006)
		(end 157.27172 -68.160392)
		(width 0.2413)
		(layer "F.Cu")
		(net "M_A_MA1")
	)
	(segment
		(start 108.46689 -50.844196)
		(end 107.907328 -50.844196)
		(width 0.1016)
		(layer "F.Cu")
		(net "M_A_MA1")
	)
	(segment
		(start 108.575348 -50.952654)
		(end 108.46689 -50.844196)
		(width 0.1016)
		(layer "F.Cu")
		(net "M_A_MA1")
	)
	(via
		(at 107.907328 -50.844196)
		(size 0.4318)
		(drill 0.2032)
		(layers "F.Cu" "B.Cu")
		(net "M_A_MA1")
	)
	(via
		(at 157.2514 -67.3862)
		(size 0.4318)
		(drill 0.2032)
		(layers "F.Cu" "B.Cu")
		(net "M_A_MA1")
	)
	(segment
		(start 156.550106 -62.599824)
		(end 156.550106 -65.338706)
		(width 0.2413)
		(layer "B.Cu")
		(net "M_A_MA1")
	)
	(segment
		(start 156.550106 -65.338706)
		(end 156.846778 -65.635378)
		(width 0.2413)
		(layer "B.Cu")
		(net "M_A_MA1")
	)
	(segment
		(start 157.2514 -67.376294)
		(end 157.2514 -67.3862)
		(width 0.2413)
		(layer "B.Cu")
		(net "M_A_MA1")
	)
	(segment
		(start 156.79547 -66.920364)
		(end 157.2514 -67.376294)
		(width 0.2413)
		(layer "B.Cu")
		(net "M_A_MA1")
	)
	(segment
		(start 156.846778 -65.635378)
		(end 156.846778 -66.47434)
		(width 0.2413)
		(layer "B.Cu")
		(net "M_A_MA1")
	)
	(segment
		(start 156.79547 -66.525648)
		(end 156.79547 -66.920364)
		(width 0.2413)
		(layer "B.Cu")
		(net "M_A_MA1")
	)
	(segment
		(start 156.846778 -66.47434)
		(end 156.79547 -66.525648)
		(width 0.2413)
		(layer "B.Cu")
		(net "M_A_MA1")
	)
	(segment
		(start 132.881116 -53.38445)
		(end 132.500116 -53.38445)
		(width 0.1905)
		(layer "In9.Cu")
		(net "M_A_MA1")
	)
	(segment
		(start 131.547616 -53.57495)
		(end 131.357116 -53.38445)
		(width 0.1905)
		(layer "In9.Cu")
		(net "M_A_MA1")
	)
	(segment
		(start 132.500116 -53.38445)
		(end 132.309616 -53.57495)
		(width 0.1905)
		(layer "In9.Cu")
		(net "M_A_MA1")
	)
	(segment
		(start 147.75815 -54.453536)
		(end 146.349466 -54.453536)
		(width 0.1905)
		(layer "In9.Cu")
		(net "M_A_MA1")
	)
	(segment
		(start 118.40464 -53.38445)
		(end 117.89664 -53.89245)
		(width 0.1905)
		(layer "In9.Cu")
		(net "M_A_MA1")
	)
	(segment
		(start 152.46985 -59.07405)
		(end 152.378664 -59.07405)
		(width 0.1905)
		(layer "In9.Cu")
		(net "M_A_MA1")
	)
	(segment
		(start 156.82087 -66.90995)
		(end 156.82087 -66.199258)
		(width 0.1905)
		(layer "In9.Cu")
		(net "M_A_MA1")
	)
	(segment
		(start 131.738116 -53.96865)
		(end 131.547616 -53.77815)
		(width 0.1905)
		(layer "In9.Cu")
		(net "M_A_MA1")
	)
	(segment
		(start 145.86458 -53.96865)
		(end 133.262116 -53.96865)
		(width 0.1905)
		(layer "In9.Cu")
		(net "M_A_MA1")
	)
	(segment
		(start 117.89664 -53.89245)
		(end 110.28045 -53.89245)
		(width 0.1905)
		(layer "In9.Cu")
		(net "M_A_MA1")
	)
	(segment
		(start 133.071616 -53.57495)
		(end 132.881116 -53.38445)
		(width 0.1905)
		(layer "In9.Cu")
		(net "M_A_MA1")
	)
	(segment
		(start 110.28045 -53.89245)
		(end 108.9406 -52.5526)
		(width 0.1016)
		(layer "In9.Cu")
		(net "M_A_MA1")
	)
	(segment
		(start 156.821378 -65.813178)
		(end 156.5656 -65.5574)
		(width 0.1905)
		(layer "In9.Cu")
		(net "M_A_MA1")
	)
	(segment
		(start 156.5656 -65.5574)
		(end 156.5656 -63.1698)
		(width 0.1905)
		(layer "In9.Cu")
		(net "M_A_MA1")
	)
	(segment
		(start 130.595116 -53.96865)
		(end 129.503424 -53.96865)
		(width 0.1905)
		(layer "In9.Cu")
		(net "M_A_MA1")
	)
	(segment
		(start 107.711494 -52.263294)
		(end 107.711494 -51.04003)
		(width 0.1016)
		(layer "In9.Cu")
		(net "M_A_MA1")
	)
	(segment
		(start 152.378664 -59.07405)
		(end 147.75815 -54.453536)
		(width 0.1905)
		(layer "In9.Cu")
		(net "M_A_MA1")
	)
	(segment
		(start 128.919224 -53.38445)
		(end 118.40464 -53.38445)
		(width 0.1905)
		(layer "In9.Cu")
		(net "M_A_MA1")
	)
	(segment
		(start 108.0008 -52.5526)
		(end 107.711494 -52.263294)
		(width 0.1016)
		(layer "In9.Cu")
		(net "M_A_MA1")
	)
	(segment
		(start 157.2514 -67.3862)
		(end 157.2514 -67.34048)
		(width 0.1905)
		(layer "In9.Cu")
		(net "M_A_MA1")
	)
	(segment
		(start 146.349466 -54.453536)
		(end 145.86458 -53.96865)
		(width 0.1905)
		(layer "In9.Cu")
		(net "M_A_MA1")
	)
	(segment
		(start 156.821378 -66.19875)
		(end 156.821378 -65.813178)
		(width 0.1905)
		(layer "In9.Cu")
		(net "M_A_MA1")
	)
	(segment
		(start 108.9406 -52.5526)
		(end 108.0008 -52.5526)
		(width 0.1016)
		(layer "In9.Cu")
		(net "M_A_MA1")
	)
	(segment
		(start 132.309616 -53.77815)
		(end 132.119116 -53.96865)
		(width 0.1905)
		(layer "In9.Cu")
		(net "M_A_MA1")
	)
	(segment
		(start 107.711494 -51.04003)
		(end 107.907328 -50.844196)
		(width 0.1016)
		(layer "In9.Cu")
		(net "M_A_MA1")
	)
	(segment
		(start 131.547616 -53.77815)
		(end 131.547616 -53.57495)
		(width 0.1905)
		(layer "In9.Cu")
		(net "M_A_MA1")
	)
	(segment
		(start 129.503424 -53.96865)
		(end 128.919224 -53.38445)
		(width 0.1905)
		(layer "In9.Cu")
		(net "M_A_MA1")
	)
	(segment
		(start 130.785616 -53.77815)
		(end 130.595116 -53.96865)
		(width 0.1905)
		(layer "In9.Cu")
		(net "M_A_MA1")
	)
	(segment
		(start 131.357116 -53.38445)
		(end 130.976116 -53.38445)
		(width 0.1905)
		(layer "In9.Cu")
		(net "M_A_MA1")
	)
	(segment
		(start 132.309616 -53.57495)
		(end 132.309616 -53.77815)
		(width 0.1905)
		(layer "In9.Cu")
		(net "M_A_MA1")
	)
	(segment
		(start 130.976116 -53.38445)
		(end 130.785616 -53.57495)
		(width 0.1905)
		(layer "In9.Cu")
		(net "M_A_MA1")
	)
	(segment
		(start 132.119116 -53.96865)
		(end 131.738116 -53.96865)
		(width 0.1905)
		(layer "In9.Cu")
		(net "M_A_MA1")
	)
	(segment
		(start 133.262116 -53.96865)
		(end 133.071616 -53.77815)
		(width 0.1905)
		(layer "In9.Cu")
		(net "M_A_MA1")
	)
	(segment
		(start 157.2514 -67.34048)
		(end 156.82087 -66.90995)
		(width 0.1905)
		(layer "In9.Cu")
		(net "M_A_MA1")
	)
	(segment
		(start 156.5656 -63.1698)
		(end 152.46985 -59.07405)
		(width 0.1905)
		(layer "In9.Cu")
		(net "M_A_MA1")
	)
	(segment
		(start 130.785616 -53.57495)
		(end 130.785616 -53.77815)
		(width 0.1905)
		(layer "In9.Cu")
		(net "M_A_MA1")
	)
	(segment
		(start 156.82087 -66.199258)
		(end 156.821378 -66.19875)
		(width 0.1905)
		(layer "In9.Cu")
		(net "M_A_MA1")
	)
	(segment
		(start 133.071616 -53.77815)
		(end 133.071616 -53.57495)
		(width 0.1905)
		(layer "In9.Cu")
		(net "M_A_MA1")
	)
	(segment
		(start 46.2534 -54.2671)
		(end 46.6344 -54.6481)
		(width 0.508)
		(layer "F.Cu")
		(net "P3V3_CLK_VDD25")
	)
	(segment
		(start 44.5008 -51.6382)
		(end 45.2628 -51.6382)
		(width 0.3048)
		(layer "F.Cu")
		(net "P3V3_CLK_VDD25")
	)
	(segment
		(start 45.4152 -51.7906)
		(end 46.1772 -51.7906)
		(width 0.3048)
		(layer "F.Cu")
		(net "P3V3_CLK_VDD25")
	)
	(segment
		(start 46.2534 -52.8066)
		(end 46.2534 -51.8668)
		(width 0.3048)
		(layer "F.Cu")
		(net "P3V3_CLK_VDD25")
	)
	(segment
		(start 44.383706 -52.674774)
		(end 44.383706 -51.755294)
		(width 0.3048)
		(layer "F.Cu")
		(net "P3V3_CLK_VDD25")
	)
	(segment
		(start 46.2534 -51.8668)
		(end 46.1772 -51.7906)
		(width 0.3048)
		(layer "F.Cu")
		(net "P3V3_CLK_VDD25")
	)
	(segment
		(start 44.383706 -51.755294)
		(end 44.5008 -51.6382)
		(width 0.3048)
		(layer "F.Cu")
		(net "P3V3_CLK_VDD25")
	)
	(segment
		(start 45.2628 -51.6382)
		(end 45.4152 -51.7906)
		(width 0.3048)
		(layer "F.Cu")
		(net "P3V3_CLK_VDD25")
	)
	(segment
		(start 46.2534 -52.8066)
		(end 46.2534 -54.2671)
		(width 0.508)
		(layer "F.Cu")
		(net "P3V3_CLK_VDD25")
	)
	(via
		(at 46.2534 -52.8066)
		(size 0.7112)
		(drill 0.3556)
		(layers "F.Cu" "B.Cu")
		(net "P3V3_CLK_VDD25")
	)
	(via
		(at 44.383706 -52.674774)
		(size 0.508)
		(drill 0.254)
		(layers "F.Cu" "B.Cu")
		(net "P3V3_CLK_VDD25")
	)
	(segment
		(start 44.458636 -52.580032)
		(end 44.383706 -52.654962)
		(width 0.2032)
		(layer "B.Cu")
		(net "P3V3_CLK_VDD25")
	)
	(segment
		(start 44.458636 -51.70678)
		(end 44.458636 -52.580032)
		(width 0.2032)
		(layer "B.Cu")
		(net "P3V3_CLK_VDD25")
	)
	(segment
		(start 44.383706 -52.654962)
		(end 44.383706 -52.674774)
		(width 0.2032)
		(layer "B.Cu")
		(net "P3V3_CLK_VDD25")
	)
	(segment
		(start 44.058586 -52.349654)
		(end 44.383706 -52.674774)
		(width 0.2032)
		(layer "B.Cu")
		(net "P3V3_CLK_VDD25")
	)
	(segment
		(start 44.058586 -51.70678)
		(end 44.058586 -52.349654)
		(width 0.2032)
		(layer "B.Cu")
		(net "P3V3_CLK_VDD25")
	)
	(segment
		(start 131.797806 -66.407284)
		(end 131.532884 -66.672206)
		(width 0.1778)
		(layer "F.Cu")
		(net "M_A_DQS_DP7")
	)
	(segment
		(start 131.649978 -62.59322)
		(end 131.649978 -63.362586)
		(width 0.1778)
		(layer "F.Cu")
		(net "M_A_DQS_DP7")
	)
	(segment
		(start 95.842836 -52.545742)
		(end 95.745808 -52.448714)
		(width 0.1016)
		(layer "F.Cu")
		(net "M_A_DQS_DP7")
	)
	(segment
		(start 131.797806 -63.510414)
		(end 131.797806 -66.407284)
		(width 0.1778)
		(layer "F.Cu")
		(net "M_A_DQS_DP7")
	)
	(segment
		(start 95.5802 -53.594)
		(end 95.842836 -53.331364)
		(width 0.1016)
		(layer "F.Cu")
		(net "M_A_DQS_DP7")
	)
	(segment
		(start 95.842836 -53.331364)
		(end 95.842836 -52.545742)
		(width 0.1016)
		(layer "F.Cu")
		(net "M_A_DQS_DP7")
	)
	(segment
		(start 131.649978 -63.362586)
		(end 131.797806 -63.510414)
		(width 0.1778)
		(layer "F.Cu")
		(net "M_A_DQS_DP7")
	)
	(via
		(at 131.532884 -66.672206)
		(size 0.4318)
		(drill 0.2032)
		(layers "F.Cu" "B.Cu")
		(net "M_A_DQS_DP7")
	)
	(via
		(at 95.5802 -53.594)
		(size 0.4318)
		(drill 0.2032)
		(layers "F.Cu" "B.Cu")
		(net "M_A_DQS_DP7")
	)
	(segment
		(start 131.649978 -70.79996)
		(end 131.649978 -70.058026)
		(width 0.1778)
		(layer "B.Cu")
		(net "M_A_DQS_DP7")
	)
	(segment
		(start 131.797806 -69.910198)
		(end 131.797806 -66.937128)
		(width 0.1778)
		(layer "B.Cu")
		(net "M_A_DQS_DP7")
	)
	(segment
		(start 131.797806 -66.937128)
		(end 131.532884 -66.672206)
		(width 0.1778)
		(layer "B.Cu")
		(net "M_A_DQS_DP7")
	)
	(segment
		(start 131.649978 -70.058026)
		(end 131.797806 -69.910198)
		(width 0.1778)
		(layer "B.Cu")
		(net "M_A_DQS_DP7")
	)
	(segment
		(start 117.065298 -65.763902)
		(end 124.355098 -65.763902)
		(width 0.1524)
		(layer "In7.Cu")
		(net "M_A_DQS_DP7")
	)
	(segment
		(start 128.6002 -63.627)
		(end 131.5466 -63.627)
		(width 0.1524)
		(layer "In7.Cu")
		(net "M_A_DQS_DP7")
	)
	(segment
		(start 96.415352 -61.939424)
		(end 100.769928 -66.294)
		(width 0.1524)
		(layer "In7.Cu")
		(net "M_A_DQS_DP7")
	)
	(segment
		(start 110.96879 -66.41846)
		(end 111.09325 -66.294)
		(width 0.1524)
		(layer "In7.Cu")
		(net "M_A_DQS_DP7")
	)
	(segment
		(start 100.769928 -66.294)
		(end 103.280464 -66.294)
		(width 0.1524)
		(layer "In7.Cu")
		(net "M_A_DQS_DP7")
	)
	(segment
		(start 126.238 -66.0654)
		(end 126.873 -66.0654)
		(width 0.1524)
		(layer "In7.Cu")
		(net "M_A_DQS_DP7")
	)
	(segment
		(start 115.74653 -66.294)
		(end 116.5352 -66.294)
		(width 0.1524)
		(layer "In7.Cu")
		(net "M_A_DQS_DP7")
	)
	(segment
		(start 115.62207 -66.41846)
		(end 115.74653 -66.294)
		(width 0.1524)
		(layer "In7.Cu")
		(net "M_A_DQS_DP7")
	)
	(segment
		(start 113.87709 -66.294)
		(end 114.00155 -66.41846)
		(width 0.1524)
		(layer "In7.Cu")
		(net "M_A_DQS_DP7")
	)
	(segment
		(start 131.5466 -63.627)
		(end 131.8006 -63.881)
		(width 0.1524)
		(layer "In7.Cu")
		(net "M_A_DQS_DP7")
	)
	(segment
		(start 114.00155 -66.41846)
		(end 114.45875 -66.41846)
		(width 0.1524)
		(layer "In7.Cu")
		(net "M_A_DQS_DP7")
	)
	(segment
		(start 109.22381 -66.294)
		(end 109.34827 -66.41846)
		(width 0.1524)
		(layer "In7.Cu")
		(net "M_A_DQS_DP7")
	)
	(segment
		(start 116.5352 -66.294)
		(end 117.065298 -65.763902)
		(width 0.1524)
		(layer "In7.Cu")
		(net "M_A_DQS_DP7")
	)
	(segment
		(start 132.1816 -65.317624)
		(end 132.1816 -65.619376)
		(width 0.1524)
		(layer "In7.Cu")
		(net "M_A_DQS_DP7")
	)
	(segment
		(start 128.3462 -63.881)
		(end 128.6002 -63.627)
		(width 0.1524)
		(layer "In7.Cu")
		(net "M_A_DQS_DP7")
	)
	(segment
		(start 125.5014 -65.3288)
		(end 126.238 -66.0654)
		(width 0.1524)
		(layer "In7.Cu")
		(net "M_A_DQS_DP7")
	)
	(segment
		(start 95.5802 -53.594)
		(end 95.1484 -54.0258)
		(width 0.1524)
		(layer "In7.Cu")
		(net "M_A_DQS_DP7")
	)
	(segment
		(start 96.415352 -59.864752)
		(end 96.415352 -61.939424)
		(width 0.1524)
		(layer "In7.Cu")
		(net "M_A_DQS_DP7")
	)
	(segment
		(start 109.80547 -66.41846)
		(end 109.92993 -66.294)
		(width 0.1524)
		(layer "In7.Cu")
		(net "M_A_DQS_DP7")
	)
	(segment
		(start 103.986584 -66.294)
		(end 104.443784 -66.294)
		(width 0.1524)
		(layer "In7.Cu")
		(net "M_A_DQS_DP7")
	)
	(segment
		(start 105.025444 -66.41846)
		(end 105.149904 -66.294)
		(width 0.1524)
		(layer "In7.Cu")
		(net "M_A_DQS_DP7")
	)
	(segment
		(start 112.83823 -66.41846)
		(end 113.29543 -66.41846)
		(width 0.1524)
		(layer "In7.Cu")
		(net "M_A_DQS_DP7")
	)
	(segment
		(start 105.149904 -66.294)
		(end 105.607104 -66.294)
		(width 0.1524)
		(layer "In7.Cu")
		(net "M_A_DQS_DP7")
	)
	(segment
		(start 103.280464 -66.294)
		(end 103.404924 -66.41846)
		(width 0.1524)
		(layer "In7.Cu")
		(net "M_A_DQS_DP7")
	)
	(segment
		(start 115.04041 -66.294)
		(end 115.16487 -66.41846)
		(width 0.1524)
		(layer "In7.Cu")
		(net "M_A_DQS_DP7")
	)
	(segment
		(start 111.09325 -66.294)
		(end 111.55045 -66.294)
		(width 0.1524)
		(layer "In7.Cu")
		(net "M_A_DQS_DP7")
	)
	(segment
		(start 131.8006 -66.40449)
		(end 131.532884 -66.672206)
		(width 0.1524)
		(layer "In7.Cu")
		(net "M_A_DQS_DP7")
	)
	(segment
		(start 131.8006 -66.000376)
		(end 131.8006 -66.40449)
		(width 0.1524)
		(layer "In7.Cu")
		(net "M_A_DQS_DP7")
	)
	(segment
		(start 103.404924 -66.41846)
		(end 103.862124 -66.41846)
		(width 0.1524)
		(layer "In7.Cu")
		(net "M_A_DQS_DP7")
	)
	(segment
		(start 109.92993 -66.294)
		(end 110.38713 -66.294)
		(width 0.1524)
		(layer "In7.Cu")
		(net "M_A_DQS_DP7")
	)
	(segment
		(start 110.38713 -66.294)
		(end 110.51159 -66.41846)
		(width 0.1524)
		(layer "In7.Cu")
		(net "M_A_DQS_DP7")
	)
	(segment
		(start 112.13211 -66.41846)
		(end 112.25657 -66.294)
		(width 0.1524)
		(layer "In7.Cu")
		(net "M_A_DQS_DP7")
	)
	(segment
		(start 104.568244 -66.41846)
		(end 105.025444 -66.41846)
		(width 0.1524)
		(layer "In7.Cu")
		(net "M_A_DQS_DP7")
	)
	(segment
		(start 124.355098 -65.763902)
		(end 124.7902 -65.3288)
		(width 0.1524)
		(layer "In7.Cu")
		(net "M_A_DQS_DP7")
	)
	(segment
		(start 105.607104 -66.294)
		(end 105.731564 -66.41846)
		(width 0.1524)
		(layer "In7.Cu")
		(net "M_A_DQS_DP7")
	)
	(segment
		(start 128.3462 -64.5922)
		(end 128.3462 -63.881)
		(width 0.1524)
		(layer "In7.Cu")
		(net "M_A_DQS_DP7")
	)
	(segment
		(start 107.898692 -66.41846)
		(end 108.023152 -66.294)
		(width 0.1524)
		(layer "In7.Cu")
		(net "M_A_DQS_DP7")
	)
	(segment
		(start 106.313224 -66.294)
		(end 107.317032 -66.294)
		(width 0.1524)
		(layer "In7.Cu")
		(net "M_A_DQS_DP7")
	)
	(segment
		(start 111.55045 -66.294)
		(end 111.67491 -66.41846)
		(width 0.1524)
		(layer "In7.Cu")
		(net "M_A_DQS_DP7")
	)
	(segment
		(start 105.731564 -66.41846)
		(end 106.188764 -66.41846)
		(width 0.1524)
		(layer "In7.Cu")
		(net "M_A_DQS_DP7")
	)
	(segment
		(start 111.67491 -66.41846)
		(end 112.13211 -66.41846)
		(width 0.1524)
		(layer "In7.Cu")
		(net "M_A_DQS_DP7")
	)
	(segment
		(start 95.1484 -54.0258)
		(end 95.1484 -58.5978)
		(width 0.1524)
		(layer "In7.Cu")
		(net "M_A_DQS_DP7")
	)
	(segment
		(start 112.71377 -66.294)
		(end 112.83823 -66.41846)
		(width 0.1524)
		(layer "In7.Cu")
		(net "M_A_DQS_DP7")
	)
	(segment
		(start 95.1484 -58.5978)
		(end 96.415352 -59.864752)
		(width 0.1524)
		(layer "In7.Cu")
		(net "M_A_DQS_DP7")
	)
	(segment
		(start 115.16487 -66.41846)
		(end 115.62207 -66.41846)
		(width 0.1524)
		(layer "In7.Cu")
		(net "M_A_DQS_DP7")
	)
	(segment
		(start 106.188764 -66.41846)
		(end 106.313224 -66.294)
		(width 0.1524)
		(layer "In7.Cu")
		(net "M_A_DQS_DP7")
	)
	(segment
		(start 131.8006 -64.936624)
		(end 132.1816 -65.317624)
		(width 0.1524)
		(layer "In7.Cu")
		(net "M_A_DQS_DP7")
	)
	(segment
		(start 103.862124 -66.41846)
		(end 103.986584 -66.294)
		(width 0.1524)
		(layer "In7.Cu")
		(net "M_A_DQS_DP7")
	)
	(segment
		(start 114.45875 -66.41846)
		(end 114.58321 -66.294)
		(width 0.1524)
		(layer "In7.Cu")
		(net "M_A_DQS_DP7")
	)
	(segment
		(start 113.29543 -66.41846)
		(end 113.41989 -66.294)
		(width 0.1524)
		(layer "In7.Cu")
		(net "M_A_DQS_DP7")
	)
	(segment
		(start 124.7902 -65.3288)
		(end 125.5014 -65.3288)
		(width 0.1524)
		(layer "In7.Cu")
		(net "M_A_DQS_DP7")
	)
	(segment
		(start 110.51159 -66.41846)
		(end 110.96879 -66.41846)
		(width 0.1524)
		(layer "In7.Cu")
		(net "M_A_DQS_DP7")
	)
	(segment
		(start 126.873 -66.0654)
		(end 128.3462 -64.5922)
		(width 0.1524)
		(layer "In7.Cu")
		(net "M_A_DQS_DP7")
	)
	(segment
		(start 107.317032 -66.294)
		(end 107.441492 -66.41846)
		(width 0.1524)
		(layer "In7.Cu")
		(net "M_A_DQS_DP7")
	)
	(segment
		(start 114.58321 -66.294)
		(end 115.04041 -66.294)
		(width 0.1524)
		(layer "In7.Cu")
		(net "M_A_DQS_DP7")
	)
	(segment
		(start 107.441492 -66.41846)
		(end 107.898692 -66.41846)
		(width 0.1524)
		(layer "In7.Cu")
		(net "M_A_DQS_DP7")
	)
	(segment
		(start 113.41989 -66.294)
		(end 113.87709 -66.294)
		(width 0.1524)
		(layer "In7.Cu")
		(net "M_A_DQS_DP7")
	)
	(segment
		(start 112.25657 -66.294)
		(end 112.71377 -66.294)
		(width 0.1524)
		(layer "In7.Cu")
		(net "M_A_DQS_DP7")
	)
	(segment
		(start 131.8006 -63.881)
		(end 131.8006 -64.936624)
		(width 0.1524)
		(layer "In7.Cu")
		(net "M_A_DQS_DP7")
	)
	(segment
		(start 108.023152 -66.294)
		(end 109.22381 -66.294)
		(width 0.1524)
		(layer "In7.Cu")
		(net "M_A_DQS_DP7")
	)
	(segment
		(start 104.443784 -66.294)
		(end 104.568244 -66.41846)
		(width 0.1524)
		(layer "In7.Cu")
		(net "M_A_DQS_DP7")
	)
	(segment
		(start 109.34827 -66.41846)
		(end 109.80547 -66.41846)
		(width 0.1524)
		(layer "In7.Cu")
		(net "M_A_DQS_DP7")
	)
	(segment
		(start 132.1816 -65.619376)
		(end 131.8006 -66.000376)
		(width 0.1524)
		(layer "In7.Cu")
		(net "M_A_DQS_DP7")
	)
	(via
		(at 99.443032 -65.524126)
		(size 0.7112)
		(drill 0.3556)
		(layers "F.Cu" "B.Cu")
		(net "AGND_P1V1")
	)
	(segment
		(start 101.5492 -64.643)
		(end 101.092 -65.1002)
		(width 0.254)
		(layer "B.Cu")
		(net "AGND_P1V1")
	)
	(segment
		(start 100.965 -65.2272)
		(end 100.33 -65.2272)
		(width 0.254)
		(layer "B.Cu")
		(net "AGND_P1V1")
	)
	(segment
		(start 100.33 -65.2272)
		(end 99.739958 -65.2272)
		(width 0.254)
		(layer "B.Cu")
		(net "AGND_P1V1")
	)
	(segment
		(start 101.9556 -64.643)
		(end 101.5492 -64.643)
		(width 0.254)
		(layer "B.Cu")
		(net "AGND_P1V1")
	)
	(segment
		(start 98.443796 -65.659)
		(end 99.308158 -65.659)
		(width 0.254)
		(layer "B.Cu")
		(net "AGND_P1V1")
	)
	(segment
		(start 101.092 -65.1002)
		(end 100.965 -65.2272)
		(width 0.254)
		(layer "B.Cu")
		(net "AGND_P1V1")
	)
	(segment
		(start 99.739958 -65.2272)
		(end 99.443032 -65.524126)
		(width 0.254)
		(layer "B.Cu")
		(net "AGND_P1V1")
	)
	(segment
		(start 99.308158 -65.659)
		(end 99.443032 -65.524126)
		(width 0.254)
		(layer "B.Cu")
		(net "AGND_P1V1")
	)
	(segment
		(start 114.0968 -49.7332)
		(end 114.0968 -48.982884)
		(width 0.1016)
		(layer "F.Cu")
		(net "M_A_ECC6")
	)
	(segment
		(start 114.0968 -48.982884)
		(end 112.098328 -46.984412)
		(width 0.1016)
		(layer "F.Cu")
		(net "M_A_ECC6")
	)
	(segment
		(start 163.74999 -69.39407)
		(end 164.17544 -68.96862)
		(width 0.1778)
		(layer "F.Cu")
		(net "M_A_ECC6")
	)
	(segment
		(start 114.4016 -50.038)
		(end 114.0968 -49.7332)
		(width 0.1016)
		(layer "F.Cu")
		(net "M_A_ECC6")
	)
	(segment
		(start 112.098328 -46.984412)
		(end 112.098328 -46.870874)
		(width 0.1016)
		(layer "F.Cu")
		(net "M_A_ECC6")
	)
	(segment
		(start 163.74999 -70.806564)
		(end 163.74999 -69.39407)
		(width 0.1778)
		(layer "F.Cu")
		(net "M_A_ECC6")
	)
	(via
		(at 114.4016 -50.038)
		(size 0.4318)
		(drill 0.2032)
		(layers "F.Cu" "B.Cu")
		(net "M_A_ECC6")
	)
	(via
		(at 164.17544 -68.96862)
		(size 0.4318)
		(drill 0.2032)
		(layers "F.Cu" "B.Cu")
		(net "M_A_ECC6")
	)
	(segment
		(start 164.049964 -69.094096)
		(end 164.17544 -68.96862)
		(width 0.1778)
		(layer "B.Cu")
		(net "M_A_ECC6")
	)
	(segment
		(start 164.049964 -70.79996)
		(end 164.049964 -69.094096)
		(width 0.1778)
		(layer "B.Cu")
		(net "M_A_ECC6")
	)
	(segment
		(start 164.3126 -67.66306)
		(end 164.3126 -68.7832)
		(width 0.1524)
		(layer "In2.Cu")
		(net "M_A_ECC6")
	)
	(segment
		(start 146.106388 -53.53558)
		(end 146.32178 -53.53558)
		(width 0.1524)
		(layer "In2.Cu")
		(net "M_A_ECC6")
	)
	(segment
		(start 117.6274 -49.5808)
		(end 114.8588 -49.5808)
		(width 0.1016)
		(layer "In2.Cu")
		(net "M_A_ECC6")
	)
	(segment
		(start 143.450056 -50.663856)
		(end 143.949928 -51.163728)
		(width 0.1524)
		(layer "In2.Cu")
		(net "M_A_ECC6")
	)
	(segment
		(start 118.710456 -50.663856)
		(end 143.450056 -50.663856)
		(width 0.1524)
		(layer "In2.Cu")
		(net "M_A_ECC6")
	)
	(segment
		(start 154.479498 -55.9308)
		(end 159.851852 -55.9308)
		(width 0.1524)
		(layer "In2.Cu")
		(net "M_A_ECC6")
	)
	(segment
		(start 146.32178 -53.53558)
		(end 146.7358 -53.9496)
		(width 0.1524)
		(layer "In2.Cu")
		(net "M_A_ECC6")
	)
	(segment
		(start 145.459196 -52.672996)
		(end 145.675096 -52.888896)
		(width 0.1524)
		(layer "In2.Cu")
		(net "M_A_ECC6")
	)
	(segment
		(start 144.812512 -52.241704)
		(end 144.456404 -52.597812)
		(width 0.1524)
		(layer "In2.Cu")
		(net "M_A_ECC6")
	)
	(segment
		(start 164.3126 -68.7832)
		(end 164.17544 -68.92036)
		(width 0.1524)
		(layer "In2.Cu")
		(net "M_A_ECC6")
	)
	(segment
		(start 145.675096 -52.888896)
		(end 145.675096 -53.104288)
		(width 0.1524)
		(layer "In2.Cu")
		(net "M_A_ECC6")
	)
	(segment
		(start 145.52168 -54.120288)
		(end 146.106388 -53.53558)
		(width 0.1524)
		(layer "In2.Cu")
		(net "M_A_ECC6")
	)
	(segment
		(start 146.7358 -55.62727)
		(end 147.48383 -56.3753)
		(width 0.1524)
		(layer "In2.Cu")
		(net "M_A_ECC6")
	)
	(segment
		(start 165.5826 -61.661548)
		(end 165.5826 -64.67856)
		(width 0.1524)
		(layer "In2.Cu")
		(net "M_A_ECC6")
	)
	(segment
		(start 118.710456 -50.663856)
		(end 117.6274 -49.5808)
		(width 0.1016)
		(layer "In2.Cu")
		(net "M_A_ECC6")
	)
	(segment
		(start 143.689578 -51.63947)
		(end 143.689578 -51.854862)
		(width 0.1524)
		(layer "In2.Cu")
		(net "M_A_ECC6")
	)
	(segment
		(start 145.306288 -54.120288)
		(end 145.52168 -54.120288)
		(width 0.1524)
		(layer "In2.Cu")
		(net "M_A_ECC6")
	)
	(segment
		(start 154.034998 -56.3753)
		(end 154.479498 -55.9308)
		(width 0.1524)
		(layer "In2.Cu")
		(net "M_A_ECC6")
	)
	(segment
		(start 144.887696 -53.029104)
		(end 145.243804 -52.672996)
		(width 0.1524)
		(layer "In2.Cu")
		(net "M_A_ECC6")
	)
	(segment
		(start 144.596612 -51.810412)
		(end 144.812512 -52.026312)
		(width 0.1524)
		(layer "In2.Cu")
		(net "M_A_ECC6")
	)
	(segment
		(start 143.905478 -52.070762)
		(end 144.12087 -52.070762)
		(width 0.1524)
		(layer "In2.Cu")
		(net "M_A_ECC6")
	)
	(segment
		(start 144.38122 -51.810412)
		(end 144.596612 -51.810412)
		(width 0.1524)
		(layer "In2.Cu")
		(net "M_A_ECC6")
	)
	(segment
		(start 144.812512 -52.026312)
		(end 144.812512 -52.241704)
		(width 0.1524)
		(layer "In2.Cu")
		(net "M_A_ECC6")
	)
	(segment
		(start 114.8588 -49.5808)
		(end 114.4016 -50.038)
		(width 0.1016)
		(layer "In2.Cu")
		(net "M_A_ECC6")
	)
	(segment
		(start 147.48383 -56.3753)
		(end 154.034998 -56.3753)
		(width 0.1524)
		(layer "In2.Cu")
		(net "M_A_ECC6")
	)
	(segment
		(start 145.675096 -53.104288)
		(end 145.090388 -53.688996)
		(width 0.1524)
		(layer "In2.Cu")
		(net "M_A_ECC6")
	)
	(segment
		(start 144.456404 -52.813204)
		(end 144.672304 -53.029104)
		(width 0.1524)
		(layer "In2.Cu")
		(net "M_A_ECC6")
	)
	(segment
		(start 145.090388 -53.688996)
		(end 145.090388 -53.904388)
		(width 0.1524)
		(layer "In2.Cu")
		(net "M_A_ECC6")
	)
	(segment
		(start 146.7358 -53.9496)
		(end 146.7358 -55.62727)
		(width 0.1524)
		(layer "In2.Cu")
		(net "M_A_ECC6")
	)
	(segment
		(start 143.949928 -51.37912)
		(end 143.689578 -51.63947)
		(width 0.1524)
		(layer "In2.Cu")
		(net "M_A_ECC6")
	)
	(segment
		(start 143.689578 -51.854862)
		(end 143.905478 -52.070762)
		(width 0.1524)
		(layer "In2.Cu")
		(net "M_A_ECC6")
	)
	(segment
		(start 144.12087 -52.070762)
		(end 144.38122 -51.810412)
		(width 0.1524)
		(layer "In2.Cu")
		(net "M_A_ECC6")
	)
	(segment
		(start 143.949928 -51.163728)
		(end 143.949928 -51.37912)
		(width 0.1524)
		(layer "In2.Cu")
		(net "M_A_ECC6")
	)
	(segment
		(start 145.090388 -53.904388)
		(end 145.306288 -54.120288)
		(width 0.1524)
		(layer "In2.Cu")
		(net "M_A_ECC6")
	)
	(segment
		(start 145.243804 -52.672996)
		(end 145.459196 -52.672996)
		(width 0.1524)
		(layer "In2.Cu")
		(net "M_A_ECC6")
	)
	(segment
		(start 164.17544 -68.92036)
		(end 164.17544 -68.96862)
		(width 0.1524)
		(layer "In2.Cu")
		(net "M_A_ECC6")
	)
	(segment
		(start 164.191442 -67.541902)
		(end 164.3126 -67.66306)
		(width 0.1524)
		(layer "In2.Cu")
		(net "M_A_ECC6")
	)
	(segment
		(start 164.191442 -66.069718)
		(end 164.191442 -67.541902)
		(width 0.1524)
		(layer "In2.Cu")
		(net "M_A_ECC6")
	)
	(segment
		(start 144.672304 -53.029104)
		(end 144.887696 -53.029104)
		(width 0.1524)
		(layer "In2.Cu")
		(net "M_A_ECC6")
	)
	(segment
		(start 159.851852 -55.9308)
		(end 165.5826 -61.661548)
		(width 0.1524)
		(layer "In2.Cu")
		(net "M_A_ECC6")
	)
	(segment
		(start 165.5826 -64.67856)
		(end 164.191442 -66.069718)
		(width 0.1524)
		(layer "In2.Cu")
		(net "M_A_ECC6")
	)
	(segment
		(start 144.456404 -52.597812)
		(end 144.456404 -52.813204)
		(width 0.1524)
		(layer "In2.Cu")
		(net "M_A_ECC6")
	)
	(via
		(at 40.386 -49.1744)
		(size 0.7112)
		(drill 0.3556)
		(layers "F.Cu" "B.Cu")
		(net "SMB_CLKGEN_R_DATA")
	)
	(segment
		(start 43.04919 -48.297338)
		(end 42.253662 -48.297338)
		(width 0.1143)
		(layer "B.Cu")
		(net "SMB_CLKGEN_R_DATA")
	)
	(segment
		(start 39.4208 -49.6062)
		(end 39.9415 -49.6062)
		(width 0.1143)
		(layer "B.Cu")
		(net "SMB_CLKGEN_R_DATA")
	)
	(segment
		(start 42.253662 -48.297338)
		(end 41.3766 -49.1744)
		(width 0.1143)
		(layer "B.Cu")
		(net "SMB_CLKGEN_R_DATA")
	)
	(segment
		(start 39.9415 -49.6062)
		(end 40.3733 -49.1744)
		(width 0.1143)
		(layer "B.Cu")
		(net "SMB_CLKGEN_R_DATA")
	)
	(segment
		(start 40.3733 -49.1744)
		(end 40.386 -49.1744)
		(width 0.1143)
		(layer "B.Cu")
		(net "SMB_CLKGEN_R_DATA")
	)
	(segment
		(start 41.3766 -49.1744)
		(end 40.386 -49.1744)
		(width 0.1143)
		(layer "B.Cu")
		(net "SMB_CLKGEN_R_DATA")
	)
	(segment
		(start 94.234 -67.818)
		(end 89.6874 -67.818)
		(width 0.254)
		(layer "F.Cu")
		(net "PWRGD_P1V1_PG")
	)
	(segment
		(start 99.314 -67.31)
		(end 99.06 -67.564)
		(width 0.254)
		(layer "F.Cu")
		(net "PWRGD_P1V1_PG")
	)
	(segment
		(start 99.06 -67.564)
		(end 94.488 -67.564)
		(width 0.254)
		(layer "F.Cu")
		(net "PWRGD_P1V1_PG")
	)
	(segment
		(start 89.6874 -67.818)
		(end 88.8746 -67.0052)
		(width 0.254)
		(layer "F.Cu")
		(net "PWRGD_P1V1_PG")
	)
	(segment
		(start 94.488 -67.564)
		(end 94.234 -67.818)
		(width 0.254)
		(layer "F.Cu")
		(net "PWRGD_P1V1_PG")
	)
	(segment
		(start 100.1776 -66.8274)
		(end 99.7966 -66.8274)
		(width 0.254)
		(layer "F.Cu")
		(net "PWRGD_P1V1_PG")
	)
	(segment
		(start 99.7966 -66.8274)
		(end 99.314 -67.31)
		(width 0.254)
		(layer "F.Cu")
		(net "PWRGD_P1V1_PG")
	)
	(via
		(at 79.2861 -25.573228)
		(size 0.508)
		(drill 0.254)
		(layers "F.Cu" "B.Cu")
		(net "PWRGD_P1V1_PG")
	)
	(via
		(at 72.4408 -59.182)
		(size 0.7112)
		(drill 0.3556)
		(layers "F.Cu" "B.Cu")
		(net "PWRGD_P1V1_PG")
	)
	(via
		(at 73.0504 -60.4774)
		(size 0.508)
		(drill 0.254)
		(layers "F.Cu" "B.Cu")
		(net "PWRGD_P1V1_PG")
	)
	(via
		(at 99.314 -67.31)
		(size 0.508)
		(drill 0.254)
		(layers "F.Cu" "B.Cu")
		(net "PWRGD_P1V1_PG")
	)
	(via
		(at 77.6732 -49.6316)
		(size 0.4318)
		(drill 0.2032)
		(layers "F.Cu" "B.Cu")
		(net "PWRGD_P1V1_PG")
	)
	(via
		(at 88.8746 -67.0052)
		(size 0.508)
		(drill 0.254)
		(layers "F.Cu" "B.Cu")
		(net "PWRGD_P1V1_PG")
	)
	(segment
		(start 77.6732 -51.037998)
		(end 77.6732 -49.6316)
		(width 0.254)
		(layer "B.Cu")
		(net "PWRGD_P1V1_PG")
	)
	(segment
		(start 72.4408 -59.182)
		(end 72.4408 -56.885332)
		(width 0.254)
		(layer "B.Cu")
		(net "PWRGD_P1V1_PG")
	)
	(segment
		(start 79.306928 -25.5524)
		(end 79.2861 -25.573228)
		(width 0.254)
		(layer "B.Cu")
		(net "PWRGD_P1V1_PG")
	)
	(segment
		(start 98.443796 -67.658996)
		(end 98.965004 -67.658996)
		(width 0.254)
		(layer "B.Cu")
		(net "PWRGD_P1V1_PG")
	)
	(segment
		(start 78.0288 -53.575458)
		(end 78.0288 -51.393598)
		(width 0.254)
		(layer "B.Cu")
		(net "PWRGD_P1V1_PG")
	)
	(segment
		(start 98.965004 -67.658996)
		(end 99.314 -67.31)
		(width 0.254)
		(layer "B.Cu")
		(net "PWRGD_P1V1_PG")
	)
	(segment
		(start 73.0504 -60.4774)
		(end 72.4408 -59.8678)
		(width 0.254)
		(layer "B.Cu")
		(net "PWRGD_P1V1_PG")
	)
	(segment
		(start 72.4408 -59.8678)
		(end 72.4408 -59.182)
		(width 0.254)
		(layer "B.Cu")
		(net "PWRGD_P1V1_PG")
	)
	(segment
		(start 79.306928 -25.087072)
		(end 79.306928 -25.5524)
		(width 0.254)
		(layer "B.Cu")
		(net "PWRGD_P1V1_PG")
	)
	(segment
		(start 72.4408 -56.885332)
		(end 72.728582 -56.59755)
		(width 0.254)
		(layer "B.Cu")
		(net "PWRGD_P1V1_PG")
	)
	(segment
		(start 80.01 -24.0792)
		(end 80.01 -24.384)
		(width 0.254)
		(layer "B.Cu")
		(net "PWRGD_P1V1_PG")
	)
	(segment
		(start 75.006708 -56.59755)
		(end 78.0288 -53.575458)
		(width 0.254)
		(layer "B.Cu")
		(net "PWRGD_P1V1_PG")
	)
	(segment
		(start 72.728582 -56.59755)
		(end 75.006708 -56.59755)
		(width 0.254)
		(layer "B.Cu")
		(net "PWRGD_P1V1_PG")
	)
	(segment
		(start 78.0288 -51.393598)
		(end 77.6732 -51.037998)
		(width 0.254)
		(layer "B.Cu")
		(net "PWRGD_P1V1_PG")
	)
	(segment
		(start 80.01 -24.384)
		(end 79.306928 -25.087072)
		(width 0.254)
		(layer "B.Cu")
		(net "PWRGD_P1V1_PG")
	)
	(segment
		(start 85.409024 -31.91002)
		(end 86.36127 -31.91002)
		(width 0.254)
		(layer "In7.Cu")
		(net "PWRGD_P1V1_PG")
	)
	(segment
		(start 79.2861 -25.573228)
		(end 79.49438 -25.573228)
		(width 0.254)
		(layer "In7.Cu")
		(net "PWRGD_P1V1_PG")
	)
	(segment
		(start 83.312 -28.58135)
		(end 83.312 -29.464)
		(width 0.254)
		(layer "In7.Cu")
		(net "PWRGD_P1V1_PG")
	)
	(segment
		(start 86.62162 -32.723328)
		(end 86.974934 -33.076642)
		(width 0.254)
		(layer "In7.Cu")
		(net "PWRGD_P1V1_PG")
	)
	(segment
		(start 90.193368 -45.573696)
		(end 90.193368 -47.778162)
		(width 0.254)
		(layer "In7.Cu")
		(net "PWRGD_P1V1_PG")
	)
	(segment
		(start 82.902298 -50.3301)
		(end 82.570574 -49.998376)
		(width 0.254)
		(layer "In7.Cu")
		(net "PWRGD_P1V1_PG")
	)
	(segment
		(start 73.0504 -60.4774)
		(end 75.62215 -63.04915)
		(width 0.254)
		(layer "In7.Cu")
		(net "PWRGD_P1V1_PG")
	)
	(segment
		(start 88.6333 -39.701724)
		(end 88.6333 -39.70655)
		(width 0.254)
		(layer "In7.Cu")
		(net "PWRGD_P1V1_PG")
	)
	(segment
		(start 84.352638 -50.3301)
		(end 82.902298 -50.3301)
		(width 0.254)
		(layer "In7.Cu")
		(net "PWRGD_P1V1_PG")
	)
	(segment
		(start 75.62215 -63.04915)
		(end 81.100676 -63.04915)
		(width 0.254)
		(layer "In7.Cu")
		(net "PWRGD_P1V1_PG")
	)
	(segment
		(start 88.228932 -35.549332)
		(end 88.639904 -35.960304)
		(width 0.254)
		(layer "In7.Cu")
		(net "PWRGD_P1V1_PG")
	)
	(segment
		(start 87.079074 -50.3174)
		(end 86.325456 -51.071018)
		(width 0.254)
		(layer "In7.Cu")
		(net "PWRGD_P1V1_PG")
	)
	(segment
		(start 79.981552 -26.0604)
		(end 80.79105 -26.0604)
		(width 0.254)
		(layer "In7.Cu")
		(net "PWRGD_P1V1_PG")
	)
	(segment
		(start 84.290154 -30.442154)
		(end 84.290154 -30.79115)
		(width 0.254)
		(layer "In7.Cu")
		(net "PWRGD_P1V1_PG")
	)
	(segment
		(start 81.100676 -63.04915)
		(end 81.583276 -63.53175)
		(width 0.254)
		(layer "In7.Cu")
		(net "PWRGD_P1V1_PG")
	)
	(segment
		(start 88.228932 -35.520376)
		(end 88.228932 -35.549332)
		(width 0.254)
		(layer "In7.Cu")
		(net "PWRGD_P1V1_PG")
	)
	(segment
		(start 89.025222 -38.05555)
		(end 88.4682 -38.612572)
		(width 0.254)
		(layer "In7.Cu")
		(net "PWRGD_P1V1_PG")
	)
	(segment
		(start 85.093556 -51.071018)
		(end 84.352638 -50.3301)
		(width 0.254)
		(layer "In7.Cu")
		(net "PWRGD_P1V1_PG")
	)
	(segment
		(start 89.9033 -40.971724)
		(end 89.9033 -44.06265)
		(width 0.254)
		(layer "In7.Cu")
		(net "PWRGD_P1V1_PG")
	)
	(segment
		(start 81.8515 -49.05756)
		(end 78.24724 -49.05756)
		(width 0.254)
		(layer "In7.Cu")
		(net "PWRGD_P1V1_PG")
	)
	(segment
		(start 89.2429 -49.66335)
		(end 88.58885 -50.3174)
		(width 0.254)
		(layer "In7.Cu")
		(net "PWRGD_P1V1_PG")
	)
	(segment
		(start 90.193368 -47.778162)
		(end 89.2429 -48.72863)
		(width 0.254)
		(layer "In7.Cu")
		(net "PWRGD_P1V1_PG")
	)
	(segment
		(start 82.570574 -49.776634)
		(end 81.8515 -49.05756)
		(width 0.254)
		(layer "In7.Cu")
		(net "PWRGD_P1V1_PG")
	)
	(segment
		(start 88.4682 -39.536624)
		(end 88.6333 -39.701724)
		(width 0.254)
		(layer "In7.Cu")
		(net "PWRGD_P1V1_PG")
	)
	(segment
		(start 88.898476 -39.9669)
		(end 89.9033 -40.971724)
		(width 0.254)
		(layer "In7.Cu")
		(net "PWRGD_P1V1_PG")
	)
	(segment
		(start 86.36127 -31.91002)
		(end 86.62162 -32.17037)
		(width 0.254)
		(layer "In7.Cu")
		(net "PWRGD_P1V1_PG")
	)
	(segment
		(start 87.846662 -35.138106)
		(end 88.228932 -35.520376)
		(width 0.254)
		(layer "In7.Cu")
		(net "PWRGD_P1V1_PG")
	)
	(segment
		(start 80.79105 -26.0604)
		(end 83.312 -28.58135)
		(width 0.254)
		(layer "In7.Cu")
		(net "PWRGD_P1V1_PG")
	)
	(segment
		(start 89.8017 -44.16425)
		(end 89.8017 -45.182028)
		(width 0.254)
		(layer "In7.Cu")
		(net "PWRGD_P1V1_PG")
	)
	(segment
		(start 84.290154 -30.79115)
		(end 85.409024 -31.91002)
		(width 0.254)
		(layer "In7.Cu")
		(net "PWRGD_P1V1_PG")
	)
	(segment
		(start 89.8017 -45.182028)
		(end 90.193368 -45.573696)
		(width 0.254)
		(layer "In7.Cu")
		(net "PWRGD_P1V1_PG")
	)
	(segment
		(start 86.62162 -32.17037)
		(end 86.62162 -32.723328)
		(width 0.254)
		(layer "In7.Cu")
		(net "PWRGD_P1V1_PG")
	)
	(segment
		(start 88.89365 -39.9669)
		(end 88.898476 -39.9669)
		(width 0.254)
		(layer "In7.Cu")
		(net "PWRGD_P1V1_PG")
	)
	(segment
		(start 78.24724 -49.05756)
		(end 77.6732 -49.6316)
		(width 0.254)
		(layer "In7.Cu")
		(net "PWRGD_P1V1_PG")
	)
	(segment
		(start 86.325456 -51.071018)
		(end 85.093556 -51.071018)
		(width 0.254)
		(layer "In7.Cu")
		(net "PWRGD_P1V1_PG")
	)
	(segment
		(start 87.381842 -33.076642)
		(end 87.846662 -33.541462)
		(width 0.254)
		(layer "In7.Cu")
		(net "PWRGD_P1V1_PG")
	)
	(segment
		(start 88.639904 -35.960304)
		(end 88.7476 -35.960304)
		(width 0.254)
		(layer "In7.Cu")
		(net "PWRGD_P1V1_PG")
	)
	(segment
		(start 86.974934 -33.076642)
		(end 87.381842 -33.076642)
		(width 0.254)
		(layer "In7.Cu")
		(net "PWRGD_P1V1_PG")
	)
	(segment
		(start 89.2429 -48.72863)
		(end 89.2429 -49.66335)
		(width 0.254)
		(layer "In7.Cu")
		(net "PWRGD_P1V1_PG")
	)
	(segment
		(start 81.583276 -63.53175)
		(end 85.40115 -63.53175)
		(width 0.254)
		(layer "In7.Cu")
		(net "PWRGD_P1V1_PG")
	)
	(segment
		(start 79.49438 -25.573228)
		(end 79.981552 -26.0604)
		(width 0.254)
		(layer "In7.Cu")
		(net "PWRGD_P1V1_PG")
	)
	(segment
		(start 89.9033 -44.06265)
		(end 89.8017 -44.16425)
		(width 0.254)
		(layer "In7.Cu")
		(net "PWRGD_P1V1_PG")
	)
	(segment
		(start 88.58885 -50.3174)
		(end 87.079074 -50.3174)
		(width 0.254)
		(layer "In7.Cu")
		(net "PWRGD_P1V1_PG")
	)
	(segment
		(start 82.570574 -49.998376)
		(end 82.570574 -49.776634)
		(width 0.254)
		(layer "In7.Cu")
		(net "PWRGD_P1V1_PG")
	)
	(segment
		(start 88.7476 -35.960304)
		(end 89.025222 -36.237926)
		(width 0.254)
		(layer "In7.Cu")
		(net "PWRGD_P1V1_PG")
	)
	(segment
		(start 88.4682 -38.612572)
		(end 88.4682 -39.536624)
		(width 0.254)
		(layer "In7.Cu")
		(net "PWRGD_P1V1_PG")
	)
	(segment
		(start 89.025222 -36.237926)
		(end 89.025222 -38.05555)
		(width 0.254)
		(layer "In7.Cu")
		(net "PWRGD_P1V1_PG")
	)
	(segment
		(start 87.846662 -33.541462)
		(end 87.846662 -35.138106)
		(width 0.254)
		(layer "In7.Cu")
		(net "PWRGD_P1V1_PG")
	)
	(segment
		(start 85.40115 -63.53175)
		(end 88.8746 -67.0052)
		(width 0.254)
		(layer "In7.Cu")
		(net "PWRGD_P1V1_PG")
	)
	(segment
		(start 88.6333 -39.70655)
		(end 88.89365 -39.9669)
		(width 0.254)
		(layer "In7.Cu")
		(net "PWRGD_P1V1_PG")
	)
	(segment
		(start 83.312 -29.464)
		(end 84.290154 -30.442154)
		(width 0.254)
		(layer "In7.Cu")
		(net "PWRGD_P1V1_PG")
	)
	(segment
		(start 98.0186 -55.4736)
		(end 98.125788 -55.366412)
		(width 0.1016)
		(layer "F.Cu")
		(net "M_A_DQ50")
	)
	(segment
		(start 135.850122 -62.59322)
		(end 135.850122 -63.287402)
		(width 0.1778)
		(layer "F.Cu")
		(net "M_A_DQ50")
	)
	(segment
		(start 98.125788 -51.430174)
		(end 98.455988 -51.099974)
		(width 0.1016)
		(layer "F.Cu")
		(net "M_A_DQ50")
	)
	(segment
		(start 98.125788 -55.366412)
		(end 98.125788 -51.430174)
		(width 0.1016)
		(layer "F.Cu")
		(net "M_A_DQ50")
	)
	(segment
		(start 135.850122 -63.287402)
		(end 135.07085 -64.066674)
		(width 0.1778)
		(layer "F.Cu")
		(net "M_A_DQ50")
	)
	(via
		(at 135.07085 -64.066674)
		(size 0.4318)
		(drill 0.2032)
		(layers "F.Cu" "B.Cu")
		(net "M_A_DQ50")
	)
	(via
		(at 98.0186 -55.4736)
		(size 0.4318)
		(drill 0.2032)
		(layers "F.Cu" "B.Cu")
		(net "M_A_DQ50")
	)
	(segment
		(start 134.949946 -63.266066)
		(end 135.232648 -63.548768)
		(width 0.1778)
		(layer "B.Cu")
		(net "M_A_DQ50")
	)
	(segment
		(start 135.232648 -63.904876)
		(end 135.07085 -64.066674)
		(width 0.1778)
		(layer "B.Cu")
		(net "M_A_DQ50")
	)
	(segment
		(start 134.949946 -62.599824)
		(end 134.949946 -63.266066)
		(width 0.1778)
		(layer "B.Cu")
		(net "M_A_DQ50")
	)
	(segment
		(start 135.232648 -63.548768)
		(end 135.232648 -63.904876)
		(width 0.1778)
		(layer "B.Cu")
		(net "M_A_DQ50")
	)
	(segment
		(start 128.42367 -65.3542)
		(end 128.27127 -65.5066)
		(width 0.1524)
		(layer "In4.Cu")
		(net "M_A_DQ50")
	)
	(segment
		(start 127.66167 -65.5066)
		(end 127.50927 -65.3542)
		(width 0.1524)
		(layer "In4.Cu")
		(net "M_A_DQ50")
	)
	(segment
		(start 123.317 -66.675)
		(end 120.067324 -66.675)
		(width 0.1524)
		(layer "In4.Cu")
		(net "M_A_DQ50")
	)
	(segment
		(start 97.794826 -61.367924)
		(end 97.794826 -59.73445)
		(width 0.1524)
		(layer "In4.Cu")
		(net "M_A_DQ50")
	)
	(segment
		(start 107.844336 -67.295522)
		(end 103.722424 -67.295522)
		(width 0.1524)
		(layer "In4.Cu")
		(net "M_A_DQ50")
	)
	(segment
		(start 118.727474 -68.01485)
		(end 108.563664 -68.01485)
		(width 0.1524)
		(layer "In4.Cu")
		(net "M_A_DQ50")
	)
	(segment
		(start 98.425 -55.88)
		(end 98.0186 -55.4736)
		(width 0.1016)
		(layer "In4.Cu")
		(net "M_A_DQ50")
	)
	(segment
		(start 126.44247 -66.802)
		(end 126.44247 -65.5066)
		(width 0.1524)
		(layer "In4.Cu")
		(net "M_A_DQ50")
	)
	(segment
		(start 98.425 -59.104276)
		(end 98.425 -55.88)
		(width 0.1016)
		(layer "In4.Cu")
		(net "M_A_DQ50")
	)
	(segment
		(start 127.81407 -66.4972)
		(end 127.66167 -66.3448)
		(width 0.1524)
		(layer "In4.Cu")
		(net "M_A_DQ50")
	)
	(segment
		(start 103.722424 -67.295522)
		(end 97.794826 -61.367924)
		(width 0.1524)
		(layer "In4.Cu")
		(net "M_A_DQ50")
	)
	(segment
		(start 130.499104 -63.607696)
		(end 128.7526 -65.3542)
		(width 0.1524)
		(layer "In4.Cu")
		(net "M_A_DQ50")
	)
	(segment
		(start 108.563664 -68.01485)
		(end 107.844336 -67.295522)
		(width 0.1524)
		(layer "In4.Cu")
		(net "M_A_DQ50")
	)
	(segment
		(start 127.05207 -65.5066)
		(end 127.05207 -66.802)
		(width 0.1524)
		(layer "In4.Cu")
		(net "M_A_DQ50")
	)
	(segment
		(start 97.794826 -59.73445)
		(end 98.0694 -59.459876)
		(width 0.1524)
		(layer "In4.Cu")
		(net "M_A_DQ50")
	)
	(segment
		(start 135.027416 -64.066674)
		(end 134.568438 -63.607696)
		(width 0.1524)
		(layer "In4.Cu")
		(net "M_A_DQ50")
	)
	(segment
		(start 124.6378 -65.3542)
		(end 123.317 -66.675)
		(width 0.1524)
		(layer "In4.Cu")
		(net "M_A_DQ50")
	)
	(segment
		(start 98.0694 -59.459876)
		(end 98.425 -59.104276)
		(width 0.1016)
		(layer "In4.Cu")
		(net "M_A_DQ50")
	)
	(segment
		(start 128.27127 -66.3448)
		(end 128.11887 -66.4972)
		(width 0.1524)
		(layer "In4.Cu")
		(net "M_A_DQ50")
	)
	(segment
		(start 135.07085 -64.066674)
		(end 135.027416 -64.066674)
		(width 0.1524)
		(layer "In4.Cu")
		(net "M_A_DQ50")
	)
	(segment
		(start 127.66167 -66.3448)
		(end 127.66167 -65.5066)
		(width 0.1524)
		(layer "In4.Cu")
		(net "M_A_DQ50")
	)
	(segment
		(start 120.067324 -66.675)
		(end 118.727474 -68.01485)
		(width 0.1524)
		(layer "In4.Cu")
		(net "M_A_DQ50")
	)
	(segment
		(start 128.27127 -65.5066)
		(end 128.27127 -66.3448)
		(width 0.1524)
		(layer "In4.Cu")
		(net "M_A_DQ50")
	)
	(segment
		(start 126.59487 -66.9544)
		(end 126.44247 -66.802)
		(width 0.1524)
		(layer "In4.Cu")
		(net "M_A_DQ50")
	)
	(segment
		(start 134.568438 -63.607696)
		(end 130.499104 -63.607696)
		(width 0.1524)
		(layer "In4.Cu")
		(net "M_A_DQ50")
	)
	(segment
		(start 128.11887 -66.4972)
		(end 127.81407 -66.4972)
		(width 0.1524)
		(layer "In4.Cu")
		(net "M_A_DQ50")
	)
	(segment
		(start 127.50927 -65.3542)
		(end 127.20447 -65.3542)
		(width 0.1524)
		(layer "In4.Cu")
		(net "M_A_DQ50")
	)
	(segment
		(start 128.7526 -65.3542)
		(end 128.42367 -65.3542)
		(width 0.1524)
		(layer "In4.Cu")
		(net "M_A_DQ50")
	)
	(segment
		(start 126.89967 -66.9544)
		(end 126.59487 -66.9544)
		(width 0.1524)
		(layer "In4.Cu")
		(net "M_A_DQ50")
	)
	(segment
		(start 126.29007 -65.3542)
		(end 124.6378 -65.3542)
		(width 0.1524)
		(layer "In4.Cu")
		(net "M_A_DQ50")
	)
	(segment
		(start 126.44247 -65.5066)
		(end 126.29007 -65.3542)
		(width 0.1524)
		(layer "In4.Cu")
		(net "M_A_DQ50")
	)
	(segment
		(start 127.20447 -65.3542)
		(end 127.05207 -65.5066)
		(width 0.1524)
		(layer "In4.Cu")
		(net "M_A_DQ50")
	)
	(segment
		(start 127.05207 -66.802)
		(end 126.89967 -66.9544)
		(width 0.1524)
		(layer "In4.Cu")
		(net "M_A_DQ50")
	)
	(segment
		(start 105.550208 -30.759654)
		(end 105.880154 -31.0896)
		(width 0.1397)
		(layer "F.Cu")
		(net "CLK_100M_CPU_MPLL1_DN")
	)
	(segment
		(start 105.880154 -31.0896)
		(end 105.880154 -31.1404)
		(width 0.1397)
		(layer "F.Cu")
		(net "CLK_100M_CPU_MPLL1_DN")
	)
	(via
		(at 105.880154 -31.1404)
		(size 0.4318)
		(drill 0.2032)
		(layers "F.Cu" "B.Cu")
		(net "CLK_100M_CPU_MPLL1_DN")
	)
	(via
		(at 52.16652 -34.0868)
		(size 0.508)
		(drill 0.254)
		(layers "F.Cu" "B.Cu")
		(net "CLK_100M_CPU_MPLL1_DN")
	)
	(segment
		(start 49.379632 -49.897284)
		(end 48.668178 -49.897284)
		(width 0.1397)
		(layer "B.Cu")
		(net "CLK_100M_CPU_MPLL1_DN")
	)
	(segment
		(start 49.586642 -49.868582)
		(end 49.408334 -49.868582)
		(width 0.1397)
		(layer "B.Cu")
		(net "CLK_100M_CPU_MPLL1_DN")
	)
	(segment
		(start 49.408334 -49.868582)
		(end 49.379632 -49.897284)
		(width 0.1397)
		(layer "B.Cu")
		(net "CLK_100M_CPU_MPLL1_DN")
	)
	(segment
		(start 53.086 -48.763682)
		(end 53.086 -49.60874)
		(width 0.1397)
		(layer "B.Cu")
		(net "CLK_100M_CPU_MPLL1_DN")
	)
	(segment
		(start 51.6001 -36.00704)
		(end 51.6001 -40.80256)
		(width 0.1397)
		(layer "B.Cu")
		(net "CLK_100M_CPU_MPLL1_DN")
	)
	(segment
		(start 53.6575 -47.290228)
		(end 53.6575 -48.192182)
		(width 0.1397)
		(layer "B.Cu")
		(net "CLK_100M_CPU_MPLL1_DN")
	)
	(segment
		(start 53.086 -49.60874)
		(end 51.97094 -50.7238)
		(width 0.1397)
		(layer "B.Cu")
		(net "CLK_100M_CPU_MPLL1_DN")
	)
	(segment
		(start 51.6001 -40.80256)
		(end 52.0446 -41.24706)
		(width 0.1397)
		(layer "B.Cu")
		(net "CLK_100M_CPU_MPLL1_DN")
	)
	(segment
		(start 53.6575 -48.192182)
		(end 53.086 -48.763682)
		(width 0.1397)
		(layer "B.Cu")
		(net "CLK_100M_CPU_MPLL1_DN")
	)
	(segment
		(start 51.9557 -35.65144)
		(end 51.6001 -36.00704)
		(width 0.1397)
		(layer "B.Cu")
		(net "CLK_100M_CPU_MPLL1_DN")
	)
	(segment
		(start 51.9557 -34.29762)
		(end 51.9557 -35.65144)
		(width 0.1397)
		(layer "B.Cu")
		(net "CLK_100M_CPU_MPLL1_DN")
	)
	(segment
		(start 51.97094 -50.7238)
		(end 50.44186 -50.7238)
		(width 0.1397)
		(layer "B.Cu")
		(net "CLK_100M_CPU_MPLL1_DN")
	)
	(segment
		(start 50.44186 -50.7238)
		(end 49.586642 -49.868582)
		(width 0.1397)
		(layer "B.Cu")
		(net "CLK_100M_CPU_MPLL1_DN")
	)
	(segment
		(start 52.0446 -45.677328)
		(end 53.6575 -47.290228)
		(width 0.1397)
		(layer "B.Cu")
		(net "CLK_100M_CPU_MPLL1_DN")
	)
	(segment
		(start 52.0446 -41.24706)
		(end 52.0446 -45.677328)
		(width 0.1397)
		(layer "B.Cu")
		(net "CLK_100M_CPU_MPLL1_DN")
	)
	(segment
		(start 52.16652 -34.0868)
		(end 51.9557 -34.29762)
		(width 0.1397)
		(layer "B.Cu")
		(net "CLK_100M_CPU_MPLL1_DN")
	)
	(segment
		(start 56.32704 -28.899866)
		(end 59.12104 -28.899866)
		(width 0.1143)
		(layer "In4.Cu")
		(net "CLK_100M_CPU_MPLL1_DN")
	)
	(segment
		(start 63.737236 -24.9682)
		(end 64.823086 -23.88235)
		(width 0.1143)
		(layer "In4.Cu")
		(net "CLK_100M_CPU_MPLL1_DN")
	)
	(segment
		(start 82.931 -24.2824)
		(end 83.610196 -24.2824)
		(width 0.1143)
		(layer "In4.Cu")
		(net "CLK_100M_CPU_MPLL1_DN")
	)
	(segment
		(start 96.4946 -33.6296)
		(end 102.328472 -33.6296)
		(width 0.1016)
		(layer "In4.Cu")
		(net "CLK_100M_CPU_MPLL1_DN")
	)
	(segment
		(start 84.3026 -24.816054)
		(end 84.3026 -24.9809)
		(width 0.1143)
		(layer "In4.Cu")
		(net "CLK_100M_CPU_MPLL1_DN")
	)
	(segment
		(start 90.525092 -26.066496)
		(end 92.685362 -26.066496)
		(width 0.1143)
		(layer "In4.Cu")
		(net "CLK_100M_CPU_MPLL1_DN")
	)
	(segment
		(start 64.823086 -23.88235)
		(end 67.26301 -23.88235)
		(width 0.1143)
		(layer "In4.Cu")
		(net "CLK_100M_CPU_MPLL1_DN")
	)
	(segment
		(start 103.868728 -33.86328)
		(end 104.45496 -33.277048)
		(width 0.1016)
		(layer "In4.Cu")
		(net "CLK_100M_CPU_MPLL1_DN")
	)
	(segment
		(start 104.521 -30.822646)
		(end 104.774746 -30.5689)
		(width 0.1016)
		(layer "In4.Cu")
		(net "CLK_100M_CPU_MPLL1_DN")
	)
	(segment
		(start 104.45496 -32.57296)
		(end 104.397048 -32.515048)
		(width 0.1016)
		(layer "In4.Cu")
		(net "CLK_100M_CPU_MPLL1_DN")
	)
	(segment
		(start 104.774746 -30.5689)
		(end 105.080054 -30.5689)
		(width 0.1016)
		(layer "In4.Cu")
		(net "CLK_100M_CPU_MPLL1_DN")
	)
	(segment
		(start 60.73775 -27.283156)
		(end 60.73775 -26.00325)
		(width 0.1143)
		(layer "In4.Cu")
		(net "CLK_100M_CPU_MPLL1_DN")
	)
	(segment
		(start 83.914996 -24.42845)
		(end 84.3026 -24.816054)
		(width 0.1143)
		(layer "In4.Cu")
		(net "CLK_100M_CPU_MPLL1_DN")
	)
	(segment
		(start 52.16652 -34.0868)
		(end 51.8668 -33.78708)
		(width 0.1143)
		(layer "In4.Cu")
		(net "CLK_100M_CPU_MPLL1_DN")
	)
	(segment
		(start 86.2965 -25.3492)
		(end 87.0585 -24.5872)
		(width 0.1143)
		(layer "In4.Cu")
		(net "CLK_100M_CPU_MPLL1_DN")
	)
	(segment
		(start 71.133716 -26.0731)
		(end 74.16165 -26.0731)
		(width 0.1143)
		(layer "In4.Cu")
		(net "CLK_100M_CPU_MPLL1_DN")
	)
	(segment
		(start 68.06311 -24.68245)
		(end 69.743066 -24.68245)
		(width 0.1143)
		(layer "In4.Cu")
		(net "CLK_100M_CPU_MPLL1_DN")
	)
	(segment
		(start 96.4184 -33.6931)
		(end 96.4311 -33.6931)
		(width 0.1016)
		(layer "In4.Cu")
		(net "CLK_100M_CPU_MPLL1_DN")
	)
	(segment
		(start 74.16165 -26.0731)
		(end 74.4728 -25.76195)
		(width 0.1143)
		(layer "In4.Cu")
		(net "CLK_100M_CPU_MPLL1_DN")
	)
	(segment
		(start 105.599484 -30.85973)
		(end 105.880154 -31.1404)
		(width 0.1016)
		(layer "In4.Cu")
		(net "CLK_100M_CPU_MPLL1_DN")
	)
	(segment
		(start 104.397048 -31.111952)
		(end 104.521 -30.988)
		(width 0.1016)
		(layer "In4.Cu")
		(net "CLK_100M_CPU_MPLL1_DN")
	)
	(segment
		(start 104.521 -30.988)
		(end 104.521 -30.822646)
		(width 0.1016)
		(layer "In4.Cu")
		(net "CLK_100M_CPU_MPLL1_DN")
	)
	(segment
		(start 104.45496 -33.277048)
		(end 104.45496 -32.57296)
		(width 0.1016)
		(layer "In4.Cu")
		(net "CLK_100M_CPU_MPLL1_DN")
	)
	(segment
		(start 104.397048 -32.515048)
		(end 104.397048 -31.111952)
		(width 0.1016)
		(layer "In4.Cu")
		(net "CLK_100M_CPU_MPLL1_DN")
	)
	(segment
		(start 79.39405 -24.51735)
		(end 82.69605 -24.51735)
		(width 0.1143)
		(layer "In4.Cu")
		(net "CLK_100M_CPU_MPLL1_DN")
	)
	(segment
		(start 89.045796 -24.5872)
		(end 90.525092 -26.066496)
		(width 0.1143)
		(layer "In4.Cu")
		(net "CLK_100M_CPU_MPLL1_DN")
	)
	(segment
		(start 105.080054 -30.5689)
		(end 105.370884 -30.85973)
		(width 0.1016)
		(layer "In4.Cu")
		(net "CLK_100M_CPU_MPLL1_DN")
	)
	(segment
		(start 102.562152 -33.86328)
		(end 103.868728 -33.86328)
		(width 0.1016)
		(layer "In4.Cu")
		(net "CLK_100M_CPU_MPLL1_DN")
	)
	(segment
		(start 87.0585 -24.5872)
		(end 89.045796 -24.5872)
		(width 0.1143)
		(layer "In4.Cu")
		(net "CLK_100M_CPU_MPLL1_DN")
	)
	(segment
		(start 96.090994 -33.6931)
		(end 96.4184 -33.6931)
		(width 0.1143)
		(layer "In4.Cu")
		(net "CLK_100M_CPU_MPLL1_DN")
	)
	(segment
		(start 61.7728 -24.9682)
		(end 63.737236 -24.9682)
		(width 0.1143)
		(layer "In4.Cu")
		(net "CLK_100M_CPU_MPLL1_DN")
	)
	(segment
		(start 51.8668 -33.78708)
		(end 51.8668 -33.360106)
		(width 0.1143)
		(layer "In4.Cu")
		(net "CLK_100M_CPU_MPLL1_DN")
	)
	(segment
		(start 102.328472 -33.6296)
		(end 102.562152 -33.86328)
		(width 0.1016)
		(layer "In4.Cu")
		(net "CLK_100M_CPU_MPLL1_DN")
	)
	(segment
		(start 83.756246 -24.42845)
		(end 83.914996 -24.42845)
		(width 0.1143)
		(layer "In4.Cu")
		(net "CLK_100M_CPU_MPLL1_DN")
	)
	(segment
		(start 78.14945 -25.76195)
		(end 79.39405 -24.51735)
		(width 0.1143)
		(layer "In4.Cu")
		(net "CLK_100M_CPU_MPLL1_DN")
	)
	(segment
		(start 95.071184 -28.452318)
		(end 95.071184 -32.67329)
		(width 0.1143)
		(layer "In4.Cu")
		(net "CLK_100M_CPU_MPLL1_DN")
	)
	(segment
		(start 84.3026 -24.9809)
		(end 84.6709 -25.3492)
		(width 0.1143)
		(layer "In4.Cu")
		(net "CLK_100M_CPU_MPLL1_DN")
	)
	(segment
		(start 95.071184 -32.67329)
		(end 96.090994 -33.6931)
		(width 0.1143)
		(layer "In4.Cu")
		(net "CLK_100M_CPU_MPLL1_DN")
	)
	(segment
		(start 51.8668 -33.360106)
		(end 56.32704 -28.899866)
		(width 0.1143)
		(layer "In4.Cu")
		(net "CLK_100M_CPU_MPLL1_DN")
	)
	(segment
		(start 96.4311 -33.6931)
		(end 96.4946 -33.6296)
		(width 0.1016)
		(layer "In4.Cu")
		(net "CLK_100M_CPU_MPLL1_DN")
	)
	(segment
		(start 59.12104 -28.899866)
		(end 60.73775 -27.283156)
		(width 0.1143)
		(layer "In4.Cu")
		(net "CLK_100M_CPU_MPLL1_DN")
	)
	(segment
		(start 69.743066 -24.68245)
		(end 71.133716 -26.0731)
		(width 0.1143)
		(layer "In4.Cu")
		(net "CLK_100M_CPU_MPLL1_DN")
	)
	(segment
		(start 67.26301 -23.88235)
		(end 68.06311 -24.68245)
		(width 0.1143)
		(layer "In4.Cu")
		(net "CLK_100M_CPU_MPLL1_DN")
	)
	(segment
		(start 82.69605 -24.51735)
		(end 82.931 -24.2824)
		(width 0.1143)
		(layer "In4.Cu")
		(net "CLK_100M_CPU_MPLL1_DN")
	)
	(segment
		(start 84.6709 -25.3492)
		(end 86.2965 -25.3492)
		(width 0.1143)
		(layer "In4.Cu")
		(net "CLK_100M_CPU_MPLL1_DN")
	)
	(segment
		(start 92.685362 -26.066496)
		(end 95.071184 -28.452318)
		(width 0.1143)
		(layer "In4.Cu")
		(net "CLK_100M_CPU_MPLL1_DN")
	)
	(segment
		(start 105.370884 -30.85973)
		(end 105.599484 -30.85973)
		(width 0.1016)
		(layer "In4.Cu")
		(net "CLK_100M_CPU_MPLL1_DN")
	)
	(segment
		(start 83.610196 -24.2824)
		(end 83.756246 -24.42845)
		(width 0.1143)
		(layer "In4.Cu")
		(net "CLK_100M_CPU_MPLL1_DN")
	)
	(segment
		(start 60.73775 -26.00325)
		(end 61.7728 -24.9682)
		(width 0.1143)
		(layer "In4.Cu")
		(net "CLK_100M_CPU_MPLL1_DN")
	)
	(segment
		(start 74.4728 -25.76195)
		(end 78.14945 -25.76195)
		(width 0.1143)
		(layer "In4.Cu")
		(net "CLK_100M_CPU_MPLL1_DN")
	)
	(segment
		(start 70.53834 -53.13934)
		(end 72.16521 -53.13934)
		(width 0.3048)
		(layer "F.Cu")
		(net "P3V3")
	)
	(segment
		(start 54.930294 -21.676106)
		(end 53.8734 -22.733)
		(width 0.254)
		(layer "F.Cu")
		(net "P3V3")
	)
	(segment
		(start 46.04512 -41.24452)
		(end 46.04512 -42.47388)
		(width 0.3048)
		(layer "F.Cu")
		(net "P3V3")
	)
	(segment
		(start 91.0844 -40.366442)
		(end 91.0844 -40.430958)
		(width 0.254)
		(layer "F.Cu")
		(net "P3V3")
	)
	(segment
		(start 68.15455 -58.74385)
		(end 68.15455 -56.78805)
		(width 0.3048)
		(layer "F.Cu")
		(net "P3V3")
	)
	(segment
		(start 76.0476 -50.673)
		(end 74.041 -50.673)
		(width 0.381)
		(layer "F.Cu")
		(net "P3V3")
	)
	(segment
		(start 48.68545 -23.681944)
		(end 48.8188 -23.548594)
		(width 0.4572)
		(layer "F.Cu")
		(net "P3V3")
	)
	(segment
		(start 70.682612 -44.734988)
		(end 70.682612 -44.023788)
		(width 0.3048)
		(layer "F.Cu")
		(net "P3V3")
	)
	(segment
		(start 106.7562 -66.459354)
		(end 106.7562 -65.532)
		(width 0.3048)
		(layer "F.Cu")
		(net "P3V3")
	)
	(segment
		(start 77.661516 -52.197)
		(end 78.0542 -51.804316)
		(width 0.3048)
		(layer "F.Cu")
		(net "P3V3")
	)
	(segment
		(start 67.3862 -12.573)
		(end 67.3862 -12.634976)
		(width 0.3048)
		(layer "F.Cu")
		(net "P3V3")
	)
	(segment
		(start 73.7362 -41.6814)
		(end 73.7108 -41.656)
		(width 0.3048)
		(layer "F.Cu")
		(net "P3V3")
	)
	(segment
		(start 110.8964 -69.4944)
		(end 109.728 -68.326)
		(width 0.3048)
		(layer "F.Cu")
		(net "P3V3")
	)
	(segment
		(start 72.7202 -49.3522)
		(end 72.7202 -48.73879)
		(width 0.381)
		(layer "F.Cu")
		(net "P3V3")
	)
	(segment
		(start 108.622846 -68.326)
		(end 106.7562 -66.459354)
		(width 0.3048)
		(layer "F.Cu")
		(net "P3V3")
	)
	(segment
		(start 72.9488 -43.981116)
		(end 72.9488 -43.5102)
		(width 0.3048)
		(layer "F.Cu")
		(net "P3V3")
	)
	(segment
		(start 66.6242 -13.462)
		(end 65.8622 -13.462)
		(width 0.3048)
		(layer "F.Cu")
		(net "P3V3")
	)
	(segment
		(start 77.2033 -50.5079)
		(end 77.2033 -49.7459)
		(width 0.3048)
		(layer "F.Cu")
		(net "P3V3")
	)
	(segment
		(start 68.15455 -56.78805)
		(end 68.497196 -56.445404)
		(width 0.3048)
		(layer "F.Cu")
		(net "P3V3")
	)
	(segment
		(start 73.152 -43.307)
		(end 73.7362 -43.307)
		(width 0.3048)
		(layer "F.Cu")
		(net "P3V3")
	)
	(segment
		(start 91.0844 -40.430958)
		(end 91.053158 -40.4622)
		(width 0.254)
		(layer "F.Cu")
		(net "P3V3")
	)
	(segment
		(start 69.3674 -64.773048)
		(end 70.503796 -65.909444)
		(width 0.3048)
		(layer "F.Cu")
		(net "P3V3")
	)
	(segment
		(start 69.3674 -63.043054)
		(end 69.3674 -64.773048)
		(width 0.3048)
		(layer "F.Cu")
		(net "P3V3")
	)
	(segment
		(start 50.1904 -22.5552)
		(end 50.3682 -22.733)
		(width 0.381)
		(layer "F.Cu")
		(net "P3V3")
	)
	(segment
		(start 45.58284 -40.78224)
		(end 46.04512 -41.24452)
		(width 0.3048)
		(layer "F.Cu")
		(net "P3V3")
	)
	(segment
		(start 68.15455 -59.16295)
		(end 68.15455 -61.830204)
		(width 0.3048)
		(layer "F.Cu")
		(net "P3V3")
	)
	(segment
		(start 53.8734 -22.733)
		(end 51.3588 -22.733)
		(width 0.254)
		(layer "F.Cu")
		(net "P3V3")
	)
	(segment
		(start 66.6242 -13.396976)
		(end 66.6242 -13.462)
		(width 0.3048)
		(layer "F.Cu")
		(net "P3V3")
	)
	(segment
		(start 73.50379 -47.9552)
		(end 72.7202 -48.73879)
		(width 0.3048)
		(layer "F.Cu")
		(net "P3V3")
	)
	(segment
		(start 109.728 -68.326)
		(end 108.622846 -68.326)
		(width 0.3048)
		(layer "F.Cu")
		(net "P3V3")
	)
	(segment
		(start 91.450668 -40.000174)
		(end 91.0844 -40.366442)
		(width 0.254)
		(layer "F.Cu")
		(net "P3V3")
	)
	(segment
		(start 54.930294 -19.010884)
		(end 54.930294 -21.676106)
		(width 0.254)
		(layer "F.Cu")
		(net "P3V3")
	)
	(segment
		(start 72.218804 -53.086)
		(end 73.107804 -52.197)
		(width 0.3048)
		(layer "F.Cu")
		(net "P3V3")
	)
	(segment
		(start 77.257402 -67.3354)
		(end 79.333852 -69.41185)
		(width 0.3048)
		(layer "F.Cu")
		(net "P3V3")
	)
	(segment
		(start 126.8476 -47.8536)
		(end 125.8316 -46.8376)
		(width 0.3048)
		(layer "F.Cu")
		(net "P3V3")
	)
	(segment
		(start 69.6087 -41.4909)
		(end 69.6214 -41.4782)
		(width 0.3048)
		(layer "F.Cu")
		(net "P3V3")
	)
	(segment
		(start 76.6826 -66.791586)
		(end 76.6826 -67.0306)
		(width 0.3048)
		(layer "F.Cu")
		(net "P3V3")
	)
	(segment
		(start 73.0758 -49.7078)
		(end 72.7202 -49.3522)
		(width 0.381)
		(layer "F.Cu")
		(net "P3V3")
	)
	(segment
		(start 68.072 -12.827)
		(end 67.818 -12.573)
		(width 0.3048)
		(layer "F.Cu")
		(net "P3V3")
	)
	(segment
		(start 76.9874 -67.3354)
		(end 77.257402 -67.3354)
		(width 0.3048)
		(layer "F.Cu")
		(net "P3V3")
	)
	(segment
		(start 70.0024 -44.0182)
		(end 70.6882 -44.0182)
		(width 0.3048)
		(layer "F.Cu")
		(net "P3V3")
	)
	(segment
		(start 130.429 -47.8536)
		(end 126.8476 -47.8536)
		(width 0.3048)
		(layer "F.Cu")
		(net "P3V3")
	)
	(segment
		(start 73.66 -49.7078)
		(end 73.0758 -49.7078)
		(width 0.381)
		(layer "F.Cu")
		(net "P3V3")
	)
	(segment
		(start 48.8188 -22.99208)
		(end 49.25568 -22.5552)
		(width 0.4572)
		(layer "F.Cu")
		(net "P3V3")
	)
	(segment
		(start 40.8686 -40.49268)
		(end 40.259 -41.10228)
		(width 0.3048)
		(layer "F.Cu")
		(net "P3V3")
	)
	(segment
		(start 75.800458 -65.909444)
		(end 76.6826 -66.791586)
		(width 0.3048)
		(layer "F.Cu")
		(net "P3V3")
	)
	(segment
		(start 65.602104 -13.3858)
		(end 65.786 -13.3858)
		(width 0.3048)
		(layer "F.Cu")
		(net "P3V3")
	)
	(segment
		(start 32.385 -32.8676)
		(end 31.8008 -33.4518)
		(width 0.3048)
		(layer "F.Cu")
		(net "P3V3")
	)
	(segment
		(start 68.5038 -51.054)
		(end 68.5038 -51.1048)
		(width 0.3048)
		(layer "F.Cu")
		(net "P3V3")
	)
	(segment
		(start 48.641 -23.9014)
		(end 48.68545 -23.85695)
		(width 0.4572)
		(layer "F.Cu")
		(net "P3V3")
	)
	(segment
		(start 73.66 -50.292)
		(end 73.66 -49.7078)
		(width 0.381)
		(layer "F.Cu")
		(net "P3V3")
	)
	(segment
		(start 68.5038 -51.1048)
		(end 70.53834 -53.13934)
		(width 0.3048)
		(layer "F.Cu")
		(net "P3V3")
	)
	(segment
		(start 67.818 -12.573)
		(end 67.3862 -12.573)
		(width 0.3048)
		(layer "F.Cu")
		(net "P3V3")
	)
	(segment
		(start 74.041 -50.673)
		(end 73.66 -50.292)
		(width 0.381)
		(layer "F.Cu")
		(net "P3V3")
	)
	(segment
		(start 77.2033 -49.7459)
		(end 77.089 -49.6316)
		(width 0.3048)
		(layer "F.Cu")
		(net "P3V3")
	)
	(segment
		(start 73.7362 -43.307)
		(end 73.7362 -42.418)
		(width 0.3048)
		(layer "F.Cu")
		(net "P3V3")
	)
	(segment
		(start 72.916034 -43.981116)
		(end 72.9488 -43.981116)
		(width 0.3048)
		(layer "F.Cu")
		(net "P3V3")
	)
	(segment
		(start 73.7362 -43.307)
		(end 73.7362 -44.069)
		(width 0.3048)
		(layer "F.Cu")
		(net "P3V3")
	)
	(segment
		(start 110.8964 -69.85)
		(end 110.8964 -69.4944)
		(width 0.3048)
		(layer "F.Cu")
		(net "P3V3")
	)
	(segment
		(start 68.15455 -61.830204)
		(end 69.3674 -63.043054)
		(width 0.3048)
		(layer "F.Cu")
		(net "P3V3")
	)
	(segment
		(start 40.8686 -39.4208)
		(end 40.8686 -40.49268)
		(width 0.3048)
		(layer "F.Cu")
		(net "P3V3")
	)
	(segment
		(start 45.38472 -40.78224)
		(end 45.58284 -40.78224)
		(width 0.3048)
		(layer "F.Cu")
		(net "P3V3")
	)
	(segment
		(start 45.38472 -43.13428)
		(end 45.974 -42.545)
		(width 0.3048)
		(layer "F.Cu")
		(net "P3V3")
	)
	(segment
		(start 79.47025 -69.41185)
		(end 80.3656 -70.3072)
		(width 0.3048)
		(layer "F.Cu")
		(net "P3V3")
	)
	(segment
		(start 76.6826 -67.0306)
		(end 76.9874 -67.3354)
		(width 0.3048)
		(layer "F.Cu")
		(net "P3V3")
	)
	(segment
		(start 68.497196 -56.445404)
		(end 68.776596 -56.445404)
		(width 0.3048)
		(layer "F.Cu")
		(net "P3V3")
	)
	(segment
		(start 67.3862 -12.634976)
		(end 66.6242 -13.396976)
		(width 0.3048)
		(layer "F.Cu")
		(net "P3V3")
	)
	(segment
		(start 79.333852 -69.41185)
		(end 79.47025 -69.41185)
		(width 0.3048)
		(layer "F.Cu")
		(net "P3V3")
	)
	(segment
		(start 72.16521 -53.13934)
		(end 72.218804 -53.086)
		(width 0.3048)
		(layer "F.Cu")
		(net "P3V3")
	)
	(segment
		(start 49.4284 -22.5552)
		(end 50.1904 -22.5552)
		(width 0.4572)
		(layer "F.Cu")
		(net "P3V3")
	)
	(segment
		(start 78.0542 -51.804316)
		(end 78.0542 -51.3588)
		(width 0.3048)
		(layer "F.Cu")
		(net "P3V3")
	)
	(segment
		(start 125.8316 -46.8376)
		(end 125.8316 -46.609)
		(width 0.3048)
		(layer "F.Cu")
		(net "P3V3")
	)
	(segment
		(start 45.38472 -43.19524)
		(end 45.38472 -43.13428)
		(width 0.3048)
		(layer "F.Cu")
		(net "P3V3")
	)
	(segment
		(start 71.1962 -45.248576)
		(end 70.682612 -44.734988)
		(width 0.3048)
		(layer "F.Cu")
		(net "P3V3")
	)
	(segment
		(start 77.089 -49.6316)
		(end 76.0476 -50.673)
		(width 0.381)
		(layer "F.Cu")
		(net "P3V3")
	)
	(segment
		(start 73.7362 -42.418)
		(end 73.7362 -41.6814)
		(width 0.3048)
		(layer "F.Cu")
		(net "P3V3")
	)
	(segment
		(start 69.6087 -42.1005)
		(end 69.6087 -41.4909)
		(width 0.3048)
		(layer "F.Cu")
		(net "P3V3")
	)
	(segment
		(start 65.8622 -13.462)
		(end 65.786 -13.3858)
		(width 0.3048)
		(layer "F.Cu")
		(net "P3V3")
	)
	(segment
		(start 50.3682 -22.733)
		(end 51.3588 -22.733)
		(width 0.381)
		(layer "F.Cu")
		(net "P3V3")
	)
	(segment
		(start 31.8008 -33.4518)
		(end 31.623 -33.4518)
		(width 0.3048)
		(layer "F.Cu")
		(net "P3V3")
	)
	(segment
		(start 70.682612 -44.023788)
		(end 70.6882 -44.0182)
		(width 0.3048)
		(layer "F.Cu")
		(net "P3V3")
	)
	(segment
		(start 69.9262 -44.0944)
		(end 70.0024 -44.0182)
		(width 0.3048)
		(layer "F.Cu")
		(net "P3V3")
	)
	(segment
		(start 73.6346 -47.9552)
		(end 73.50379 -47.9552)
		(width 0.3048)
		(layer "F.Cu")
		(net "P3V3")
	)
	(segment
		(start 48.68545 -23.85695)
		(end 48.68545 -23.681944)
		(width 0.4572)
		(layer "F.Cu")
		(net "P3V3")
	)
	(segment
		(start 46.04512 -42.47388)
		(end 45.974 -42.545)
		(width 0.3048)
		(layer "F.Cu")
		(net "P3V3")
	)
	(segment
		(start 64.6684 -10.4394)
		(end 65.119504 -10.890504)
		(width 0.3048)
		(layer "F.Cu")
		(net "P3V3")
	)
	(segment
		(start 69.7484 -42.2402)
		(end 69.6087 -42.1005)
		(width 0.3048)
		(layer "F.Cu")
		(net "P3V3")
	)
	(segment
		(start 67.945 -58.9534)
		(end 68.15455 -58.74385)
		(width 0.3048)
		(layer "F.Cu")
		(net "P3V3")
	)
	(segment
		(start 106.7562 -65.532)
		(end 106.807 -65.4812)
		(width 0.3048)
		(layer "F.Cu")
		(net "P3V3")
	)
	(segment
		(start 78.0542 -51.3588)
		(end 77.2033 -50.5079)
		(width 0.3048)
		(layer "F.Cu")
		(net "P3V3")
	)
	(segment
		(start 48.8188 -23.548594)
		(end 48.8188 -22.99208)
		(width 0.4572)
		(layer "F.Cu")
		(net "P3V3")
	)
	(segment
		(start 70.503796 -65.909444)
		(end 75.800458 -65.909444)
		(width 0.3048)
		(layer "F.Cu")
		(net "P3V3")
	)
	(segment
		(start 65.119504 -12.9032)
		(end 65.602104 -13.3858)
		(width 0.3048)
		(layer "F.Cu")
		(net "P3V3")
	)
	(segment
		(start 32.385 -32.81172)
		(end 32.385 -32.8676)
		(width 0.3048)
		(layer "F.Cu")
		(net "P3V3")
	)
	(segment
		(start 49.25568 -22.5552)
		(end 49.4284 -22.5552)
		(width 0.4572)
		(layer "F.Cu")
		(net "P3V3")
	)
	(segment
		(start 73.107804 -52.197)
		(end 77.661516 -52.197)
		(width 0.3048)
		(layer "F.Cu")
		(net "P3V3")
	)
	(segment
		(start 67.945 -58.9534)
		(end 68.15455 -59.16295)
		(width 0.3048)
		(layer "F.Cu")
		(net "P3V3")
	)
	(segment
		(start 71.1962 -45.3136)
		(end 71.1962 -45.248576)
		(width 0.3048)
		(layer "F.Cu")
		(net "P3V3")
	)
	(segment
		(start 65.119504 -10.890504)
		(end 65.119504 -12.9032)
		(width 0.3048)
		(layer "F.Cu")
		(net "P3V3")
	)
	(segment
		(start 72.9488 -43.5102)
		(end 73.152 -43.307)
		(width 0.3048)
		(layer "F.Cu")
		(net "P3V3")
	)
	(segment
		(start 68.39204 -12.827)
		(end 68.072 -12.827)
		(width 0.3048)
		(layer "F.Cu")
		(net "P3V3")
	)
	(via
		(at 40.259 -41.10228)
		(size 0.508)
		(drill 0.254)
		(layers "F.Cu" "B.Cu")
		(net "P3V3")
	)
	(via
		(at 48.641 -23.9014)
		(size 0.508)
		(drill 0.254)
		(layers "F.Cu" "B.Cu")
		(net "P3V3")
	)
	(via
		(at 65.452498 -43.14698)
		(size 0.508)
		(drill 0.254)
		(layers "F.Cu" "B.Cu")
		(net "P3V3")
	)
	(via
		(at 54.930294 -19.010884)
		(size 0.7112)
		(drill 0.4064)
		(layers "F.Cu" "B.Cu")
		(net "P3V3")
	)
	(via
		(at 72.7964 -41.5544)
		(size 0.7112)
		(drill 0.3556)
		(layers "F.Cu" "B.Cu")
		(net "P3V3")
	)
	(via
		(at 174.4218 -47.5996)
		(size 0.508)
		(drill 0.254)
		(layers "F.Cu" "B.Cu")
		(net "P3V3")
	)
	(via
		(at 110.8964 -69.85)
		(size 0.508)
		(drill 0.254)
		(layers "F.Cu" "B.Cu")
		(net "P3V3")
	)
	(via
		(at 70.877684 -56.404002)
		(size 0.7112)
		(drill 0.3556)
		(layers "F.Cu" "B.Cu")
		(net "P3V3")
	)
	(via
		(at 50.6984 -40.6654)
		(size 0.5588)
		(drill 0.3048)
		(layers "F.Cu" "B.Cu")
		(net "P3V3")
	)
	(via
		(at 69.6214 -41.4782)
		(size 0.508)
		(drill 0.254)
		(layers "F.Cu" "B.Cu")
		(net "P3V3")
	)
	(via
		(at 77.089 -49.6316)
		(size 0.4318)
		(drill 0.2032)
		(layers "F.Cu" "B.Cu")
		(net "P3V3")
	)
	(via
		(at 14.6812 -67.0814)
		(size 0.508)
		(drill 0.254)
		(layers "F.Cu" "B.Cu")
		(net "P3V3")
	)
	(via
		(at 91.053158 -40.4622)
		(size 0.4318)
		(drill 0.2032)
		(layers "F.Cu" "B.Cu")
		(net "P3V3")
	)
	(via
		(at 14.6812 -67.945)
		(size 0.508)
		(drill 0.254)
		(layers "F.Cu" "B.Cu")
		(net "P3V3")
	)
	(via
		(at 173.3804 -29.0322)
		(size 0.508)
		(drill 0.254)
		(layers "F.Cu" "B.Cu")
		(net "P3V3")
	)
	(via
		(at 36.2966 -35.20313)
		(size 0.508)
		(drill 0.254)
		(layers "F.Cu" "B.Cu")
		(net "P3V3")
	)
	(via
		(at 125.8316 -46.609)
		(size 0.508)
		(drill 0.254)
		(layers "F.Cu" "B.Cu")
		(net "P3V3")
	)
	(via
		(at 73.6854 -48.4886)
		(size 0.7112)
		(drill 0.3556)
		(layers "F.Cu" "B.Cu")
		(net "P3V3")
	)
	(via
		(at 68.776596 -56.445404)
		(size 0.508)
		(drill 0.254)
		(layers "F.Cu" "B.Cu")
		(net "P3V3")
	)
	(via
		(at 51.1048 -41.7068)
		(size 0.7112)
		(drill 0.4064)
		(layers "F.Cu" "B.Cu")
		(net "P3V3")
	)
	(via
		(at 53.9242 -39.9542)
		(size 0.7112)
		(drill 0.4064)
		(layers "F.Cu" "B.Cu")
		(net "P3V3")
	)
	(via
		(at 144.5006 -50.0126)
		(size 0.7112)
		(drill 0.3556)
		(layers "F.Cu" "B.Cu")
		(net "P3V3")
	)
	(via
		(at 72.916034 -43.981116)
		(size 0.508)
		(drill 0.254)
		(layers "F.Cu" "B.Cu")
		(net "P3V3")
	)
	(via
		(at 49.9872 -15.9004)
		(size 0.5588)
		(drill 0.3048)
		(layers "F.Cu" "B.Cu")
		(net "P3V3")
	)
	(via
		(at 32.385 -32.81172)
		(size 0.508)
		(drill 0.254)
		(layers "F.Cu" "B.Cu")
		(net "P3V3")
	)
	(via
		(at 70.832472 -14.224)
		(size 0.508)
		(drill 0.254)
		(layers "F.Cu" "B.Cu")
		(net "P3V3")
	)
	(via
		(at 57.6326 -33.8582)
		(size 0.7112)
		(drill 0.4064)
		(layers "F.Cu" "B.Cu")
		(net "P3V3")
	)
	(via
		(at 49.5046 -31.5468)
		(size 0.508)
		(drill 0.254)
		(layers "F.Cu" "B.Cu")
		(net "P3V3")
	)
	(via
		(at 45.974 -42.545)
		(size 0.508)
		(drill 0.254)
		(layers "F.Cu" "B.Cu")
		(net "P3V3")
	)
	(via
		(at 112.141 -15.875)
		(size 0.7112)
		(drill 0.3556)
		(layers "F.Cu" "B.Cu")
		(net "P3V3")
	)
	(via
		(at 59.7916 -16.1036)
		(size 0.508)
		(drill 0.254)
		(layers "F.Cu" "B.Cu")
		(net "P3V3")
	)
	(via
		(at 106.807 -65.4812)
		(size 0.508)
		(drill 0.254)
		(layers "F.Cu" "B.Cu")
		(net "P3V3")
	)
	(via
		(at 88.7984 -49.4792)
		(size 0.4318)
		(drill 0.2032)
		(layers "F.Cu" "B.Cu")
		(net "P3V3")
	)
	(via
		(at 15.367 -65.5574)
		(size 0.7112)
		(drill 0.3556)
		(layers "F.Cu" "B.Cu")
		(net "P3V3")
	)
	(via
		(at 170.307 -28.4226)
		(size 0.7112)
		(drill 0.3556)
		(layers "F.Cu" "B.Cu")
		(net "P3V3")
	)
	(via
		(at 64.6684 -10.4394)
		(size 0.508)
		(drill 0.254)
		(layers "F.Cu" "B.Cu")
		(net "P3V3")
	)
	(via
		(at 34.663126 -22.835108)
		(size 0.508)
		(drill 0.254)
		(layers "F.Cu" "B.Cu")
		(net "P3V3")
	)
	(via
		(at 51.3588 -22.733)
		(size 0.508)
		(drill 0.254)
		(layers "F.Cu" "B.Cu")
		(net "P3V3")
	)
	(via
		(at 65.693036 -24.3459)
		(size 0.508)
		(drill 0.254)
		(layers "F.Cu" "B.Cu")
		(net "P3V3")
	)
	(via
		(at 12.7 -68.58)
		(size 0.508)
		(drill 0.254)
		(layers "F.Cu" "B.Cu")
		(net "P3V3")
	)
	(via
		(at 16.0528 -49.5046)
		(size 0.7112)
		(drill 0.4064)
		(layers "F.Cu" "B.Cu")
		(net "P3V3")
	)
	(via
		(at 72.7202 -48.73879)
		(size 0.508)
		(drill 0.254)
		(layers "F.Cu" "B.Cu")
		(net "P3V3")
	)
	(via
		(at 54.0004 -41.021)
		(size 0.7112)
		(drill 0.4064)
		(layers "F.Cu" "B.Cu")
		(net "P3V3")
	)
	(via
		(at 18.0086 -49.2252)
		(size 0.7112)
		(drill 0.4064)
		(layers "F.Cu" "B.Cu")
		(net "P3V3")
	)
	(via
		(at 70.6882 -44.0182)
		(size 0.508)
		(drill 0.254)
		(layers "F.Cu" "B.Cu")
		(net "P3V3")
	)
	(via
		(at 191.262 -69.1134)
		(size 0.4318)
		(drill 0.2032)
		(layers "F.Cu" "B.Cu")
		(net "P3V3")
	)
	(via
		(at 80.3656 -70.3072)
		(size 0.508)
		(drill 0.254)
		(layers "F.Cu" "B.Cu")
		(net "P3V3")
	)
	(segment
		(start 74.4982 -49.149)
		(end 74.4982 -49.0982)
		(width 0.3048)
		(layer "B.Cu")
		(net "P3V3")
	)
	(segment
		(start 104.1908 -15.09268)
		(end 104.18572 -15.09776)
		(width 0.3048)
		(layer "B.Cu")
		(net "P3V3")
	)
	(segment
		(start 164.331142 -24.896826)
		(end 167.856916 -28.4226)
		(width 0.3048)
		(layer "B.Cu")
		(net "P3V3")
	)
	(segment
		(start 144.5514 -50.0634)
		(end 155.623768 -50.0634)
		(width 0.3048)
		(layer "B.Cu")
		(net "P3V3")
	)
	(segment
		(start 112.02035 -3.49885)
		(end 111.0742 -4.445)
		(width 0.3048)
		(layer "B.Cu")
		(net "P3V3")
	)
	(segment
		(start 65.693036 -24.3459)
		(end 65.693036 -24.341836)
		(width 0.381)
		(layer "B.Cu")
		(net "P3V3")
	)
	(segment
		(start 59.4741 -16.0401)
		(end 59.7281 -16.0401)
		(width 0.3048)
		(layer "B.Cu")
		(net "P3V3")
	)
	(segment
		(start 125.8316 -46.609)
		(end 125.8316 -47.28972)
		(width 0.3048)
		(layer "B.Cu")
		(net "P3V3")
	)
	(segment
		(start 111.49076 -6.25856)
		(end 112.08004 -5.66928)
		(width 0.254)
		(layer "B.Cu")
		(net "P3V3")
	)
	(segment
		(start 113.508282 -6.32968)
		(end 113.508282 -8.374888)
		(width 0.254)
		(layer "B.Cu")
		(net "P3V3")
	)
	(segment
		(start 74.741278 -55.54345)
		(end 71.738236 -55.54345)
		(width 0.381)
		(layer "B.Cu")
		(net "P3V3")
	)
	(segment
		(start 35.3314 -21.2344)
		(end 35.687 -20.8788)
		(width 0.3048)
		(layer "B.Cu")
		(net "P3V3")
	)
	(segment
		(start 58.674 -15.24)
		(end 59.4741 -16.0401)
		(width 0.3048)
		(layer "B.Cu")
		(net "P3V3")
	)
	(segment
		(start 57.327546 -19.101054)
		(end 59.7916 -16.637)
		(width 0.3048)
		(layer "B.Cu")
		(net "P3V3")
	)
	(segment
		(start 88.265 -47.96155)
		(end 88.2269 -47.99965)
		(width 0.254)
		(layer "B.Cu")
		(net "P3V3")
	)
	(segment
		(start 112.08004 -5.66928)
		(end 113.07445 -5.66928)
		(width 0.254)
		(layer "B.Cu")
		(net "P3V3")
	)
	(segment
		(start 117.6528 -6.096)
		(end 117.983 -6.4262)
		(width 0.3048)
		(layer "B.Cu")
		(net "P3V3")
	)
	(segment
		(start 196.7992 -66.04)
		(end 196.7992 -66.802)
		(width 0.3048)
		(layer "B.Cu")
		(net "P3V3")
	)
	(segment
		(start 89.8906 -40.2082)
		(end 90.424 -40.2082)
		(width 0.3048)
		(layer "B.Cu")
		(net "P3V3")
	)
	(segment
		(start 90.799158 -40.2082)
		(end 91.053158 -40.4622)
		(width 0.3048)
		(layer "B.Cu")
		(net "P3V3")
	)
	(segment
		(start 113.22304 -6.044438)
		(end 113.508282 -6.32968)
		(width 0.254)
		(layer "B.Cu")
		(net "P3V3")
	)
	(segment
		(start 73.2028 -44.196)
		(end 72.987916 -43.981116)
		(width 0.3048)
		(layer "B.Cu")
		(net "P3V3")
	)
	(segment
		(start 88.392 -46.6598)
		(end 88.265 -46.7868)
		(width 0.254)
		(layer "B.Cu")
		(net "P3V3")
	)
	(segment
		(start 76.9874 -53.297328)
		(end 74.741278 -55.54345)
		(width 0.381)
		(layer "B.Cu")
		(net "P3V3")
	)
	(segment
		(start 70.6882 -44.0182)
		(end 70.725284 -43.981116)
		(width 0.508)
		(layer "B.Cu")
		(net "P3V3")
	)
	(segment
		(start 73.914 -48.514)
		(end 73.7108 -48.514)
		(width 0.3048)
		(layer "B.Cu")
		(net "P3V3")
	)
	(segment
		(start 73.569576 -40.767)
		(end 72.9996 -40.197024)
		(width 0.3048)
		(layer "B.Cu")
		(net "P3V3")
	)
	(segment
		(start 70.682612 -44.023788)
		(end 70.6882 -44.0182)
		(width 0.3048)
		(layer "B.Cu")
		(net "P3V3")
	)
	(segment
		(start 115.243102 -3.49885)
		(end 112.02035 -3.49885)
		(width 0.3048)
		(layer "B.Cu")
		(net "P3V3")
	)
	(segment
		(start 144.5006 -50.0126)
		(end 144.5514 -50.0634)
		(width 0.3048)
		(layer "B.Cu")
		(net "P3V3")
	)
	(segment
		(start 69.215 -41.8846)
		(end 69.6214 -41.4782)
		(width 0.508)
		(layer "B.Cu")
		(net "P3V3")
	)
	(segment
		(start 114.2746 -23.8125)
		(end 114.2746 -17.9324)
		(width 0.3048)
		(layer "B.Cu")
		(net "P3V3")
	)
	(segment
		(start 34.663126 -22.835108)
		(end 35.3314 -22.166834)
		(width 0.3048)
		(layer "B.Cu")
		(net "P3V3")
	)
	(segment
		(start 56.537352 -19.101054)
		(end 57.327546 -19.101054)
		(width 0.3048)
		(layer "B.Cu")
		(net "P3V3")
	)
	(segment
		(start 72.9996 -40.197024)
		(end 72.9996 -38.0746)
		(width 0.3048)
		(layer "B.Cu")
		(net "P3V3")
	)
	(segment
		(start 110.236 -13.97)
		(end 110.236 -13.7668)
		(width 0.3048)
		(layer "B.Cu")
		(net "P3V3")
	)
	(segment
		(start 117.983 -6.436106)
		(end 119.253 -7.706106)
		(width 0.3048)
		(layer "B.Cu")
		(net "P3V3")
	)
	(segment
		(start 90.424 -40.2082)
		(end 90.799158 -40.2082)
		(width 0.3048)
		(layer "B.Cu")
		(net "P3V3")
	)
	(segment
		(start 103.251 -17.3228)
		(end 103.251 -16.03248)
		(width 0.3048)
		(layer "B.Cu")
		(net "P3V3")
	)
	(segment
		(start 119.253 -21.682456)
		(end 120.887236 -23.316692)
		(width 0.3048)
		(layer "B.Cu")
		(net "P3V3")
	)
	(segment
		(start 170.307 -28.4226)
		(end 172.7708 -28.4226)
		(width 0.3048)
		(layer "B.Cu")
		(net "P3V3")
	)
	(segment
		(start 89.6112 -40.4876)
		(end 89.8906 -40.2082)
		(width 0.3048)
		(layer "B.Cu")
		(net "P3V3")
	)
	(segment
		(start 73.5838 -40.767)
		(end 73.569576 -40.767)
		(width 0.3048)
		(layer "B.Cu")
		(net "P3V3")
	)
	(segment
		(start 69.589142 -43.525186)
		(end 69.215 -43.151044)
		(width 0.508)
		(layer "B.Cu")
		(net "P3V3")
	)
	(segment
		(start 71.738236 -55.54345)
		(end 70.877684 -56.404002)
		(width 0.381)
		(layer "B.Cu")
		(net "P3V3")
	)
	(segment
		(start 88.265 -46.7868)
		(end 88.265 -47.96155)
		(width 0.254)
		(layer "B.Cu")
		(net "P3V3")
	)
	(segment
		(start 72.3646 -41.9862)
		(end 72.7964 -41.5544)
		(width 0.3048)
		(layer "B.Cu")
		(net "P3V3")
	)
	(segment
		(start 122.6185 -35.969956)
		(end 122.6185 -32.1564)
		(width 0.3048)
		(layer "B.Cu")
		(net "P3V3")
	)
	(segment
		(start 65.693036 -24.341836)
		(end 65.4812 -24.13)
		(width 0.381)
		(layer "B.Cu")
		(net "P3V3")
	)
	(segment
		(start 70.597014 -44.0182)
		(end 70.104 -43.525186)
		(width 0.508)
		(layer "B.Cu")
		(net "P3V3")
	)
	(segment
		(start 117.22608 -5.66928)
		(end 117.22608 -5.09524)
		(width 0.3048)
		(layer "B.Cu")
		(net "P3V3")
	)
	(segment
		(start 111.0742 -5.842)
		(end 111.49076 -6.25856)
		(width 0.3048)
		(layer "B.Cu")
		(net "P3V3")
	)
	(segment
		(start 70.104 -43.525186)
		(end 69.589142 -43.525186)
		(width 0.508)
		(layer "B.Cu")
		(net "P3V3")
	)
	(segment
		(start 167.856916 -28.4226)
		(end 170.307 -28.4226)
		(width 0.3048)
		(layer "B.Cu")
		(net "P3V3")
	)
	(segment
		(start 117.22608 -5.09524)
		(end 116.839492 -5.09524)
		(width 0.3048)
		(layer "B.Cu")
		(net "P3V3")
	)
	(segment
		(start 69.215 -43.151044)
		(end 69.215 -41.8846)
		(width 0.508)
		(layer "B.Cu")
		(net "P3V3")
	)
	(segment
		(start 73.7362 -45.085)
		(end 73.7362 -44.196)
		(width 0.3048)
		(layer "B.Cu")
		(net "P3V3")
	)
	(segment
		(start 88.2269 -47.99965)
		(end 88.2269 -49.226216)
		(width 0.254)
		(layer "B.Cu")
		(net "P3V3")
	)
	(segment
		(start 104.1908 -14.097)
		(end 104.1908 -15.09268)
		(width 0.3048)
		(layer "B.Cu")
		(net "P3V3")
	)
	(segment
		(start 88.479884 -49.4792)
		(end 88.7984 -49.4792)
		(width 0.254)
		(layer "B.Cu")
		(net "P3V3")
	)
	(segment
		(start 127.82423 -23.316692)
		(end 128.2065 -22.934422)
		(width 0.3048)
		(layer "B.Cu")
		(net "P3V3")
	)
	(segment
		(start 164.8714 -48.7426)
		(end 166.216076 -47.397924)
		(width 0.3048)
		(layer "B.Cu")
		(net "P3V3")
	)
	(segment
		(start 72.771 -48.73879)
		(end 72.7202 -48.73879)
		(width 0.3048)
		(layer "B.Cu")
		(net "P3V3")
	)
	(segment
		(start 112.2172 -15.875)
		(end 112.141 -15.875)
		(width 0.3048)
		(layer "B.Cu")
		(net "P3V3")
	)
	(segment
		(start 65.4812 -24.13)
		(end 65.4812 -22.9108)
		(width 0.381)
		(layer "B.Cu")
		(net "P3V3")
	)
	(segment
		(start 125.8316 -47.28972)
		(end 128.55448 -50.0126)
		(width 0.3048)
		(layer "B.Cu")
		(net "P3V3")
	)
	(segment
		(start 73.7108 -48.514)
		(end 73.6854 -48.4886)
		(width 0.3048)
		(layer "B.Cu")
		(net "P3V3")
	)
	(segment
		(start 114.2746 -17.9324)
		(end 112.2172 -15.875)
		(width 0.3048)
		(layer "B.Cu")
		(net "P3V3")
	)
	(segment
		(start 128.2065 -21.289772)
		(end 130.001772 -19.4945)
		(width 0.3048)
		(layer "B.Cu")
		(net "P3V3")
	)
	(segment
		(start 113.22304 -5.81787)
		(end 113.22304 -6.044438)
		(width 0.254)
		(layer "B.Cu")
		(net "P3V3")
	)
	(segment
		(start 69.353684 -57.022492)
		(end 68.776596 -56.445404)
		(width 0.381)
		(layer "B.Cu")
		(net "P3V3")
	)
	(segment
		(start 125.8316 -46.609)
		(end 125.8316 -39.183056)
		(width 0.3048)
		(layer "B.Cu")
		(net "P3V3")
	)
	(segment
		(start 73.5838 -40.767)
		(end 73.7362 -40.767)
		(width 0.3048)
		(layer "B.Cu")
		(net "P3V3")
	)
	(segment
		(start 36.5252 -28.448)
		(end 36.26485 -28.70835)
		(width 0.254)
		(layer "B.Cu")
		(net "P3V3")
	)
	(segment
		(start 14.855698 -63.935102)
		(end 14.220698 -63.935102)
		(width 0.254)
		(layer "B.Cu")
		(net "P3V3")
	)
	(segment
		(start 70.877684 -56.404002)
		(end 70.259194 -57.022492)
		(width 0.381)
		(layer "B.Cu")
		(net "P3V3")
	)
	(segment
		(start 88.2269 -49.226216)
		(end 88.479884 -49.4792)
		(width 0.254)
		(layer "B.Cu")
		(net "P3V3")
	)
	(segment
		(start 35.3314 -22.166834)
		(end 35.3314 -21.2344)
		(width 0.3048)
		(layer "B.Cu")
		(net "P3V3")
	)
	(segment
		(start 70.358 -13.749528)
		(end 70.832472 -14.224)
		(width 0.381)
		(layer "B.Cu")
		(net "P3V3")
	)
	(segment
		(start 72.987916 -43.981116)
		(end 72.916034 -43.981116)
		(width 0.3048)
		(layer "B.Cu")
		(net "P3V3")
	)
	(segment
		(start 50.3174 -30.734)
		(end 50.3174 -30.5308)
		(width 0.381)
		(layer "B.Cu")
		(net "P3V3")
	)
	(segment
		(start 113.07445 -8.80872)
		(end 113.03508 -8.80872)
		(width 0.254)
		(layer "B.Cu")
		(net "P3V3")
	)
	(segment
		(start 111.49076 -6.25856)
		(end 111.49076 -6.30428)
		(width 0.3048)
		(layer "B.Cu")
		(net "P3V3")
	)
	(segment
		(start 73.6092 -37.465)
		(end 73.6092 -36.703)
		(width 0.3048)
		(layer "B.Cu")
		(net "P3V3")
	)
	(segment
		(start 48.055276 -31.5468)
		(end 49.5046 -31.5468)
		(width 0.254)
		(layer "B.Cu")
		(net "P3V3")
	)
	(segment
		(start 40.64 -41.8338)
		(end 40.64 -41.48328)
		(width 0.3048)
		(layer "B.Cu")
		(net "P3V3")
	)
	(segment
		(start 72.9996 -38.0746)
		(end 73.6092 -37.465)
		(width 0.3048)
		(layer "B.Cu")
		(net "P3V3")
	)
	(segment
		(start 164.331142 -21.892514)
		(end 164.331142 -24.896826)
		(width 0.3048)
		(layer "B.Cu")
		(net "P3V3")
	)
	(segment
		(start 113.508282 -8.374888)
		(end 113.07445 -8.80872)
		(width 0.254)
		(layer "B.Cu")
		(net "P3V3")
	)
	(segment
		(start 116.839492 -5.09524)
		(end 115.243102 -3.49885)
		(width 0.3048)
		(layer "B.Cu")
		(net "P3V3")
	)
	(segment
		(start 106.2482 -17.3228)
		(end 103.251 -17.3228)
		(width 0.3048)
		(layer "B.Cu")
		(net "P3V3")
	)
	(segment
		(start 74.4982 -49.0982)
		(end 73.914 -48.514)
		(width 0.3048)
		(layer "B.Cu")
		(net "P3V3")
	)
	(segment
		(start 111.0742 -4.445)
		(end 111.0742 -5.842)
		(width 0.3048)
		(layer "B.Cu")
		(net "P3V3")
	)
	(segment
		(start 56.77535 -31.100014)
		(end 55.753508 -31.100014)
		(width 0.508)
		(layer "B.Cu")
		(net "P3V3")
	)
	(segment
		(start 77.089 -49.6316)
		(end 76.9874 -49.7332)
		(width 0.381)
		(layer "B.Cu")
		(net "P3V3")
	)
	(segment
		(start 45.3644 -28.7528)
		(end 46.1264 -28.7528)
		(width 0.254)
		(layer "B.Cu")
		(net "P3V3")
	)
	(segment
		(start 120.887236 -23.316692)
		(end 127.82423 -23.316692)
		(width 0.3048)
		(layer "B.Cu")
		(net "P3V3")
	)
	(segment
		(start 72.7964 -41.5544)
		(end 73.5838 -40.767)
		(width 0.3048)
		(layer "B.Cu")
		(net "P3V3")
	)
	(segment
		(start 172.7708 -28.4226)
		(end 173.3804 -29.0322)
		(width 0.3048)
		(layer "B.Cu")
		(net "P3V3")
	)
	(segment
		(start 130.001772 -19.4945)
		(end 161.933128 -19.4945)
		(width 0.3048)
		(layer "B.Cu")
		(net "P3V3")
	)
	(segment
		(start 73.6854 -48.4886)
		(end 73.02119 -48.4886)
		(width 0.3048)
		(layer "B.Cu")
		(net "P3V3")
	)
	(segment
		(start 156.944568 -48.7426)
		(end 164.8714 -48.7426)
		(width 0.3048)
		(layer "B.Cu")
		(net "P3V3")
	)
	(segment
		(start 76.9874 -49.7332)
		(end 76.9874 -53.297328)
		(width 0.381)
		(layer "B.Cu")
		(net "P3V3")
	)
	(segment
		(start 155.623768 -50.0634)
		(end 156.944568 -48.7426)
		(width 0.3048)
		(layer "B.Cu")
		(net "P3V3")
	)
	(segment
		(start 70.4596 -45.1612)
		(end 70.682612 -44.938188)
		(width 0.3048)
		(layer "B.Cu")
		(net "P3V3")
	)
	(segment
		(start 52.6796 -22.3266)
		(end 51.7652 -22.3266)
		(width 0.254)
		(layer "B.Cu")
		(net "P3V3")
	)
	(segment
		(start 40.64 -41.48328)
		(end 40.259 -41.10228)
		(width 0.3048)
		(layer "B.Cu")
		(net "P3V3")
	)
	(segment
		(start 70.682612 -44.938188)
		(end 70.682612 -44.023788)
		(width 0.3048)
		(layer "B.Cu")
		(net "P3V3")
	)
	(segment
		(start 195.83146 -68.53174)
		(end 196.7992 -67.564)
		(width 0.3048)
		(layer "B.Cu")
		(net "P3V3")
	)
	(segment
		(start 40.21328 -41.148)
		(end 40.259 -41.10228)
		(width 0.3048)
		(layer "B.Cu")
		(net "P3V3")
	)
	(segment
		(start 69.6214 -41.4782)
		(end 70.1294 -41.9862)
		(width 0.3048)
		(layer "B.Cu")
		(net "P3V3")
	)
	(segment
		(start 36.26485 -35.17138)
		(end 36.2966 -35.20313)
		(width 0.254)
		(layer "B.Cu")
		(net "P3V3")
	)
	(segment
		(start 117.6528 -6.096)
		(end 117.22608 -5.66928)
		(width 0.3048)
		(layer "B.Cu")
		(net "P3V3")
	)
	(segment
		(start 58.4708 -15.24)
		(end 58.674 -15.24)
		(width 0.3048)
		(layer "B.Cu")
		(net "P3V3")
	)
	(segment
		(start 39.1668 -41.148)
		(end 40.21328 -41.148)
		(width 0.3048)
		(layer "B.Cu")
		(net "P3V3")
	)
	(segment
		(start 109.8042 -13.7668)
		(end 106.2482 -17.3228)
		(width 0.3048)
		(layer "B.Cu")
		(net "P3V3")
	)
	(segment
		(start 117.22608 -5.09524)
		(end 119.09552 -5.09524)
		(width 0.3048)
		(layer "B.Cu")
		(net "P3V3")
	)
	(segment
		(start 112.141 -15.875)
		(end 110.236 -13.97)
		(width 0.3048)
		(layer "B.Cu")
		(net "P3V3")
	)
	(segment
		(start 128.55448 -50.0126)
		(end 144.5006 -50.0126)
		(width 0.3048)
		(layer "B.Cu")
		(net "P3V3")
	)
	(segment
		(start 73.7362 -42.672)
		(end 73.7362 -43.434)
		(width 0.3048)
		(layer "B.Cu")
		(net "P3V3")
	)
	(segment
		(start 128.2065 -22.934422)
		(end 128.2065 -21.289772)
		(width 0.3048)
		(layer "B.Cu")
		(net "P3V3")
	)
	(segment
		(start 36.26485 -28.70835)
		(end 36.26485 -35.17138)
		(width 0.254)
		(layer "B.Cu")
		(net "P3V3")
	)
	(segment
		(start 161.933128 -19.4945)
		(end 164.331142 -21.892514)
		(width 0.3048)
		(layer "B.Cu")
		(net "P3V3")
	)
	(segment
		(start 70.725284 -43.981116)
		(end 72.916034 -43.981116)
		(width 0.508)
		(layer "B.Cu")
		(net "P3V3")
	)
	(segment
		(start 46.1264 -28.7528)
		(end 46.1264 -29.617924)
		(width 0.254)
		(layer "B.Cu")
		(net "P3V3")
	)
	(segment
		(start 122.6185 -32.1564)
		(end 114.2746 -23.8125)
		(width 0.3048)
		(layer "B.Cu")
		(net "P3V3")
	)
	(segment
		(start 70.1294 -41.9862)
		(end 72.3646 -41.9862)
		(width 0.3048)
		(layer "B.Cu")
		(net "P3V3")
	)
	(segment
		(start 49.5046 -31.5468)
		(end 50.3174 -30.734)
		(width 0.381)
		(layer "B.Cu")
		(net "P3V3")
	)
	(segment
		(start 117.983 -6.4262)
		(end 117.983 -6.436106)
		(width 0.3048)
		(layer "B.Cu")
		(net "P3V3")
	)
	(segment
		(start 113.07445 -5.66928)
		(end 113.22304 -5.81787)
		(width 0.254)
		(layer "B.Cu")
		(net "P3V3")
	)
	(segment
		(start 73.7362 -44.196)
		(end 73.2028 -44.196)
		(width 0.3048)
		(layer "B.Cu")
		(net "P3V3")
	)
	(segment
		(start 191.262 -69.1134)
		(end 191.84366 -68.53174)
		(width 0.3048)
		(layer "B.Cu")
		(net "P3V3")
	)
	(segment
		(start 103.251 -16.03248)
		(end 104.18572 -15.09776)
		(width 0.3048)
		(layer "B.Cu")
		(net "P3V3")
	)
	(segment
		(start 57.531 -31.855664)
		(end 56.77535 -31.100014)
		(width 0.508)
		(layer "B.Cu")
		(net "P3V3")
	)
	(segment
		(start 70.358 -13.3858)
		(end 70.358 -13.749528)
		(width 0.381)
		(layer "B.Cu")
		(net "P3V3")
	)
	(segment
		(start 125.8316 -39.183056)
		(end 122.6185 -35.969956)
		(width 0.3048)
		(layer "B.Cu")
		(net "P3V3")
	)
	(segment
		(start 51.7652 -22.3266)
		(end 51.3588 -22.733)
		(width 0.254)
		(layer "B.Cu")
		(net "P3V3")
	)
	(segment
		(start 119.253 -7.706106)
		(end 119.253 -21.682456)
		(width 0.3048)
		(layer "B.Cu")
		(net "P3V3")
	)
	(segment
		(start 70.259194 -57.022492)
		(end 69.353684 -57.022492)
		(width 0.381)
		(layer "B.Cu")
		(net "P3V3")
	)
	(segment
		(start 73.02119 -48.4886)
		(end 72.771 -48.73879)
		(width 0.3048)
		(layer "B.Cu")
		(net "P3V3")
	)
	(segment
		(start 59.7916 -16.637)
		(end 59.7916 -16.1036)
		(width 0.3048)
		(layer "B.Cu")
		(net "P3V3")
	)
	(segment
		(start 110.236 -13.7668)
		(end 109.8042 -13.7668)
		(width 0.3048)
		(layer "B.Cu")
		(net "P3V3")
	)
	(segment
		(start 70.6882 -44.0182)
		(end 70.597014 -44.0182)
		(width 0.508)
		(layer "B.Cu")
		(net "P3V3")
	)
	(segment
		(start 196.7992 -67.564)
		(end 196.7992 -66.802)
		(width 0.3048)
		(layer "B.Cu")
		(net "P3V3")
	)
	(segment
		(start 59.7281 -16.0401)
		(end 59.7916 -16.1036)
		(width 0.3048)
		(layer "B.Cu")
		(net "P3V3")
	)
	(segment
		(start 65.4812 -22.9108)
		(end 66.3702 -22.9108)
		(width 0.381)
		(layer "B.Cu")
		(net "P3V3")
	)
	(segment
		(start 174.220124 -47.397924)
		(end 174.4218 -47.5996)
		(width 0.3048)
		(layer "B.Cu")
		(net "P3V3")
	)
	(segment
		(start 113.03508 -8.80872)
		(end 112.6998 -9.144)
		(width 0.254)
		(layer "B.Cu")
		(net "P3V3")
	)
	(segment
		(start 73.7362 -43.434)
		(end 73.7362 -44.196)
		(width 0.3048)
		(layer "B.Cu")
		(net "P3V3")
	)
	(segment
		(start 166.216076 -47.397924)
		(end 174.220124 -47.397924)
		(width 0.3048)
		(layer "B.Cu")
		(net "P3V3")
	)
	(segment
		(start 46.1264 -29.617924)
		(end 48.055276 -31.5468)
		(width 0.254)
		(layer "B.Cu")
		(net "P3V3")
	)
	(segment
		(start 191.84366 -68.53174)
		(end 195.83146 -68.53174)
		(width 0.3048)
		(layer "B.Cu")
		(net "P3V3")
	)
	(segment
		(start 74.4982 -49.911)
		(end 74.4982 -49.149)
		(width 0.3048)
		(layer "B.Cu")
		(net "P3V3")
	)
	(segment
		(start 64.6684 -10.4394)
		(end 66.548 -12.319)
		(width 0.3048)
		(layer "In2.Cu")
		(net "P3V3")
	)
	(segment
		(start 192.151 -64.181228)
		(end 192.151 -63.881508)
		(width 0.3048)
		(layer "In2.Cu")
		(net "P3V3")
	)
	(segment
		(start 172.974508 -46.609508)
		(end 173.9646 -47.5996)
		(width 0.3048)
		(layer "In2.Cu")
		(net "P3V3")
	)
	(segment
		(start 126.365 -66.527934)
		(end 125.521466 -65.6844)
		(width 0.3048)
		(layer "In2.Cu")
		(net "P3V3")
	)
	(segment
		(start 47.2948 -25.0444)
		(end 47.2948 -24.4094)
		(width 0.4572)
		(layer "In2.Cu")
		(net "P3V3")
	)
	(segment
		(start 180.6956 -47.5996)
		(end 174.4218 -47.5996)
		(width 0.3048)
		(layer "In2.Cu")
		(net "P3V3")
	)
	(segment
		(start 123.545092 -65.683892)
		(end 122.57786 -64.71666)
		(width 0.3048)
		(layer "In2.Cu")
		(net "P3V3")
	)
	(segment
		(start 125.521466 -65.6844)
		(end 125.20295 -65.6844)
		(width 0.3048)
		(layer "In2.Cu")
		(net "P3V3")
	)
	(segment
		(start 66.548 -12.319)
		(end 68.927472 -12.319)
		(width 0.3048)
		(layer "In2.Cu")
		(net "P3V3")
	)
	(segment
		(start 173.6344 -29.2862)
		(end 173.6344 -43.5356)
		(width 0.3048)
		(layer "In2.Cu")
		(net "P3V3")
	)
	(segment
		(start 191.262 -68.58)
		(end 190.5 -67.818)
		(width 0.3048)
		(layer "In2.Cu")
		(net "P3V3")
	)
	(segment
		(start 182.9054 -49.8094)
		(end 180.6956 -47.5996)
		(width 0.3048)
		(layer "In2.Cu")
		(net "P3V3")
	)
	(segment
		(start 47.2948 -24.4094)
		(end 47.6758 -24.0284)
		(width 0.4572)
		(layer "In2.Cu")
		(net "P3V3")
	)
	(segment
		(start 182.9054 -54.635908)
		(end 182.9054 -49.8094)
		(width 0.3048)
		(layer "In2.Cu")
		(net "P3V3")
	)
	(segment
		(start 191.262 -69.1134)
		(end 191.262 -68.58)
		(width 0.3048)
		(layer "In2.Cu")
		(net "P3V3")
	)
	(segment
		(start 190.5 -67.818)
		(end 190.5 -65.832228)
		(width 0.3048)
		(layer "In2.Cu")
		(net "P3V3")
	)
	(segment
		(start 49.5046 -31.5468)
		(end 49.5046 -27.2542)
		(width 0.4572)
		(layer "In2.Cu")
		(net "P3V3")
	)
	(segment
		(start 191.262 -69.1134)
		(end 189.2681 -71.1073)
		(width 0.3048)
		(layer "In2.Cu")
		(net "P3V3")
	)
	(segment
		(start 47.6758 -24.0284)
		(end 48.514 -24.0284)
		(width 0.4572)
		(layer "In2.Cu")
		(net "P3V3")
	)
	(segment
		(start 125.200156 -65.683892)
		(end 123.545092 -65.683892)
		(width 0.3048)
		(layer "In2.Cu")
		(net "P3V3")
	)
	(segment
		(start 190.5 -65.832228)
		(end 192.151 -64.181228)
		(width 0.3048)
		(layer "In2.Cu")
		(net "P3V3")
	)
	(segment
		(start 68.927472 -12.319)
		(end 70.832472 -14.224)
		(width 0.3048)
		(layer "In2.Cu")
		(net "P3V3")
	)
	(segment
		(start 49.5046 -27.2542)
		(end 47.2948 -25.0444)
		(width 0.4572)
		(layer "In2.Cu")
		(net "P3V3")
	)
	(segment
		(start 122.57786 -64.71666)
		(end 107.39374 -64.71666)
		(width 0.3048)
		(layer "In2.Cu")
		(net "P3V3")
	)
	(segment
		(start 125.20295 -65.6844)
		(end 125.200156 -65.683892)
		(width 0.3048)
		(layer "In2.Cu")
		(net "P3V3")
	)
	(segment
		(start 172.974508 -44.195492)
		(end 172.974508 -46.609508)
		(width 0.3048)
		(layer "In2.Cu")
		(net "P3V3")
	)
	(segment
		(start 192.151 -63.881508)
		(end 182.9054 -54.635908)
		(width 0.3048)
		(layer "In2.Cu")
		(net "P3V3")
	)
	(segment
		(start 173.3804 -29.0322)
		(end 173.6344 -29.2862)
		(width 0.3048)
		(layer "In2.Cu")
		(net "P3V3")
	)
	(segment
		(start 173.6344 -43.5356)
		(end 172.974508 -44.195492)
		(width 0.3048)
		(layer "In2.Cu")
		(net "P3V3")
	)
	(segment
		(start 126.365 -67.945)
		(end 126.365 -66.527934)
		(width 0.3048)
		(layer "In2.Cu")
		(net "P3V3")
	)
	(segment
		(start 106.807 -65.3034)
		(end 106.807 -65.4812)
		(width 0.3048)
		(layer "In2.Cu")
		(net "P3V3")
	)
	(segment
		(start 173.9646 -47.5996)
		(end 174.4218 -47.5996)
		(width 0.3048)
		(layer "In2.Cu")
		(net "P3V3")
	)
	(segment
		(start 48.514 -24.0284)
		(end 48.641 -23.9014)
		(width 0.4572)
		(layer "In2.Cu")
		(net "P3V3")
	)
	(segment
		(start 129.5273 -71.1073)
		(end 126.365 -67.945)
		(width 0.3048)
		(layer "In2.Cu")
		(net "P3V3")
	)
	(segment
		(start 189.2681 -71.1073)
		(end 129.5273 -71.1073)
		(width 0.3048)
		(layer "In2.Cu")
		(net "P3V3")
	)
	(segment
		(start 107.39374 -64.71666)
		(end 106.807 -65.3034)
		(width 0.3048)
		(layer "In2.Cu")
		(net "P3V3")
	)
	(segment
		(start 31.597346 -36.506912)
		(end 31.597346 -33.66897)
		(width 0.3048)
		(layer "In4.Cu")
		(net "P3V3")
	)
	(segment
		(start 40.588692 -45.822616)
		(end 40.588692 -42.672)
		(width 0.508)
		(layer "In4.Cu")
		(net "P3V3")
	)
	(segment
		(start 68.9102 -42.1894)
		(end 69.6214 -41.4782)
		(width 0.508)
		(layer "In4.Cu")
		(net "P3V3")
	)
	(segment
		(start 48.1838 -21.1328)
		(end 45.6438 -21.1328)
		(width 0.254)
		(layer "In4.Cu")
		(net "P3V3")
	)
	(segment
		(start 49.1998 -22.1488)
		(end 48.1838 -21.1328)
		(width 0.254)
		(layer "In4.Cu")
		(net "P3V3")
	)
	(segment
		(start 51.3588 -22.733)
		(end 50.7746 -22.1488)
		(width 0.254)
		(layer "In4.Cu")
		(net "P3V3")
	)
	(segment
		(start 46.562264 -47.064168)
		(end 41.830244 -47.064168)
		(width 0.508)
		(layer "In4.Cu")
		(net "P3V3")
	)
	(segment
		(start 40.5765 -22.5425)
		(end 35.471608 -22.5425)
		(width 0.254)
		(layer "In4.Cu")
		(net "P3V3")
	)
	(segment
		(start 48.887634 -44.58335)
		(end 48.873918 -44.58335)
		(width 0.508)
		(layer "In4.Cu")
		(net "P3V3")
	)
	(segment
		(start 31.597346 -33.66897)
		(end 32.2834 -32.982916)
		(width 0.3048)
		(layer "In4.Cu")
		(net "P3V3")
	)
	(segment
		(start 48.873918 -44.58335)
		(end 47.8028 -45.654468)
		(width 0.508)
		(layer "In4.Cu")
		(net "P3V3")
	)
	(segment
		(start 45.6438 -21.1328)
		(end 45.3644 -21.4122)
		(width 0.254)
		(layer "In4.Cu")
		(net "P3V3")
	)
	(segment
		(start 28.194 -41.682162)
		(end 28.194 -39.910258)
		(width 0.3048)
		(layer "In4.Cu")
		(net "P3V3")
	)
	(segment
		(start 47.8028 -45.654468)
		(end 47.8028 -45.823632)
		(width 0.508)
		(layer "In4.Cu")
		(net "P3V3")
	)
	(segment
		(start 32.2834 -32.982916)
		(end 32.2834 -32.91332)
		(width 0.3048)
		(layer "In4.Cu")
		(net "P3V3")
	)
	(segment
		(start 45.3644 -21.4122)
		(end 41.7068 -21.4122)
		(width 0.254)
		(layer "In4.Cu")
		(net "P3V3")
	)
	(segment
		(start 27.11577 -46.355)
		(end 29.991558 -43.47972)
		(width 0.508)
		(layer "In4.Cu")
		(net "P3V3")
	)
	(segment
		(start 19.470878 -46.355)
		(end 27.11577 -46.355)
		(width 0.508)
		(layer "In4.Cu")
		(net "P3V3")
	)
	(segment
		(start 18.0086 -49.2252)
		(end 18.0086 -47.817278)
		(width 0.508)
		(layer "In4.Cu")
		(net "P3V3")
	)
	(segment
		(start 29.991558 -43.47972)
		(end 32.323278 -41.148)
		(width 0.508)
		(layer "In4.Cu")
		(net "P3V3")
	)
	(segment
		(start 41.830244 -47.064168)
		(end 40.588692 -45.822616)
		(width 0.508)
		(layer "In4.Cu")
		(net "P3V3")
	)
	(segment
		(start 35.471608 -22.5425)
		(end 35.179 -22.835108)
		(width 0.254)
		(layer "In4.Cu")
		(net "P3V3")
	)
	(segment
		(start 18.0086 -47.817278)
		(end 19.470878 -46.355)
		(width 0.508)
		(layer "In4.Cu")
		(net "P3V3")
	)
	(segment
		(start 50.292 -43.178984)
		(end 48.887634 -44.58335)
		(width 0.508)
		(layer "In4.Cu")
		(net "P3V3")
	)
	(segment
		(start 65.452498 -43.14698)
		(end 66.410078 -42.1894)
		(width 0.508)
		(layer "In4.Cu")
		(net "P3V3")
	)
	(segment
		(start 28.194 -39.910258)
		(end 31.597346 -36.506912)
		(width 0.3048)
		(layer "In4.Cu")
		(net "P3V3")
	)
	(segment
		(start 32.323278 -41.148)
		(end 37.341302 -41.148)
		(width 0.508)
		(layer "In4.Cu")
		(net "P3V3")
	)
	(segment
		(start 29.991558 -43.47972)
		(end 28.194 -41.682162)
		(width 0.3048)
		(layer "In4.Cu")
		(net "P3V3")
	)
	(segment
		(start 35.179 -22.835108)
		(end 34.663126 -22.835108)
		(width 0.254)
		(layer "In4.Cu")
		(net "P3V3")
	)
	(segment
		(start 50.292 -42.418)
		(end 50.292 -43.178984)
		(width 0.508)
		(layer "In4.Cu")
		(net "P3V3")
	)
	(segment
		(start 41.7068 -21.4122)
		(end 40.5765 -22.5425)
		(width 0.254)
		(layer "In4.Cu")
		(net "P3V3")
	)
	(segment
		(start 32.2834 -32.91332)
		(end 32.385 -32.81172)
		(width 0.3048)
		(layer "In4.Cu")
		(net "P3V3")
	)
	(segment
		(start 39.293546 -41.10228)
		(end 40.259 -41.10228)
		(width 0.508)
		(layer "In4.Cu")
		(net "P3V3")
	)
	(segment
		(start 40.259 -42.342308)
		(end 40.259 -41.10228)
		(width 0.508)
		(layer "In4.Cu")
		(net "P3V3")
	)
	(segment
		(start 38.817042 -41.578784)
		(end 39.293546 -41.10228)
		(width 0.508)
		(layer "In4.Cu")
		(net "P3V3")
	)
	(segment
		(start 37.341302 -41.148)
		(end 37.772086 -41.578784)
		(width 0.508)
		(layer "In4.Cu")
		(net "P3V3")
	)
	(segment
		(start 37.772086 -41.578784)
		(end 38.817042 -41.578784)
		(width 0.508)
		(layer "In4.Cu")
		(net "P3V3")
	)
	(segment
		(start 40.588692 -42.672)
		(end 40.259 -42.342308)
		(width 0.508)
		(layer "In4.Cu")
		(net "P3V3")
	)
	(segment
		(start 66.410078 -42.1894)
		(end 68.9102 -42.1894)
		(width 0.508)
		(layer "In4.Cu")
		(net "P3V3")
	)
	(segment
		(start 50.7746 -22.1488)
		(end 49.1998 -22.1488)
		(width 0.254)
		(layer "In4.Cu")
		(net "P3V3")
	)
	(segment
		(start 47.8028 -45.823632)
		(end 46.562264 -47.064168)
		(width 0.508)
		(layer "In4.Cu")
		(net "P3V3")
	)
	(segment
		(start 80.6958 -69.977)
		(end 80.3656 -70.3072)
		(width 0.3048)
		(layer "In7.Cu")
		(net "P3V3")
	)
	(segment
		(start 83.450684 -48.2219)
		(end 83.425284 -48.1965)
		(width 0.3048)
		(layer "In7.Cu")
		(net "P3V3")
	)
	(segment
		(start 55.372 -41.021)
		(end 55.88 -40.513)
		(width 0.508)
		(layer "In7.Cu")
		(net "P3V3")
	)
	(segment
		(start 88.665304 -49.612296)
		(end 87.259922 -49.612296)
		(width 0.3048)
		(layer "In7.Cu")
		(net "P3V3")
	)
	(segment
		(start 41.69664 -42.07764)
		(end 41.23436 -42.07764)
		(width 0.3048)
		(layer "In7.Cu")
		(net "P3V3")
	)
	(segment
		(start 45.974 -42.545)
		(end 42.164 -42.545)
		(width 0.3048)
		(layer "In7.Cu")
		(net "P3V3")
	)
	(segment
		(start 60.429648 -40.513)
		(end 62.112398 -42.19575)
		(width 0.508)
		(layer "In7.Cu")
		(net "P3V3")
	)
	(segment
		(start 83.82127 -71.7677)
		(end 82.5246 -70.47103)
		(width 0.3048)
		(layer "In7.Cu")
		(net "P3V3")
	)
	(segment
		(start 83.425284 -48.1965)
		(end 82.492342 -48.1965)
		(width 0.3048)
		(layer "In7.Cu")
		(net "P3V3")
	)
	(segment
		(start 41.23436 -42.07764)
		(end 40.259 -41.10228)
		(width 0.3048)
		(layer "In7.Cu")
		(net "P3V3")
	)
	(segment
		(start 87.259922 -49.612296)
		(end 86.949026 -49.3014)
		(width 0.3048)
		(layer "In7.Cu")
		(net "P3V3")
	)
	(segment
		(start 60.59043 -21.3487)
		(end 59.376056 -21.3487)
		(width 0.508)
		(layer "In7.Cu")
		(net "P3V3")
	)
	(segment
		(start 82.492342 -48.1965)
		(end 82.357722 -48.33112)
		(width 0.3048)
		(layer "In7.Cu")
		(net "P3V3")
	)
	(segment
		(start 65.693036 -24.3459)
		(end 65.693036 -24.341836)
		(width 0.508)
		(layer "In7.Cu")
		(net "P3V3")
	)
	(segment
		(start 58.448956 -20.4216)
		(end 56.34101 -20.4216)
		(width 0.508)
		(layer "In7.Cu")
		(net "P3V3")
	)
	(segment
		(start 82.5246 -70.304152)
		(end 82.197448 -69.977)
		(width 0.3048)
		(layer "In7.Cu")
		(net "P3V3")
	)
	(segment
		(start 64.501268 -42.19575)
		(end 65.452498 -43.14698)
		(width 0.508)
		(layer "In7.Cu")
		(net "P3V3")
	)
	(segment
		(start 62.74308 -23.50135)
		(end 60.59043 -21.3487)
		(width 0.508)
		(layer "In7.Cu")
		(net "P3V3")
	)
	(segment
		(start 55.88 -40.513)
		(end 60.429648 -40.513)
		(width 0.508)
		(layer "In7.Cu")
		(net "P3V3")
	)
	(segment
		(start 88.7984 -49.4792)
		(end 88.665304 -49.612296)
		(width 0.3048)
		(layer "In7.Cu")
		(net "P3V3")
	)
	(segment
		(start 56.34101 -20.4216)
		(end 54.930294 -19.010884)
		(width 0.508)
		(layer "In7.Cu")
		(net "P3V3")
	)
	(segment
		(start 108.9787 -71.7677)
		(end 83.82127 -71.7677)
		(width 0.3048)
		(layer "In7.Cu")
		(net "P3V3")
	)
	(segment
		(start 82.357722 -48.33112)
		(end 78.308962 -48.33112)
		(width 0.3048)
		(layer "In7.Cu")
		(net "P3V3")
	)
	(segment
		(start 64.85255 -23.50135)
		(end 62.74308 -23.50135)
		(width 0.508)
		(layer "In7.Cu")
		(net "P3V3")
	)
	(segment
		(start 84.61502 -49.3014)
		(end 83.53552 -48.2219)
		(width 0.3048)
		(layer "In7.Cu")
		(net "P3V3")
	)
	(segment
		(start 62.112398 -42.19575)
		(end 64.501268 -42.19575)
		(width 0.508)
		(layer "In7.Cu")
		(net "P3V3")
	)
	(segment
		(start 54.0004 -41.021)
		(end 55.372 -41.021)
		(width 0.508)
		(layer "In7.Cu")
		(net "P3V3")
	)
	(segment
		(start 82.5246 -70.47103)
		(end 82.5246 -70.304152)
		(width 0.3048)
		(layer "In7.Cu")
		(net "P3V3")
	)
	(segment
		(start 59.376056 -21.3487)
		(end 58.448956 -20.4216)
		(width 0.508)
		(layer "In7.Cu")
		(net "P3V3")
	)
	(segment
		(start 110.8964 -69.85)
		(end 108.9787 -71.7677)
		(width 0.3048)
		(layer "In7.Cu")
		(net "P3V3")
	)
	(segment
		(start 77.089 -49.551082)
		(end 77.089 -49.6316)
		(width 0.3048)
		(layer "In7.Cu")
		(net "P3V3")
	)
	(segment
		(start 83.53552 -48.2219)
		(end 83.450684 -48.2219)
		(width 0.3048)
		(layer "In7.Cu")
		(net "P3V3")
	)
	(segment
		(start 65.693036 -24.341836)
		(end 64.85255 -23.50135)
		(width 0.508)
		(layer "In7.Cu")
		(net "P3V3")
	)
	(segment
		(start 86.949026 -49.3014)
		(end 84.61502 -49.3014)
		(width 0.3048)
		(layer "In7.Cu")
		(net "P3V3")
	)
	(segment
		(start 82.197448 -69.977)
		(end 80.6958 -69.977)
		(width 0.3048)
		(layer "In7.Cu")
		(net "P3V3")
	)
	(segment
		(start 78.308962 -48.33112)
		(end 77.089 -49.551082)
		(width 0.3048)
		(layer "In7.Cu")
		(net "P3V3")
	)
	(segment
		(start 42.164 -42.545)
		(end 41.69664 -42.07764)
		(width 0.3048)
		(layer "In7.Cu")
		(net "P3V3")
	)
	(segment
		(start 89.2048 -48.730662)
		(end 89.891616 -48.0441)
		(width 0.3048)
		(layer "In9.Cu")
		(net "P3V3")
	)
	(segment
		(start 91.1225 -42.8117)
		(end 90.548968 -42.238168)
		(width 0.3048)
		(layer "In9.Cu")
		(net "P3V3")
	)
	(segment
		(start 89.143586 -48.791876)
		(end 89.2048 -48.730662)
		(width 0.3048)
		(layer "In9.Cu")
		(net "P3V3")
	)
	(segment
		(start 70.6882 -44.0182)
		(end 70.6882 -46.260512)
		(width 0.3048)
		(layer "In9.Cu")
		(net "P3V3")
	)
	(segment
		(start 59.2582 -13.1318)
		(end 60.806076 -13.1318)
		(width 0.3048)
		(layer "In9.Cu")
		(net "P3V3")
	)
	(segment
		(start 59.6392 -16.1036)
		(end 58.6232 -15.0876)
		(width 0.3048)
		(layer "In9.Cu")
		(net "P3V3")
	)
	(segment
		(start 89.143586 -49.134014)
		(end 89.143586 -48.791876)
		(width 0.3048)
		(layer "In9.Cu")
		(net "P3V3")
	)
	(segment
		(start 33.22828 -33.655)
		(end 32.385 -32.81172)
		(width 0.3048)
		(layer "In9.Cu")
		(net "P3V3")
	)
	(segment
		(start 70.6882 -46.260512)
		(end 72.7202 -48.292512)
		(width 0.3048)
		(layer "In9.Cu")
		(net "P3V3")
	)
	(segment
		(start 58.6232 -15.0876)
		(end 58.6232 -13.7668)
		(width 0.3048)
		(layer "In9.Cu")
		(net "P3V3")
	)
	(segment
		(start 34.74847 -33.655)
		(end 33.22828 -33.655)
		(width 0.3048)
		(layer "In9.Cu")
		(net "P3V3")
	)
	(segment
		(start 72.7202 -48.292512)
		(end 72.7202 -48.73879)
		(width 0.3048)
		(layer "In9.Cu")
		(net "P3V3")
	)
	(segment
		(start 59.7916 -16.1036)
		(end 59.6392 -16.1036)
		(width 0.3048)
		(layer "In9.Cu")
		(net "P3V3")
	)
	(segment
		(start 60.806076 -13.1318)
		(end 63.498476 -10.4394)
		(width 0.3048)
		(layer "In9.Cu")
		(net "P3V3")
	)
	(segment
		(start 88.7984 -49.4792)
		(end 89.143586 -49.134014)
		(width 0.3048)
		(layer "In9.Cu")
		(net "P3V3")
	)
	(segment
		(start 90.548968 -40.96639)
		(end 91.053158 -40.4622)
		(width 0.3048)
		(layer "In9.Cu")
		(net "P3V3")
	)
	(segment
		(start 63.498476 -10.4394)
		(end 64.6684 -10.4394)
		(width 0.3048)
		(layer "In9.Cu")
		(net "P3V3")
	)
	(segment
		(start 90.548968 -42.238168)
		(end 90.548968 -40.96639)
		(width 0.3048)
		(layer "In9.Cu")
		(net "P3V3")
	)
	(segment
		(start 58.6232 -13.7668)
		(end 59.2582 -13.1318)
		(width 0.3048)
		(layer "In9.Cu")
		(net "P3V3")
	)
	(segment
		(start 36.2966 -35.20313)
		(end 34.74847 -33.655)
		(width 0.3048)
		(layer "In9.Cu")
		(net "P3V3")
	)
	(segment
		(start 89.891616 -48.0441)
		(end 90.542618 -48.0441)
		(width 0.3048)
		(layer "In9.Cu")
		(net "P3V3")
	)
	(segment
		(start 91.1225 -47.464218)
		(end 91.1225 -42.8117)
		(width 0.3048)
		(layer "In9.Cu")
		(net "P3V3")
	)
	(segment
		(start 90.542618 -48.0441)
		(end 91.1225 -47.464218)
		(width 0.3048)
		(layer "In9.Cu")
		(net "P3V3")
	)
	(segment
		(start 95.796608 -52.046124)
		(end 95.796608 -51.503834)
		(width 0.1016)
		(layer "F.Cu")
		(net "M_A_DQS_DN7")
	)
	(segment
		(start 96.046036 -52.295552)
		(end 95.796608 -52.046124)
		(width 0.1016)
		(layer "F.Cu")
		(net "M_A_DQS_DN7")
	)
	(segment
		(start 96.046036 -53.415692)
		(end 96.046036 -52.295552)
		(width 0.1016)
		(layer "F.Cu")
		(net "M_A_DQS_DN7")
	)
	(segment
		(start 132.25018 -62.59322)
		(end 132.25018 -63.361824)
		(width 0.1778)
		(layer "F.Cu")
		(net "M_A_DQS_DN7")
	)
	(segment
		(start 132.102606 -66.407538)
		(end 132.367274 -66.672206)
		(width 0.1778)
		(layer "F.Cu")
		(net "M_A_DQS_DN7")
	)
	(segment
		(start 95.9866 -54.5084)
		(end 95.9866 -53.475128)
		(width 0.1016)
		(layer "F.Cu")
		(net "M_A_DQS_DN7")
	)
	(segment
		(start 95.9866 -53.475128)
		(end 96.046036 -53.415692)
		(width 0.1016)
		(layer "F.Cu")
		(net "M_A_DQS_DN7")
	)
	(segment
		(start 132.25018 -63.361824)
		(end 132.102606 -63.509398)
		(width 0.1778)
		(layer "F.Cu")
		(net "M_A_DQS_DN7")
	)
	(segment
		(start 95.5802 -54.9148)
		(end 95.9866 -54.5084)
		(width 0.1016)
		(layer "F.Cu")
		(net "M_A_DQS_DN7")
	)
	(segment
		(start 132.102606 -63.509398)
		(end 132.102606 -66.407538)
		(width 0.1778)
		(layer "F.Cu")
		(net "M_A_DQS_DN7")
	)
	(via
		(at 95.5802 -54.9148)
		(size 0.4318)
		(drill 0.2032)
		(layers "F.Cu" "B.Cu")
		(net "M_A_DQS_DN7")
	)
	(via
		(at 132.367274 -66.672206)
		(size 0.4318)
		(drill 0.2032)
		(layers "F.Cu" "B.Cu")
		(net "M_A_DQS_DN7")
	)
	(segment
		(start 132.25018 -70.79996)
		(end 132.25018 -70.033388)
		(width 0.1778)
		(layer "B.Cu")
		(net "M_A_DQS_DN7")
	)
	(segment
		(start 132.102606 -69.885814)
		(end 132.102606 -66.936874)
		(width 0.1778)
		(layer "B.Cu")
		(net "M_A_DQS_DN7")
	)
	(segment
		(start 132.25018 -70.033388)
		(end 132.102606 -69.885814)
		(width 0.1778)
		(layer "B.Cu")
		(net "M_A_DQS_DN7")
	)
	(segment
		(start 132.102606 -66.936874)
		(end 132.367274 -66.672206)
		(width 0.1778)
		(layer "B.Cu")
		(net "M_A_DQS_DN7")
	)
	(segment
		(start 124.239274 -65.484502)
		(end 124.674376 -65.0494)
		(width 0.1524)
		(layer "In7.Cu")
		(net "M_A_DQS_DN7")
	)
	(segment
		(start 95.4278 -58.481976)
		(end 96.694752 -59.748928)
		(width 0.1524)
		(layer "In7.Cu")
		(net "M_A_DQS_DN7")
	)
	(segment
		(start 128.484376 -63.3476)
		(end 131.662424 -63.3476)
		(width 0.1524)
		(layer "In7.Cu")
		(net "M_A_DQS_DN7")
	)
	(segment
		(start 132.08 -66.1162)
		(end 132.08 -66.384932)
		(width 0.1524)
		(layer "In7.Cu")
		(net "M_A_DQS_DN7")
	)
	(segment
		(start 95.5802 -54.9148)
		(end 95.4278 -55.0672)
		(width 0.1524)
		(layer "In7.Cu")
		(net "M_A_DQS_DN7")
	)
	(segment
		(start 95.4278 -55.0672)
		(end 95.4278 -58.481976)
		(width 0.1524)
		(layer "In7.Cu")
		(net "M_A_DQS_DN7")
	)
	(segment
		(start 125.617224 -65.0494)
		(end 126.353824 -65.786)
		(width 0.1524)
		(layer "In7.Cu")
		(net "M_A_DQS_DN7")
	)
	(segment
		(start 116.419376 -66.0146)
		(end 116.949474 -65.484502)
		(width 0.1524)
		(layer "In7.Cu")
		(net "M_A_DQS_DN7")
	)
	(segment
		(start 132.461 -65.7352)
		(end 132.08 -66.1162)
		(width 0.1524)
		(layer "In7.Cu")
		(net "M_A_DQS_DN7")
	)
	(segment
		(start 116.949474 -65.484502)
		(end 124.239274 -65.484502)
		(width 0.1524)
		(layer "In7.Cu")
		(net "M_A_DQS_DN7")
	)
	(segment
		(start 124.674376 -65.0494)
		(end 125.617224 -65.0494)
		(width 0.1524)
		(layer "In7.Cu")
		(net "M_A_DQS_DN7")
	)
	(segment
		(start 132.461 -65.2018)
		(end 132.461 -65.7352)
		(width 0.1524)
		(layer "In7.Cu")
		(net "M_A_DQS_DN7")
	)
	(segment
		(start 126.757176 -65.786)
		(end 128.0668 -64.476376)
		(width 0.1524)
		(layer "In7.Cu")
		(net "M_A_DQS_DN7")
	)
	(segment
		(start 128.0668 -64.476376)
		(end 128.0668 -63.765176)
		(width 0.1524)
		(layer "In7.Cu")
		(net "M_A_DQS_DN7")
	)
	(segment
		(start 100.885752 -66.0146)
		(end 116.419376 -66.0146)
		(width 0.1524)
		(layer "In7.Cu")
		(net "M_A_DQS_DN7")
	)
	(segment
		(start 132.08 -64.8208)
		(end 132.461 -65.2018)
		(width 0.1524)
		(layer "In7.Cu")
		(net "M_A_DQS_DN7")
	)
	(segment
		(start 132.08 -66.384932)
		(end 132.367274 -66.672206)
		(width 0.1524)
		(layer "In7.Cu")
		(net "M_A_DQS_DN7")
	)
	(segment
		(start 131.662424 -63.3476)
		(end 132.08 -63.765176)
		(width 0.1524)
		(layer "In7.Cu")
		(net "M_A_DQS_DN7")
	)
	(segment
		(start 96.694752 -59.748928)
		(end 96.694752 -61.8236)
		(width 0.1524)
		(layer "In7.Cu")
		(net "M_A_DQS_DN7")
	)
	(segment
		(start 132.08 -63.765176)
		(end 132.08 -64.8208)
		(width 0.1524)
		(layer "In7.Cu")
		(net "M_A_DQS_DN7")
	)
	(segment
		(start 96.694752 -61.8236)
		(end 100.885752 -66.0146)
		(width 0.1524)
		(layer "In7.Cu")
		(net "M_A_DQS_DN7")
	)
	(segment
		(start 128.0668 -63.765176)
		(end 128.484376 -63.3476)
		(width 0.1524)
		(layer "In7.Cu")
		(net "M_A_DQS_DN7")
	)
	(segment
		(start 126.353824 -65.786)
		(end 126.757176 -65.786)
		(width 0.1524)
		(layer "In7.Cu")
		(net "M_A_DQS_DN7")
	)
	(segment
		(start 47.498 -53.213)
		(end 47.498 -52.8193)
		(width 0.381)
		(layer "F.Cu")
		(net "P1V5_CLK_VDD_CORE")
	)
	(segment
		(start 47.498 -52.8193)
		(end 47.8536 -52.4637)
		(width 0.381)
		(layer "F.Cu")
		(net "P1V5_CLK_VDD_CORE")
	)
	(segment
		(start 48.425354 -53.3781)
		(end 48.425354 -53.035454)
		(width 0.381)
		(layer "F.Cu")
		(net "P1V5_CLK_VDD_CORE")
	)
	(segment
		(start 48.425354 -53.035454)
		(end 47.8536 -52.4637)
		(width 0.381)
		(layer "F.Cu")
		(net "P1V5_CLK_VDD_CORE")
	)
	(via
		(at 47.3202 -43.7896)
		(size 0.508)
		(drill 0.254)
		(layers "F.Cu" "B.Cu")
		(net "P1V5_CLK_VDD_CORE")
	)
	(via
		(at 47.498 -53.213)
		(size 0.508)
		(drill 0.254)
		(layers "F.Cu" "B.Cu")
		(net "P1V5_CLK_VDD_CORE")
	)
	(via
		(at 47.4218 -44.577)
		(size 0.7112)
		(drill 0.3556)
		(layers "F.Cu" "B.Cu")
		(net "P1V5_CLK_VDD_CORE")
	)
	(segment
		(start 47.4218 -44.577)
		(end 47.4218 -43.8912)
		(width 0.2032)
		(layer "B.Cu")
		(net "P1V5_CLK_VDD_CORE")
	)
	(segment
		(start 47.3202 -43.7896)
		(end 47.3202 -43.1546)
		(width 0.3048)
		(layer "B.Cu")
		(net "P1V5_CLK_VDD_CORE")
	)
	(segment
		(start 46.858682 -46.087792)
		(end 46.858682 -45.470318)
		(width 0.2032)
		(layer "B.Cu")
		(net "P1V5_CLK_VDD_CORE")
	)
	(segment
		(start 46.858682 -45.470318)
		(end 47.4218 -44.9072)
		(width 0.2032)
		(layer "B.Cu")
		(net "P1V5_CLK_VDD_CORE")
	)
	(segment
		(start 47.3202 -43.1546)
		(end 46.99 -42.8244)
		(width 0.3048)
		(layer "B.Cu")
		(net "P1V5_CLK_VDD_CORE")
	)
	(segment
		(start 47.4218 -44.9072)
		(end 47.4218 -44.577)
		(width 0.2032)
		(layer "B.Cu")
		(net "P1V5_CLK_VDD_CORE")
	)
	(segment
		(start 47.4218 -43.8912)
		(end 47.3202 -43.7896)
		(width 0.2032)
		(layer "B.Cu")
		(net "P1V5_CLK_VDD_CORE")
	)
	(segment
		(start 47.498 -52.933092)
		(end 47.498 -53.213)
		(width 0.2032)
		(layer "B.Cu")
		(net "P1V5_CLK_VDD_CORE")
	)
	(segment
		(start 46.858682 -52.293774)
		(end 47.498 -52.933092)
		(width 0.2032)
		(layer "B.Cu")
		(net "P1V5_CLK_VDD_CORE")
	)
	(segment
		(start 46.858682 -51.70678)
		(end 46.858682 -52.293774)
		(width 0.2032)
		(layer "B.Cu")
		(net "P1V5_CLK_VDD_CORE")
	)
	(segment
		(start 47.3202 -45.231812)
		(end 43.928284 -48.623728)
		(width 0.508)
		(layer "In9.Cu")
		(net "P1V5_CLK_VDD_CORE")
	)
	(segment
		(start 43.928284 -48.623728)
		(end 43.928284 -49.643284)
		(width 0.508)
		(layer "In9.Cu")
		(net "P1V5_CLK_VDD_CORE")
	)
	(segment
		(start 47.3202 -43.7896)
		(end 47.3202 -45.231812)
		(width 0.508)
		(layer "In9.Cu")
		(net "P1V5_CLK_VDD_CORE")
	)
	(segment
		(start 43.928284 -49.643284)
		(end 47.498 -53.213)
		(width 0.508)
		(layer "In9.Cu")
		(net "P1V5_CLK_VDD_CORE")
	)
	(segment
		(start 158.34995 -70.806564)
		(end 158.34995 -67.49161)
		(width 0.2413)
		(layer "F.Cu")
		(net "M_A_MA5")
	)
	(segment
		(start 158.34995 -67.49161)
		(end 158.216346 -67.358006)
		(width 0.2413)
		(layer "F.Cu")
		(net "M_A_MA5")
	)
	(segment
		(start 108.704634 -51.5112)
		(end 108.712 -51.503834)
		(width 0.1016)
		(layer "F.Cu")
		(net "M_A_MA5")
	)
	(segment
		(start 108.6866 -51.5112)
		(end 108.704634 -51.5112)
		(width 0.1016)
		(layer "F.Cu")
		(net "M_A_MA5")
	)
	(segment
		(start 108.712 -51.503834)
		(end 109.256068 -51.503834)
		(width 0.1016)
		(layer "F.Cu")
		(net "M_A_MA5")
	)
	(via
		(at 158.216346 -67.358006)
		(size 0.4318)
		(drill 0.2032)
		(layers "F.Cu" "B.Cu")
		(net "M_A_MA5")
	)
	(via
		(at 108.6866 -51.5112)
		(size 0.4318)
		(drill 0.2032)
		(layers "F.Cu" "B.Cu")
		(net "M_A_MA5")
	)
	(segment
		(start 158.700978 -65.143126)
		(end 158.700978 -66.60134)
		(width 0.2413)
		(layer "B.Cu")
		(net "M_A_MA5")
	)
	(segment
		(start 158.34995 -62.599824)
		(end 158.34995 -64.792098)
		(width 0.2413)
		(layer "B.Cu")
		(net "M_A_MA5")
	)
	(segment
		(start 158.700978 -66.60134)
		(end 158.70047 -66.601848)
		(width 0.2413)
		(layer "B.Cu")
		(net "M_A_MA5")
	)
	(segment
		(start 158.70047 -66.920364)
		(end 158.262828 -67.358006)
		(width 0.2413)
		(layer "B.Cu")
		(net "M_A_MA5")
	)
	(segment
		(start 158.262828 -67.358006)
		(end 158.216346 -67.358006)
		(width 0.2413)
		(layer "B.Cu")
		(net "M_A_MA5")
	)
	(segment
		(start 158.34995 -64.792098)
		(end 158.700978 -65.143126)
		(width 0.2413)
		(layer "B.Cu")
		(net "M_A_MA5")
	)
	(segment
		(start 158.70047 -66.601848)
		(end 158.70047 -66.920364)
		(width 0.2413)
		(layer "B.Cu")
		(net "M_A_MA5")
	)
	(segment
		(start 146.32305 -52.6669)
		(end 144.07134 -52.6669)
		(width 0.1905)
		(layer "In9.Cu")
		(net "M_A_MA5")
	)
	(segment
		(start 135.861552 -52.691792)
		(end 135.671052 -52.501292)
		(width 0.1905)
		(layer "In9.Cu")
		(net "M_A_MA5")
	)
	(segment
		(start 157.773878 -66.24955)
		(end 157.773878 -65.673478)
		(width 0.1905)
		(layer "In9.Cu")
		(net "M_A_MA5")
	)
	(segment
		(start 153.85415 -58.64987)
		(end 153.85415 -57.963054)
		(width 0.1905)
		(layer "In9.Cu")
		(net "M_A_MA5")
	)
	(segment
		(start 136.433052 -52.501292)
		(end 136.242552 -52.691792)
		(width 0.1905)
		(layer "In9.Cu")
		(net "M_A_MA5")
	)
	(segment
		(start 153.85415 -57.963054)
		(end 153.046176 -57.15508)
		(width 0.1905)
		(layer "In9.Cu")
		(net "M_A_MA5")
	)
	(segment
		(start 136.623552 -52.13985)
		(end 136.433052 -52.33035)
		(width 0.1905)
		(layer "In9.Cu")
		(net "M_A_MA5")
	)
	(segment
		(start 148.825712 -53.208936)
		(end 146.865086 -53.208936)
		(width 0.1905)
		(layer "In9.Cu")
		(net "M_A_MA5")
	)
	(segment
		(start 157.4546 -65.3542)
		(end 157.4546 -62.717172)
		(width 0.1905)
		(layer "In9.Cu")
		(net "M_A_MA5")
	)
	(segment
		(start 152.771856 -57.15508)
		(end 148.825712 -53.208936)
		(width 0.1905)
		(layer "In9.Cu")
		(net "M_A_MA5")
	)
	(segment
		(start 157.77337 -66.90995)
		(end 157.77337 -66.250058)
		(width 0.1905)
		(layer "In9.Cu")
		(net "M_A_MA5")
	)
	(segment
		(start 118.09095 -52.13985)
		(end 117.5004 -52.7304)
		(width 0.1905)
		(layer "In9.Cu")
		(net "M_A_MA5")
	)
	(segment
		(start 134.909052 -52.33035)
		(end 134.909052 -52.501292)
		(width 0.1905)
		(layer "In9.Cu")
		(net "M_A_MA5")
	)
	(segment
		(start 134.147052 -52.33035)
		(end 133.956552 -52.13985)
		(width 0.1905)
		(layer "In9.Cu")
		(net "M_A_MA5")
	)
	(segment
		(start 146.865086 -53.208936)
		(end 146.32305 -52.6669)
		(width 0.1905)
		(layer "In9.Cu")
		(net "M_A_MA5")
	)
	(segment
		(start 154.636724 -59.899296)
		(end 154.636724 -59.432444)
		(width 0.1905)
		(layer "In9.Cu")
		(net "M_A_MA5")
	)
	(segment
		(start 135.671052 -52.33035)
		(end 135.480552 -52.13985)
		(width 0.1905)
		(layer "In9.Cu")
		(net "M_A_MA5")
	)
	(segment
		(start 137.195052 -52.501292)
		(end 137.195052 -52.33035)
		(width 0.1905)
		(layer "In9.Cu")
		(net "M_A_MA5")
	)
	(segment
		(start 143.54429 -52.13985)
		(end 138.147552 -52.13985)
		(width 0.1905)
		(layer "In9.Cu")
		(net "M_A_MA5")
	)
	(segment
		(start 117.5004 -52.7304)
		(end 112.0648 -52.7304)
		(width 0.1905)
		(layer "In9.Cu")
		(net "M_A_MA5")
	)
	(segment
		(start 138.147552 -52.13985)
		(end 137.957052 -52.33035)
		(width 0.1905)
		(layer "In9.Cu")
		(net "M_A_MA5")
	)
	(segment
		(start 135.480552 -52.13985)
		(end 135.099552 -52.13985)
		(width 0.1905)
		(layer "In9.Cu")
		(net "M_A_MA5")
	)
	(segment
		(start 137.957052 -52.501292)
		(end 137.766552 -52.691792)
		(width 0.1905)
		(layer "In9.Cu")
		(net "M_A_MA5")
	)
	(segment
		(start 137.004552 -52.13985)
		(end 136.623552 -52.13985)
		(width 0.1905)
		(layer "In9.Cu")
		(net "M_A_MA5")
	)
	(segment
		(start 158.216346 -67.352926)
		(end 157.77337 -66.90995)
		(width 0.1905)
		(layer "In9.Cu")
		(net "M_A_MA5")
	)
	(segment
		(start 137.195052 -52.33035)
		(end 137.004552 -52.13985)
		(width 0.1905)
		(layer "In9.Cu")
		(net "M_A_MA5")
	)
	(segment
		(start 153.046176 -57.15508)
		(end 152.771856 -57.15508)
		(width 0.1905)
		(layer "In9.Cu")
		(net "M_A_MA5")
	)
	(segment
		(start 136.242552 -52.691792)
		(end 135.861552 -52.691792)
		(width 0.1905)
		(layer "In9.Cu")
		(net "M_A_MA5")
	)
	(segment
		(start 112.0648 -52.7304)
		(end 111.8616 -52.5272)
		(width 0.1905)
		(layer "In9.Cu")
		(net "M_A_MA5")
	)
	(segment
		(start 134.909052 -52.501292)
		(end 134.718552 -52.691792)
		(width 0.1905)
		(layer "In9.Cu")
		(net "M_A_MA5")
	)
	(segment
		(start 154.636724 -59.432444)
		(end 153.85415 -58.64987)
		(width 0.1905)
		(layer "In9.Cu")
		(net "M_A_MA5")
	)
	(segment
		(start 137.766552 -52.691792)
		(end 137.385552 -52.691792)
		(width 0.1905)
		(layer "In9.Cu")
		(net "M_A_MA5")
	)
	(segment
		(start 158.216346 -67.358006)
		(end 158.216346 -67.352926)
		(width 0.1905)
		(layer "In9.Cu")
		(net "M_A_MA5")
	)
	(segment
		(start 136.433052 -52.33035)
		(end 136.433052 -52.501292)
		(width 0.1905)
		(layer "In9.Cu")
		(net "M_A_MA5")
	)
	(segment
		(start 134.718552 -52.691792)
		(end 134.337552 -52.691792)
		(width 0.1905)
		(layer "In9.Cu")
		(net "M_A_MA5")
	)
	(segment
		(start 157.4546 -62.717172)
		(end 154.636724 -59.899296)
		(width 0.1905)
		(layer "In9.Cu")
		(net "M_A_MA5")
	)
	(segment
		(start 108.9152 -51.5112)
		(end 109.9312 -52.5272)
		(width 0.1016)
		(layer "In9.Cu")
		(net "M_A_MA5")
	)
	(segment
		(start 134.337552 -52.691792)
		(end 134.147052 -52.501292)
		(width 0.1905)
		(layer "In9.Cu")
		(net "M_A_MA5")
	)
	(segment
		(start 108.6866 -51.5112)
		(end 108.9152 -51.5112)
		(width 0.1016)
		(layer "In9.Cu")
		(net "M_A_MA5")
	)
	(segment
		(start 109.9312 -52.5272)
		(end 111.8616 -52.5272)
		(width 0.1016)
		(layer "In9.Cu")
		(net "M_A_MA5")
	)
	(segment
		(start 135.099552 -52.13985)
		(end 134.909052 -52.33035)
		(width 0.1905)
		(layer "In9.Cu")
		(net "M_A_MA5")
	)
	(segment
		(start 135.671052 -52.501292)
		(end 135.671052 -52.33035)
		(width 0.1905)
		(layer "In9.Cu")
		(net "M_A_MA5")
	)
	(segment
		(start 157.773878 -65.673478)
		(end 157.4546 -65.3542)
		(width 0.1905)
		(layer "In9.Cu")
		(net "M_A_MA5")
	)
	(segment
		(start 133.956552 -52.13985)
		(end 118.09095 -52.13985)
		(width 0.1905)
		(layer "In9.Cu")
		(net "M_A_MA5")
	)
	(segment
		(start 137.957052 -52.33035)
		(end 137.957052 -52.501292)
		(width 0.1905)
		(layer "In9.Cu")
		(net "M_A_MA5")
	)
	(segment
		(start 134.147052 -52.501292)
		(end 134.147052 -52.33035)
		(width 0.1905)
		(layer "In9.Cu")
		(net "M_A_MA5")
	)
	(segment
		(start 157.77337 -66.250058)
		(end 157.773878 -66.24955)
		(width 0.1905)
		(layer "In9.Cu")
		(net "M_A_MA5")
	)
	(segment
		(start 137.385552 -52.691792)
		(end 137.195052 -52.501292)
		(width 0.1905)
		(layer "In9.Cu")
		(net "M_A_MA5")
	)
	(segment
		(start 144.07134 -52.6669)
		(end 143.54429 -52.13985)
		(width 0.1905)
		(layer "In9.Cu")
		(net "M_A_MA5")
	)
	(via
		(at 41.121838 -50.256186)
		(size 0.7112)
		(drill 0.3556)
		(layers "F.Cu" "B.Cu")
		(net "SMB_CLKGEN_R_CLK")
	)
	(segment
		(start 39.4208 -50.3682)
		(end 41.009824 -50.3682)
		(width 0.1143)
		(layer "B.Cu")
		(net "SMB_CLKGEN_R_CLK")
	)
	(segment
		(start 41.7068 -49.671224)
		(end 41.121838 -50.256186)
		(width 0.1143)
		(layer "B.Cu")
		(net "SMB_CLKGEN_R_CLK")
	)
	(segment
		(start 41.7068 -49.3268)
		(end 41.7068 -49.671224)
		(width 0.1143)
		(layer "B.Cu")
		(net "SMB_CLKGEN_R_CLK")
	)
	(segment
		(start 41.009824 -50.3682)
		(end 41.121838 -50.256186)
		(width 0.1143)
		(layer "B.Cu")
		(net "SMB_CLKGEN_R_CLK")
	)
	(segment
		(start 42.336212 -48.697388)
		(end 41.7068 -49.3268)
		(width 0.1143)
		(layer "B.Cu")
		(net "SMB_CLKGEN_R_CLK")
	)
	(segment
		(start 43.04919 -48.697388)
		(end 42.336212 -48.697388)
		(width 0.1143)
		(layer "B.Cu")
		(net "SMB_CLKGEN_R_CLK")
	)
	(segment
		(start 96.9772 -46.5582)
		(end 97.0026 -46.5582)
		(width 0.1016)
		(layer "F.Cu")
		(net "M_A_DQ33")
	)
	(segment
		(start 147.25015 -63.58128)
		(end 147.447 -63.77813)
		(width 0.1778)
		(layer "F.Cu")
		(net "M_A_DQ33")
	)
	(segment
		(start 147.447 -63.77813)
		(end 147.447 -64.40297)
		(width 0.1778)
		(layer "F.Cu")
		(net "M_A_DQ33")
	)
	(segment
		(start 97.366328 -46.194472)
		(end 97.366328 -46.116494)
		(width 0.1016)
		(layer "F.Cu")
		(net "M_A_DQ33")
	)
	(segment
		(start 97.0026 -46.5582)
		(end 97.366328 -46.194472)
		(width 0.1016)
		(layer "F.Cu")
		(net "M_A_DQ33")
	)
	(segment
		(start 147.447 -64.40297)
		(end 147.11807 -64.7319)
		(width 0.1778)
		(layer "F.Cu")
		(net "M_A_DQ33")
	)
	(segment
		(start 147.25015 -62.59322)
		(end 147.25015 -63.58128)
		(width 0.1778)
		(layer "F.Cu")
		(net "M_A_DQ33")
	)
	(via
		(at 147.11807 -64.7319)
		(size 0.4318)
		(drill 0.2032)
		(layers "F.Cu" "B.Cu")
		(net "M_A_DQ33")
	)
	(via
		(at 96.9772 -46.5582)
		(size 0.4318)
		(drill 0.2032)
		(layers "F.Cu" "B.Cu")
		(net "M_A_DQ33")
	)
	(segment
		(start 147.447 -63.881254)
		(end 147.447 -64.40297)
		(width 0.1778)
		(layer "B.Cu")
		(net "M_A_DQ33")
	)
	(segment
		(start 147.447 -64.40297)
		(end 147.11807 -64.7319)
		(width 0.1778)
		(layer "B.Cu")
		(net "M_A_DQ33")
	)
	(segment
		(start 147.550124 -62.599824)
		(end 147.550124 -63.77813)
		(width 0.1778)
		(layer "B.Cu")
		(net "M_A_DQ33")
	)
	(segment
		(start 147.550124 -63.77813)
		(end 147.447 -63.881254)
		(width 0.1778)
		(layer "B.Cu")
		(net "M_A_DQ33")
	)
	(segment
		(start 145.346166 -59.34202)
		(end 145.047716 -59.640216)
		(width 0.1524)
		(layer "In4.Cu")
		(net "M_A_DQ33")
	)
	(segment
		(start 147.2565 -61.9125)
		(end 146.6215 -61.9125)
		(width 0.1524)
		(layer "In4.Cu")
		(net "M_A_DQ33")
	)
	(segment
		(start 143.96974 -58.777632)
		(end 143.75384 -58.561732)
		(width 0.1524)
		(layer "In4.Cu")
		(net "M_A_DQ33")
	)
	(segment
		(start 144.05229 -58.048144)
		(end 144.05229 -57.832752)
		(width 0.1524)
		(layer "In4.Cu")
		(net "M_A_DQ33")
	)
	(segment
		(start 145.777458 -59.55792)
		(end 145.561558 -59.34202)
		(width 0.1524)
		(layer "In4.Cu")
		(net "M_A_DQ33")
	)
	(segment
		(start 105.6132 -53.1622)
		(end 104.0003 -51.5493)
		(width 0.1524)
		(layer "In4.Cu")
		(net "M_A_DQ33")
	)
	(segment
		(start 135.2296 -55.2704)
		(end 134.447788 -55.2704)
		(width 0.1524)
		(layer "In4.Cu")
		(net "M_A_DQ33")
	)
	(segment
		(start 109.6518 -55.8292)
		(end 109.2708 -55.4482)
		(width 0.1524)
		(layer "In4.Cu")
		(net "M_A_DQ33")
	)
	(segment
		(start 146.4564 -61.1886)
		(end 146.558 -61.087)
		(width 0.1524)
		(layer "In4.Cu")
		(net "M_A_DQ33")
	)
	(segment
		(start 141.9225 -56.7309)
		(end 141.9225 -56.251094)
		(width 0.1524)
		(layer "In4.Cu")
		(net "M_A_DQ33")
	)
	(segment
		(start 100.7364 -49.9364)
		(end 100.579682 -49.9364)
		(width 0.1016)
		(layer "In4.Cu")
		(net "M_A_DQ33")
	)
	(segment
		(start 145.9103 -60.5028)
		(end 145.694908 -60.5028)
		(width 0.1524)
		(layer "In4.Cu")
		(net "M_A_DQ33")
	)
	(segment
		(start 146.558 -61.087)
		(end 147.0152 -61.087)
		(width 0.1524)
		(layer "In4.Cu")
		(net "M_A_DQ33")
	)
	(segment
		(start 143.75384 -58.34634)
		(end 144.05229 -58.048144)
		(width 0.1524)
		(layer "In4.Cu")
		(net "M_A_DQ33")
	)
	(segment
		(start 144.914874 -58.910728)
		(end 144.914874 -58.695336)
		(width 0.1524)
		(layer "In4.Cu")
		(net "M_A_DQ33")
	)
	(segment
		(start 147.2819 -62.8396)
		(end 147.4343 -62.6872)
		(width 0.1524)
		(layer "In4.Cu")
		(net "M_A_DQ33")
	)
	(segment
		(start 141.9225 -56.251094)
		(end 141.397736 -55.72633)
		(width 0.1524)
		(layer "In4.Cu")
		(net "M_A_DQ33")
	)
	(segment
		(start 133.4008 -55.2704)
		(end 132.9436 -55.2704)
		(width 0.1524)
		(layer "In4.Cu")
		(net "M_A_DQ33")
	)
	(segment
		(start 145.047716 -59.640216)
		(end 144.832324 -59.640216)
		(width 0.1524)
		(layer "In4.Cu")
		(net "M_A_DQ33")
	)
	(segment
		(start 147.3708 -65.9384)
		(end 146.6088 -65.9384)
		(width 0.1524)
		(layer "In4.Cu")
		(net "M_A_DQ33")
	)
	(segment
		(start 102.3493 -51.5493)
		(end 100.965 -50.165)
		(width 0.1524)
		(layer "In4.Cu")
		(net "M_A_DQ33")
	)
	(segment
		(start 147.4343 -62.0903)
		(end 147.2565 -61.9125)
		(width 0.1524)
		(layer "In4.Cu")
		(net "M_A_DQ33")
	)
	(segment
		(start 134.447788 -55.2704)
		(end 134.295388 -55.4228)
		(width 0.1524)
		(layer "In4.Cu")
		(net "M_A_DQ33")
	)
	(segment
		(start 146.6088 -62.8396)
		(end 147.2819 -62.8396)
		(width 0.1524)
		(layer "In4.Cu")
		(net "M_A_DQ33")
	)
	(segment
		(start 100.457 -49.8856)
		(end 100.249482 -49.678082)
		(width 0.1016)
		(layer "In4.Cu")
		(net "M_A_DQ33")
	)
	(segment
		(start 146.6215 -61.9125)
		(end 146.4564 -61.7474)
		(width 0.1524)
		(layer "In4.Cu")
		(net "M_A_DQ33")
	)
	(segment
		(start 141.397736 -55.72633)
		(end 135.68553 -55.72633)
		(width 0.1524)
		(layer "In4.Cu")
		(net "M_A_DQ33")
	)
	(segment
		(start 146.4564 -61.7474)
		(end 146.4564 -61.1886)
		(width 0.1524)
		(layer "In4.Cu")
		(net "M_A_DQ33")
	)
	(segment
		(start 147.0152 -61.087)
		(end 147.1422 -60.96)
		(width 0.1524)
		(layer "In4.Cu")
		(net "M_A_DQ33")
	)
	(segment
		(start 146.960844 -60.274454)
		(end 146.1389 -60.274454)
		(width 0.1524)
		(layer "In4.Cu")
		(net "M_A_DQ33")
	)
	(segment
		(start 99.977702 -48.796702)
		(end 99.495102 -48.796702)
		(width 0.1016)
		(layer "In4.Cu")
		(net "M_A_DQ33")
	)
	(segment
		(start 108.5596 -55.4482)
		(end 108.1278 -55.0164)
		(width 0.1524)
		(layer "In4.Cu")
		(net "M_A_DQ33")
	)
	(segment
		(start 133.5532 -55.4228)
		(end 133.4008 -55.2704)
		(width 0.1524)
		(layer "In4.Cu")
		(net "M_A_DQ33")
	)
	(segment
		(start 142.903448 -57.1754)
		(end 142.367 -57.1754)
		(width 0.1524)
		(layer "In4.Cu")
		(net "M_A_DQ33")
	)
	(segment
		(start 144.185132 -58.777632)
		(end 143.96974 -58.777632)
		(width 0.1524)
		(layer "In4.Cu")
		(net "M_A_DQ33")
	)
	(segment
		(start 100.1776 -48.9966)
		(end 99.977702 -48.796702)
		(width 0.1016)
		(layer "In4.Cu")
		(net "M_A_DQ33")
	)
	(segment
		(start 145.479008 -60.071508)
		(end 145.777458 -59.773312)
		(width 0.1524)
		(layer "In4.Cu")
		(net "M_A_DQ33")
	)
	(segment
		(start 132.7912 -55.4228)
		(end 132.7912 -55.6768)
		(width 0.1524)
		(layer "In4.Cu")
		(net "M_A_DQ33")
	)
	(segment
		(start 145.479008 -60.2869)
		(end 145.479008 -60.071508)
		(width 0.1524)
		(layer "In4.Cu")
		(net "M_A_DQ33")
	)
	(segment
		(start 143.598138 -57.3786)
		(end 143.106648 -57.3786)
		(width 0.1524)
		(layer "In4.Cu")
		(net "M_A_DQ33")
	)
	(segment
		(start 144.616424 -59.424316)
		(end 144.616424 -59.208924)
		(width 0.1524)
		(layer "In4.Cu")
		(net "M_A_DQ33")
	)
	(segment
		(start 147.4343 -62.6872)
		(end 147.4343 -62.0903)
		(width 0.1524)
		(layer "In4.Cu")
		(net "M_A_DQ33")
	)
	(segment
		(start 146.1389 -60.274454)
		(end 145.9103 -60.5028)
		(width 0.1524)
		(layer "In4.Cu")
		(net "M_A_DQ33")
	)
	(segment
		(start 132.6388 -55.8292)
		(end 109.6518 -55.8292)
		(width 0.1524)
		(layer "In4.Cu")
		(net "M_A_DQ33")
	)
	(segment
		(start 145.777458 -59.773312)
		(end 145.777458 -59.55792)
		(width 0.1524)
		(layer "In4.Cu")
		(net "M_A_DQ33")
	)
	(segment
		(start 132.7912 -55.6768)
		(end 132.6388 -55.8292)
		(width 0.1524)
		(layer "In4.Cu")
		(net "M_A_DQ33")
	)
	(segment
		(start 147.1422 -60.96)
		(end 147.1422 -60.45581)
		(width 0.1524)
		(layer "In4.Cu")
		(net "M_A_DQ33")
	)
	(segment
		(start 144.05229 -57.832752)
		(end 143.598138 -57.3786)
		(width 0.1524)
		(layer "In4.Cu")
		(net "M_A_DQ33")
	)
	(segment
		(start 100.1776 -49.5046)
		(end 100.1776 -48.9966)
		(width 0.1016)
		(layer "In4.Cu")
		(net "M_A_DQ33")
	)
	(segment
		(start 134.295388 -55.6768)
		(end 134.142988 -55.8292)
		(width 0.1524)
		(layer "In4.Cu")
		(net "M_A_DQ33")
	)
	(segment
		(start 98.73742 -46.89602)
		(end 97.536 -46.89602)
		(width 0.1016)
		(layer "In4.Cu")
		(net "M_A_DQ33")
	)
	(segment
		(start 133.7056 -55.8292)
		(end 133.5532 -55.6768)
		(width 0.1524)
		(layer "In4.Cu")
		(net "M_A_DQ33")
	)
	(segment
		(start 143.75384 -58.561732)
		(end 143.75384 -58.34634)
		(width 0.1524)
		(layer "In4.Cu")
		(net "M_A_DQ33")
	)
	(segment
		(start 108.1278 -54.1528)
		(end 107.1372 -53.1622)
		(width 0.1524)
		(layer "In4.Cu")
		(net "M_A_DQ33")
	)
	(segment
		(start 99.314 -48.6156)
		(end 99.314 -47.4726)
		(width 0.1016)
		(layer "In4.Cu")
		(net "M_A_DQ33")
	)
	(segment
		(start 97.15881 -46.73981)
		(end 96.9772 -46.5582)
		(width 0.1016)
		(layer "In4.Cu")
		(net "M_A_DQ33")
	)
	(segment
		(start 142.367 -57.1754)
		(end 141.9225 -56.7309)
		(width 0.1524)
		(layer "In4.Cu")
		(net "M_A_DQ33")
	)
	(segment
		(start 147.11807 -64.7319)
		(end 147.5232 -65.13703)
		(width 0.1524)
		(layer "In4.Cu")
		(net "M_A_DQ33")
	)
	(segment
		(start 104.0003 -51.5493)
		(end 102.3493 -51.5493)
		(width 0.1524)
		(layer "In4.Cu")
		(net "M_A_DQ33")
	)
	(segment
		(start 109.2708 -55.4482)
		(end 108.5596 -55.4482)
		(width 0.1524)
		(layer "In4.Cu")
		(net "M_A_DQ33")
	)
	(segment
		(start 99.495102 -48.796702)
		(end 99.314 -48.6156)
		(width 0.1016)
		(layer "In4.Cu")
		(net "M_A_DQ33")
	)
	(segment
		(start 145.694908 -60.5028)
		(end 145.479008 -60.2869)
		(width 0.1524)
		(layer "In4.Cu")
		(net "M_A_DQ33")
	)
	(segment
		(start 100.965 -50.165)
		(end 100.7364 -49.9364)
		(width 0.1016)
		(layer "In4.Cu")
		(net "M_A_DQ33")
	)
	(segment
		(start 144.616424 -59.208924)
		(end 144.914874 -58.910728)
		(width 0.1524)
		(layer "In4.Cu")
		(net "M_A_DQ33")
	)
	(segment
		(start 107.1372 -53.1622)
		(end 105.6132 -53.1622)
		(width 0.1524)
		(layer "In4.Cu")
		(net "M_A_DQ33")
	)
	(segment
		(start 143.106648 -57.3786)
		(end 142.903448 -57.1754)
		(width 0.1524)
		(layer "In4.Cu")
		(net "M_A_DQ33")
	)
	(segment
		(start 147.5232 -65.786)
		(end 147.3708 -65.9384)
		(width 0.1524)
		(layer "In4.Cu")
		(net "M_A_DQ33")
	)
	(segment
		(start 147.5232 -65.13703)
		(end 147.5232 -65.786)
		(width 0.1524)
		(layer "In4.Cu")
		(net "M_A_DQ33")
	)
	(segment
		(start 144.914874 -58.695336)
		(end 144.698974 -58.479436)
		(width 0.1524)
		(layer "In4.Cu")
		(net "M_A_DQ33")
	)
	(segment
		(start 146.4564 -65.786)
		(end 146.4564 -62.992)
		(width 0.1524)
		(layer "In4.Cu")
		(net "M_A_DQ33")
	)
	(segment
		(start 133.5532 -55.6768)
		(end 133.5532 -55.4228)
		(width 0.1524)
		(layer "In4.Cu")
		(net "M_A_DQ33")
	)
	(segment
		(start 144.698974 -58.479436)
		(end 144.483582 -58.479436)
		(width 0.1524)
		(layer "In4.Cu")
		(net "M_A_DQ33")
	)
	(segment
		(start 146.6088 -65.9384)
		(end 146.4564 -65.786)
		(width 0.1524)
		(layer "In4.Cu")
		(net "M_A_DQ33")
	)
	(segment
		(start 134.142988 -55.8292)
		(end 133.7056 -55.8292)
		(width 0.1524)
		(layer "In4.Cu")
		(net "M_A_DQ33")
	)
	(segment
		(start 99.314 -47.4726)
		(end 98.73742 -46.89602)
		(width 0.1016)
		(layer "In4.Cu")
		(net "M_A_DQ33")
	)
	(segment
		(start 132.9436 -55.2704)
		(end 132.7912 -55.4228)
		(width 0.1524)
		(layer "In4.Cu")
		(net "M_A_DQ33")
	)
	(segment
		(start 108.1278 -55.0164)
		(end 108.1278 -54.1528)
		(width 0.1524)
		(layer "In4.Cu")
		(net "M_A_DQ33")
	)
	(segment
		(start 144.483582 -58.479436)
		(end 144.185132 -58.777632)
		(width 0.1524)
		(layer "In4.Cu")
		(net "M_A_DQ33")
	)
	(segment
		(start 147.1422 -60.45581)
		(end 146.960844 -60.274454)
		(width 0.1524)
		(layer "In4.Cu")
		(net "M_A_DQ33")
	)
	(segment
		(start 145.561558 -59.34202)
		(end 145.346166 -59.34202)
		(width 0.1524)
		(layer "In4.Cu")
		(net "M_A_DQ33")
	)
	(segment
		(start 146.4564 -62.992)
		(end 146.6088 -62.8396)
		(width 0.1524)
		(layer "In4.Cu")
		(net "M_A_DQ33")
	)
	(segment
		(start 134.295388 -55.4228)
		(end 134.295388 -55.6768)
		(width 0.1524)
		(layer "In4.Cu")
		(net "M_A_DQ33")
	)
	(segment
		(start 144.832324 -59.640216)
		(end 144.616424 -59.424316)
		(width 0.1524)
		(layer "In4.Cu")
		(net "M_A_DQ33")
	)
	(segment
		(start 135.68553 -55.72633)
		(end 135.2296 -55.2704)
		(width 0.1524)
		(layer "In4.Cu")
		(net "M_A_DQ33")
	)
	(arc
		(start 100.579682 -49.9364)
		(mid 100.513293 -49.923194)
		(end 100.457 -49.8856)
		(width 0.1016)
		(layer "In4.Cu")
		(net "M_A_DQ33")
	)
	(arc
		(start 100.249482 -49.678082)
		(mid 100.196299 -49.598488)
		(end 100.1776 -49.5046)
		(width 0.1016)
		(layer "In4.Cu")
		(net "M_A_DQ33")
	)
	(arc
		(start 97.536 -46.89602)
		(mid 97.331877 -46.855417)
		(end 97.15881 -46.73981)
		(width 0.1016)
		(layer "In4.Cu")
		(net "M_A_DQ33")
	)
	(segment
		(start 49.2506 -48.697388)
		(end 48.668178 -48.697388)
		(width 0.1143)
		(layer "B.Cu")
		(net "CLKGEN_PCI_STOP#")
	)
	(segment
		(start 49.4284 -48.519588)
		(end 49.2506 -48.697388)
		(width 0.1143)
		(layer "B.Cu")
		(net "CLKGEN_PCI_STOP#")
	)
	(segment
		(start 50.018188 -48.519588)
		(end 49.4284 -48.519588)
		(width 0.1143)
		(layer "B.Cu")
		(net "CLKGEN_PCI_STOP#")
	)
	(segment
		(start 50.8762 -49.53)
		(end 50.8762 -49.3776)
		(width 0.1143)
		(layer "B.Cu")
		(net "CLKGEN_PCI_STOP#")
	)
	(segment
		(start 50.8762 -49.3776)
		(end 50.018188 -48.519588)
		(width 0.1143)
		(layer "B.Cu")
		(net "CLKGEN_PCI_STOP#")
	)
	(segment
		(start 105.321354 -45.24502)
		(end 105.004108 -44.927774)
		(width 0.1016)
		(layer "F.Cu")
		(net "M_A_DQ23")
	)
	(segment
		(start 175.150018 -68.816982)
		(end 175.1838 -68.7832)
		(width 0.1778)
		(layer "F.Cu")
		(net "M_A_DQ23")
	)
	(segment
		(start 105.39984 -45.24502)
		(end 105.321354 -45.24502)
		(width 0.1016)
		(layer "F.Cu")
		(net "M_A_DQ23")
	)
	(segment
		(start 175.150018 -70.806564)
		(end 175.150018 -68.816982)
		(width 0.1778)
		(layer "F.Cu")
		(net "M_A_DQ23")
	)
	(via
		(at 175.1838 -68.7832)
		(size 0.4318)
		(drill 0.2032)
		(layers "F.Cu" "B.Cu")
		(net "M_A_DQ23")
	)
	(via
		(at 105.39984 -45.24502)
		(size 0.4318)
		(drill 0.2032)
		(layers "F.Cu" "B.Cu")
		(net "M_A_DQ23")
	)
	(segment
		(start 175.449992 -70.79996)
		(end 175.449992 -69.049392)
		(width 0.1778)
		(layer "B.Cu")
		(net "M_A_DQ23")
	)
	(segment
		(start 175.449992 -69.049392)
		(end 175.1838 -68.7832)
		(width 0.1778)
		(layer "B.Cu")
		(net "M_A_DQ23")
	)
	(segment
		(start 110.617 -50.56251)
		(end 112.53089 -52.4764)
		(width 0.1524)
		(layer "In4.Cu")
		(net "M_A_DQ23")
	)
	(segment
		(start 109.990128 -50.478182)
		(end 109.923834 -50.411634)
		(width 0.1016)
		(layer "In4.Cu")
		(net "M_A_DQ23")
	)
	(segment
		(start 106.8324 -47.752)
		(end 106.00817 -46.92777)
		(width 0.1016)
		(layer "In4.Cu")
		(net "M_A_DQ23")
	)
	(segment
		(start 175.81753 -63.60541)
		(end 175.81753 -64.25565)
		(width 0.1524)
		(layer "In4.Cu")
		(net "M_A_DQ23")
	)
	(segment
		(start 108.6231 -48.7807)
		(end 108.6231 -48.1965)
		(width 0.1016)
		(layer "In4.Cu")
		(net "M_A_DQ23")
	)
	(segment
		(start 112.53089 -52.4764)
		(end 117.5004 -52.4764)
		(width 0.1524)
		(layer "In4.Cu")
		(net "M_A_DQ23")
	)
	(segment
		(start 104.9528 -46.4058)
		(end 104.9528 -45.68825)
		(width 0.1016)
		(layer "In4.Cu")
		(net "M_A_DQ23")
	)
	(segment
		(start 118.2624 -51.7144)
		(end 122.934476 -51.7144)
		(width 0.1524)
		(layer "In4.Cu")
		(net "M_A_DQ23")
	)
	(segment
		(start 149.700742 -57.1754)
		(end 162.22599 -57.1754)
		(width 0.1524)
		(layer "In4.Cu")
		(net "M_A_DQ23")
	)
	(segment
		(start 109.728 -50.2158)
		(end 109.728 -49.8856)
		(width 0.1016)
		(layer "In4.Cu")
		(net "M_A_DQ23")
	)
	(segment
		(start 144.200372 -52.9336)
		(end 145.458942 -52.9336)
		(width 0.1524)
		(layer "In4.Cu")
		(net "M_A_DQ23")
	)
	(segment
		(start 105.32999 -45.31487)
		(end 105.39984 -45.24502)
		(width 0.1016)
		(layer "In4.Cu")
		(net "M_A_DQ23")
	)
	(segment
		(start 106.00817 -46.92777)
		(end 105.47477 -46.92777)
		(width 0.1016)
		(layer "In4.Cu")
		(net "M_A_DQ23")
	)
	(segment
		(start 104.9528 -45.68825)
		(end 105.32618 -45.31487)
		(width 0.1016)
		(layer "In4.Cu")
		(net "M_A_DQ23")
	)
	(segment
		(start 117.5004 -52.4764)
		(end 118.2624 -51.7144)
		(width 0.1524)
		(layer "In4.Cu")
		(net "M_A_DQ23")
	)
	(segment
		(start 109.728 -49.8856)
		(end 108.6231 -48.7807)
		(width 0.1016)
		(layer "In4.Cu")
		(net "M_A_DQ23")
	)
	(segment
		(start 175.320198 -66.325242)
		(end 175.320198 -68.646802)
		(width 0.1524)
		(layer "In4.Cu")
		(net "M_A_DQ23")
	)
	(segment
		(start 175.81753 -64.25565)
		(end 175.82134 -64.25946)
		(width 0.1524)
		(layer "In4.Cu")
		(net "M_A_DQ23")
	)
	(segment
		(start 107.6706 -47.9806)
		(end 107.442 -47.752)
		(width 0.1016)
		(layer "In4.Cu")
		(net "M_A_DQ23")
	)
	(segment
		(start 176.3268 -65.31864)
		(end 175.320198 -66.325242)
		(width 0.1524)
		(layer "In4.Cu")
		(net "M_A_DQ23")
	)
	(segment
		(start 107.442 -47.752)
		(end 106.8324 -47.752)
		(width 0.1016)
		(layer "In4.Cu")
		(net "M_A_DQ23")
	)
	(segment
		(start 176.3268 -64.771016)
		(end 176.3268 -65.31864)
		(width 0.1524)
		(layer "In4.Cu")
		(net "M_A_DQ23")
	)
	(segment
		(start 109.923834 -50.411634)
		(end 109.728 -50.2158)
		(width 0.1016)
		(layer "In4.Cu")
		(net "M_A_DQ23")
	)
	(segment
		(start 145.458942 -52.9336)
		(end 149.700742 -57.1754)
		(width 0.1524)
		(layer "In4.Cu")
		(net "M_A_DQ23")
	)
	(segment
		(start 170.034204 -62.9158)
		(end 175.12792 -62.9158)
		(width 0.1524)
		(layer "In4.Cu")
		(net "M_A_DQ23")
	)
	(segment
		(start 105.32618 -45.31487)
		(end 105.32999 -45.31487)
		(width 0.1016)
		(layer "In4.Cu")
		(net "M_A_DQ23")
	)
	(segment
		(start 108.4072 -47.9806)
		(end 107.6706 -47.9806)
		(width 0.1016)
		(layer "In4.Cu")
		(net "M_A_DQ23")
	)
	(segment
		(start 162.22599 -57.1754)
		(end 164.965888 -59.915298)
		(width 0.1524)
		(layer "In4.Cu")
		(net "M_A_DQ23")
	)
	(segment
		(start 164.965888 -59.915298)
		(end 167.033702 -59.915298)
		(width 0.1524)
		(layer "In4.Cu")
		(net "M_A_DQ23")
	)
	(segment
		(start 175.82134 -64.265556)
		(end 176.3268 -64.771016)
		(width 0.1524)
		(layer "In4.Cu")
		(net "M_A_DQ23")
	)
	(segment
		(start 122.934476 -51.7144)
		(end 123.391676 -51.2572)
		(width 0.1524)
		(layer "In4.Cu")
		(net "M_A_DQ23")
	)
	(segment
		(start 105.47477 -46.92777)
		(end 104.9528 -46.4058)
		(width 0.1016)
		(layer "In4.Cu")
		(net "M_A_DQ23")
	)
	(segment
		(start 123.391676 -51.2572)
		(end 142.523972 -51.2572)
		(width 0.1524)
		(layer "In4.Cu")
		(net "M_A_DQ23")
	)
	(segment
		(start 175.12792 -62.9158)
		(end 175.81753 -63.60541)
		(width 0.1524)
		(layer "In4.Cu")
		(net "M_A_DQ23")
	)
	(segment
		(start 175.82134 -64.25946)
		(end 175.82134 -64.265556)
		(width 0.1524)
		(layer "In4.Cu")
		(net "M_A_DQ23")
	)
	(segment
		(start 167.033702 -59.915298)
		(end 170.034204 -62.9158)
		(width 0.1524)
		(layer "In4.Cu")
		(net "M_A_DQ23")
	)
	(segment
		(start 110.19409 -50.56251)
		(end 110.617 -50.56251)
		(width 0.1524)
		(layer "In4.Cu")
		(net "M_A_DQ23")
	)
	(segment
		(start 142.523972 -51.2572)
		(end 144.200372 -52.9336)
		(width 0.1524)
		(layer "In4.Cu")
		(net "M_A_DQ23")
	)
	(segment
		(start 108.6231 -48.1965)
		(end 108.4072 -47.9806)
		(width 0.1016)
		(layer "In4.Cu")
		(net "M_A_DQ23")
	)
	(segment
		(start 175.320198 -68.646802)
		(end 175.1838 -68.7832)
		(width 0.1524)
		(layer "In4.Cu")
		(net "M_A_DQ23")
	)
	(arc
		(start 110.19409 -50.56251)
		(mid 110.083712 -50.540648)
		(end 109.990128 -50.478182)
		(width 0.1016)
		(layer "In4.Cu")
		(net "M_A_DQ23")
	)
	(via
		(at 40.64 -43.6118)
		(size 0.7112)
		(drill 0.3556)
		(layers "F.Cu" "B.Cu")
		(net "XTAL_CLK_GEN_OUT_R")
	)
	(segment
		(start 42.5958 -46.5582)
		(end 42.5958 -45.8216)
		(width 0.1143)
		(layer "B.Cu")
		(net "XTAL_CLK_GEN_OUT_R")
	)
	(segment
		(start 43.04919 -46.697392)
		(end 42.734992 -46.697392)
		(width 0.1143)
		(layer "B.Cu")
		(net "XTAL_CLK_GEN_OUT_R")
	)
	(segment
		(start 41.3766 -44.958)
		(end 40.9702 -44.5516)
		(width 0.1143)
		(layer "B.Cu")
		(net "XTAL_CLK_GEN_OUT_R")
	)
	(segment
		(start 39.2176 -43.6118)
		(end 40.64 -43.6118)
		(width 0.1143)
		(layer "B.Cu")
		(net "XTAL_CLK_GEN_OUT_R")
	)
	(segment
		(start 42.734992 -46.697392)
		(end 42.5958 -46.5582)
		(width 0.1143)
		(layer "B.Cu")
		(net "XTAL_CLK_GEN_OUT_R")
	)
	(segment
		(start 39.1668 -43.561)
		(end 39.2176 -43.6118)
		(width 0.1143)
		(layer "B.Cu")
		(net "XTAL_CLK_GEN_OUT_R")
	)
	(segment
		(start 40.9702 -43.942)
		(end 40.64 -43.6118)
		(width 0.1143)
		(layer "B.Cu")
		(net "XTAL_CLK_GEN_OUT_R")
	)
	(segment
		(start 41.7322 -44.958)
		(end 41.3766 -44.958)
		(width 0.1143)
		(layer "B.Cu")
		(net "XTAL_CLK_GEN_OUT_R")
	)
	(segment
		(start 40.9702 -44.5516)
		(end 40.9702 -43.942)
		(width 0.1143)
		(layer "B.Cu")
		(net "XTAL_CLK_GEN_OUT_R")
	)
	(segment
		(start 42.5958 -45.8216)
		(end 41.7322 -44.958)
		(width 0.1143)
		(layer "B.Cu")
		(net "XTAL_CLK_GEN_OUT_R")
	)
	(segment
		(start 113.8174 -50.131472)
		(end 113.8174 -48.991012)
		(width 0.1016)
		(layer "F.Cu")
		(net "M_A_ECC7")
	)
	(segment
		(start 163.150042 -69.520562)
		(end 163.305998 -69.364606)
		(width 0.1778)
		(layer "F.Cu")
		(net "M_A_ECC7")
	)
	(segment
		(start 115.6716 -50.5206)
		(end 114.206528 -50.5206)
		(width 0.1016)
		(layer "F.Cu")
		(net "M_A_ECC7")
	)
	(segment
		(start 113.8174 -48.991012)
		(end 112.08639 -47.260002)
		(width 0.1016)
		(layer "F.Cu")
		(net "M_A_ECC7")
	)
	(segment
		(start 112.08639 -47.260002)
		(end 111.250476 -47.260002)
		(width 0.1016)
		(layer "F.Cu")
		(net "M_A_ECC7")
	)
	(segment
		(start 116.1796 -50.038)
		(end 116.1542 -50.038)
		(width 0.1016)
		(layer "F.Cu")
		(net "M_A_ECC7")
	)
	(segment
		(start 116.1542 -50.038)
		(end 115.6716 -50.5206)
		(width 0.1016)
		(layer "F.Cu")
		(net "M_A_ECC7")
	)
	(segment
		(start 111.250476 -47.260002)
		(end 111.092488 -47.102014)
		(width 0.1016)
		(layer "F.Cu")
		(net "M_A_ECC7")
	)
	(segment
		(start 114.206528 -50.5206)
		(end 113.8174 -50.131472)
		(width 0.1016)
		(layer "F.Cu")
		(net "M_A_ECC7")
	)
	(segment
		(start 163.150042 -70.806564)
		(end 163.150042 -69.520562)
		(width 0.1778)
		(layer "F.Cu")
		(net "M_A_ECC7")
	)
	(via
		(at 116.1796 -50.038)
		(size 0.4318)
		(drill 0.2032)
		(layers "F.Cu" "B.Cu")
		(net "M_A_ECC7")
	)
	(via
		(at 163.305998 -69.364606)
		(size 0.4318)
		(drill 0.2032)
		(layers "F.Cu" "B.Cu")
		(net "M_A_ECC7")
	)
	(segment
		(start 163.450016 -70.79996)
		(end 163.450016 -69.508624)
		(width 0.1778)
		(layer "B.Cu")
		(net "M_A_ECC7")
	)
	(segment
		(start 163.450016 -69.508624)
		(end 163.305998 -69.364606)
		(width 0.1778)
		(layer "B.Cu")
		(net "M_A_ECC7")
	)
	(segment
		(start 163.16706 -69.225668)
		(end 163.16706 -68.525644)
		(width 0.1524)
		(layer "In2.Cu")
		(net "M_A_ECC7")
	)
	(segment
		(start 164.8714 -63.303404)
		(end 164.5666 -63.303404)
		(width 0.1524)
		(layer "In2.Cu")
		(net "M_A_ECC7")
	)
	(segment
		(start 164.4142 -63.151004)
		(end 164.4142 -62.846204)
		(width 0.1524)
		(layer "In2.Cu")
		(net "M_A_ECC7")
	)
	(segment
		(start 164.5666 -62.693804)
		(end 164.8714 -62.693804)
		(width 0.1524)
		(layer "In2.Cu")
		(net "M_A_ECC7")
	)
	(segment
		(start 155.94076 -56.515)
		(end 155.78836 -56.6674)
		(width 0.1524)
		(layer "In2.Cu")
		(net "M_A_ECC7")
	)
	(segment
		(start 158.22676 -56.6674)
		(end 158.22676 -56.8071)
		(width 0.1524)
		(layer "In2.Cu")
		(net "M_A_ECC7")
	)
	(segment
		(start 160.1724 -57.912)
		(end 160.02 -58.0644)
		(width 0.1524)
		(layer "In2.Cu")
		(net "M_A_ECC7")
	)
	(segment
		(start 154.56916 -56.8071)
		(end 154.41676 -56.9595)
		(width 0.1524)
		(layer "In2.Cu")
		(net "M_A_ECC7")
	)
	(segment
		(start 163.2966 -66.04)
		(end 163.2966 -65.4812)
		(width 0.1524)
		(layer "In2.Cu")
		(net "M_A_ECC7")
	)
	(segment
		(start 163.16706 -68.525644)
		(end 163.2966 -68.396104)
		(width 0.1524)
		(layer "In2.Cu")
		(net "M_A_ECC7")
	)
	(segment
		(start 158.83636 -56.6674)
		(end 158.68396 -56.515)
		(width 0.1524)
		(layer "In2.Cu")
		(net "M_A_ECC7")
	)
	(segment
		(start 143.5354 -53.253132)
		(end 143.5354 -52.5272)
		(width 0.1524)
		(layer "In2.Cu")
		(net "M_A_ECC7")
	)
	(segment
		(start 154.41676 -56.9595)
		(end 147.241768 -56.9595)
		(width 0.1524)
		(layer "In2.Cu")
		(net "M_A_ECC7")
	)
	(segment
		(start 158.83636 -57.15)
		(end 158.83636 -56.6674)
		(width 0.1524)
		(layer "In2.Cu")
		(net "M_A_ECC7")
	)
	(segment
		(start 159.5628 -57.912)
		(end 159.5628 -57.4548)
		(width 0.1524)
		(layer "In2.Cu")
		(net "M_A_ECC7")
	)
	(segment
		(start 160.3248 -57.545478)
		(end 160.1724 -57.697878)
		(width 0.1524)
		(layer "In2.Cu")
		(net "M_A_ECC7")
	)
	(segment
		(start 159.5628 -57.4548)
		(end 159.4104 -57.3024)
		(width 0.1524)
		(layer "In2.Cu")
		(net "M_A_ECC7")
	)
	(segment
		(start 157.00756 -56.8071)
		(end 156.85516 -56.9595)
		(width 0.1524)
		(layer "In2.Cu")
		(net "M_A_ECC7")
	)
	(segment
		(start 154.56916 -56.6674)
		(end 154.56916 -56.8071)
		(width 0.1524)
		(layer "In2.Cu")
		(net "M_A_ECC7")
	)
	(segment
		(start 164.34816 -65.2526)
		(end 165.0238 -64.57696)
		(width 0.1524)
		(layer "In2.Cu")
		(net "M_A_ECC7")
	)
	(segment
		(start 163.305998 -69.364606)
		(end 163.16706 -69.225668)
		(width 0.1524)
		(layer "In2.Cu")
		(net "M_A_ECC7")
	)
	(segment
		(start 155.78836 -56.6674)
		(end 155.78836 -56.8071)
		(width 0.1524)
		(layer "In2.Cu")
		(net "M_A_ECC7")
	)
	(segment
		(start 142.256256 -51.248056)
		(end 118.659656 -51.248056)
		(width 0.1524)
		(layer "In2.Cu")
		(net "M_A_ECC7")
	)
	(segment
		(start 163.5252 -65.2526)
		(end 164.34816 -65.2526)
		(width 0.1524)
		(layer "In2.Cu")
		(net "M_A_ECC7")
	)
	(segment
		(start 155.78836 -56.8071)
		(end 155.63596 -56.9595)
		(width 0.1524)
		(layer "In2.Cu")
		(net "M_A_ECC7")
	)
	(segment
		(start 156.39796 -56.8071)
		(end 156.39796 -56.6674)
		(width 0.1524)
		(layer "In2.Cu")
		(net "M_A_ECC7")
	)
	(segment
		(start 155.17876 -56.8071)
		(end 155.17876 -56.6674)
		(width 0.1524)
		(layer "In2.Cu")
		(net "M_A_ECC7")
	)
	(segment
		(start 163.2966 -65.4812)
		(end 163.5252 -65.2526)
		(width 0.1524)
		(layer "In2.Cu")
		(net "M_A_ECC7")
	)
	(segment
		(start 163.2966 -68.396104)
		(end 163.2966 -67.4624)
		(width 0.1524)
		(layer "In2.Cu")
		(net "M_A_ECC7")
	)
	(segment
		(start 165.0238 -61.92901)
		(end 160.640268 -57.545478)
		(width 0.1524)
		(layer "In2.Cu")
		(net "M_A_ECC7")
	)
	(segment
		(start 159.4104 -57.3024)
		(end 158.98876 -57.3024)
		(width 0.1524)
		(layer "In2.Cu")
		(net "M_A_ECC7")
	)
	(segment
		(start 155.63596 -56.9595)
		(end 155.33116 -56.9595)
		(width 0.1524)
		(layer "In2.Cu")
		(net "M_A_ECC7")
	)
	(segment
		(start 164.4142 -62.846204)
		(end 164.5666 -62.693804)
		(width 0.1524)
		(layer "In2.Cu")
		(net "M_A_ECC7")
	)
	(segment
		(start 163.2966 -67.4624)
		(end 163.449 -67.31)
		(width 0.1524)
		(layer "In2.Cu")
		(net "M_A_ECC7")
	)
	(segment
		(start 117.4496 -50.038)
		(end 118.659656 -51.248056)
		(width 0.1016)
		(layer "In2.Cu")
		(net "M_A_ECC7")
	)
	(segment
		(start 156.85516 -56.9595)
		(end 156.55036 -56.9595)
		(width 0.1524)
		(layer "In2.Cu")
		(net "M_A_ECC7")
	)
	(segment
		(start 158.07436 -56.9595)
		(end 157.76956 -56.9595)
		(width 0.1524)
		(layer "In2.Cu")
		(net "M_A_ECC7")
	)
	(segment
		(start 158.98876 -57.3024)
		(end 158.83636 -57.15)
		(width 0.1524)
		(layer "In2.Cu")
		(net "M_A_ECC7")
	)
	(segment
		(start 155.33116 -56.9595)
		(end 155.17876 -56.8071)
		(width 0.1524)
		(layer "In2.Cu")
		(net "M_A_ECC7")
	)
	(segment
		(start 157.61716 -56.8071)
		(end 157.61716 -56.6674)
		(width 0.1524)
		(layer "In2.Cu")
		(net "M_A_ECC7")
	)
	(segment
		(start 154.72156 -56.515)
		(end 154.56916 -56.6674)
		(width 0.1524)
		(layer "In2.Cu")
		(net "M_A_ECC7")
	)
	(segment
		(start 165.0238 -63.455804)
		(end 164.8714 -63.303404)
		(width 0.1524)
		(layer "In2.Cu")
		(net "M_A_ECC7")
	)
	(segment
		(start 157.00756 -56.6674)
		(end 157.00756 -56.8071)
		(width 0.1524)
		(layer "In2.Cu")
		(net "M_A_ECC7")
	)
	(segment
		(start 157.61716 -56.6674)
		(end 157.46476 -56.515)
		(width 0.1524)
		(layer "In2.Cu")
		(net "M_A_ECC7")
	)
	(segment
		(start 164.8714 -62.693804)
		(end 165.0238 -62.541404)
		(width 0.1524)
		(layer "In2.Cu")
		(net "M_A_ECC7")
	)
	(segment
		(start 157.76956 -56.9595)
		(end 157.61716 -56.8071)
		(width 0.1524)
		(layer "In2.Cu")
		(net "M_A_ECC7")
	)
	(segment
		(start 158.68396 -56.515)
		(end 158.37916 -56.515)
		(width 0.1524)
		(layer "In2.Cu")
		(net "M_A_ECC7")
	)
	(segment
		(start 157.15996 -56.515)
		(end 157.00756 -56.6674)
		(width 0.1524)
		(layer "In2.Cu")
		(net "M_A_ECC7")
	)
	(segment
		(start 147.241768 -56.9595)
		(end 143.5354 -53.253132)
		(width 0.1524)
		(layer "In2.Cu")
		(net "M_A_ECC7")
	)
	(segment
		(start 157.46476 -56.515)
		(end 157.15996 -56.515)
		(width 0.1524)
		(layer "In2.Cu")
		(net "M_A_ECC7")
	)
	(segment
		(start 158.37916 -56.515)
		(end 158.22676 -56.6674)
		(width 0.1524)
		(layer "In2.Cu")
		(net "M_A_ECC7")
	)
	(segment
		(start 163.449 -66.1924)
		(end 163.2966 -66.04)
		(width 0.1524)
		(layer "In2.Cu")
		(net "M_A_ECC7")
	)
	(segment
		(start 143.5354 -52.5272)
		(end 142.256256 -51.248056)
		(width 0.1524)
		(layer "In2.Cu")
		(net "M_A_ECC7")
	)
	(segment
		(start 116.1796 -50.038)
		(end 117.4496 -50.038)
		(width 0.1016)
		(layer "In2.Cu")
		(net "M_A_ECC7")
	)
	(segment
		(start 163.449 -67.31)
		(end 163.449 -66.1924)
		(width 0.1524)
		(layer "In2.Cu")
		(net "M_A_ECC7")
	)
	(segment
		(start 165.0238 -62.541404)
		(end 165.0238 -61.92901)
		(width 0.1524)
		(layer "In2.Cu")
		(net "M_A_ECC7")
	)
	(segment
		(start 165.0238 -64.57696)
		(end 165.0238 -63.455804)
		(width 0.1524)
		(layer "In2.Cu")
		(net "M_A_ECC7")
	)
	(segment
		(start 160.640268 -57.545478)
		(end 160.3248 -57.545478)
		(width 0.1524)
		(layer "In2.Cu")
		(net "M_A_ECC7")
	)
	(segment
		(start 156.24556 -56.515)
		(end 155.94076 -56.515)
		(width 0.1524)
		(layer "In2.Cu")
		(net "M_A_ECC7")
	)
	(segment
		(start 160.1724 -57.697878)
		(end 160.1724 -57.912)
		(width 0.1524)
		(layer "In2.Cu")
		(net "M_A_ECC7")
	)
	(segment
		(start 159.7152 -58.0644)
		(end 159.5628 -57.912)
		(width 0.1524)
		(layer "In2.Cu")
		(net "M_A_ECC7")
	)
	(segment
		(start 164.5666 -63.303404)
		(end 164.4142 -63.151004)
		(width 0.1524)
		(layer "In2.Cu")
		(net "M_A_ECC7")
	)
	(segment
		(start 155.17876 -56.6674)
		(end 155.02636 -56.515)
		(width 0.1524)
		(layer "In2.Cu")
		(net "M_A_ECC7")
	)
	(segment
		(start 156.39796 -56.6674)
		(end 156.24556 -56.515)
		(width 0.1524)
		(layer "In2.Cu")
		(net "M_A_ECC7")
	)
	(segment
		(start 158.22676 -56.8071)
		(end 158.07436 -56.9595)
		(width 0.1524)
		(layer "In2.Cu")
		(net "M_A_ECC7")
	)
	(segment
		(start 160.02 -58.0644)
		(end 159.7152 -58.0644)
		(width 0.1524)
		(layer "In2.Cu")
		(net "M_A_ECC7")
	)
	(segment
		(start 156.55036 -56.9595)
		(end 156.39796 -56.8071)
		(width 0.1524)
		(layer "In2.Cu")
		(net "M_A_ECC7")
	)
	(segment
		(start 155.02636 -56.515)
		(end 154.72156 -56.515)
		(width 0.1524)
		(layer "In2.Cu")
		(net "M_A_ECC7")
	)
	(segment
		(start 39.2176 -50.927)
		(end 38.862 -51.2826)
		(width 0.508)
		(layer "F.Cu")
		(net "P3V3_CLK_PCI")
	)
	(segment
		(start 40.6146 -50.927)
		(end 39.5986 -50.927)
		(width 0.508)
		(layer "F.Cu")
		(net "P3V3_CLK_PCI")
	)
	(segment
		(start 40.767 -51.0794)
		(end 40.6146 -50.927)
		(width 0.508)
		(layer "F.Cu")
		(net "P3V3_CLK_PCI")
	)
	(segment
		(start 39.5986 -50.927)
		(end 39.2176 -50.927)
		(width 0.508)
		(layer "F.Cu")
		(net "P3V3_CLK_PCI")
	)
	(via
		(at 38.862 -51.2826)
		(size 0.508)
		(drill 0.254)
		(layers "F.Cu" "B.Cu")
		(net "P3V3_CLK_PCI")
	)
	(via
		(at 39.5986 -50.927)
		(size 0.7112)
		(drill 0.3556)
		(layers "F.Cu" "B.Cu")
		(net "P3V3_CLK_PCI")
	)
	(segment
		(start 40.0812 -51.4858)
		(end 39.878 -51.2826)
		(width 0.3048)
		(layer "B.Cu")
		(net "P3V3_CLK_PCI")
	)
	(segment
		(start 40.894 -51.435)
		(end 42.164 -50.165)
		(width 0.3048)
		(layer "B.Cu")
		(net "P3V3_CLK_PCI")
	)
	(segment
		(start 42.164 -49.403)
		(end 42.469816 -49.097184)
		(width 0.2032)
		(layer "B.Cu")
		(net "P3V3_CLK_PCI")
	)
	(segment
		(start 38.862 -51.2826)
		(end 39.878 -51.2826)
		(width 0.508)
		(layer "B.Cu")
		(net "P3V3_CLK_PCI")
	)
	(segment
		(start 40.894 -51.4858)
		(end 40.0812 -51.4858)
		(width 0.3048)
		(layer "B.Cu")
		(net "P3V3_CLK_PCI")
	)
	(segment
		(start 42.469816 -49.097184)
		(end 43.04919 -49.097184)
		(width 0.2032)
		(layer "B.Cu")
		(net "P3V3_CLK_PCI")
	)
	(segment
		(start 42.164 -50.165)
		(end 42.164 -49.403)
		(width 0.2032)
		(layer "B.Cu")
		(net "P3V3_CLK_PCI")
	)
	(segment
		(start 40.894 -51.4858)
		(end 40.894 -51.435)
		(width 0.3048)
		(layer "B.Cu")
		(net "P3V3_CLK_PCI")
	)
	(segment
		(start 106.672888 -52.204112)
		(end 106.672888 -52.965096)
		(width 0.1016)
		(layer "F.Cu")
		(net "CLK_100M_CPU_MPLL0_DP")
	)
	(segment
		(start 107.7087 -56.866028)
		(end 105.500678 -59.07405)
		(width 0.1016)
		(layer "F.Cu")
		(net "CLK_100M_CPU_MPLL0_DP")
	)
	(segment
		(start 100.134166 -60.889134)
		(end 100.134166 -61.246512)
		(width 0.1397)
		(layer "F.Cu")
		(net "CLK_100M_CPU_MPLL0_DP")
	)
	(segment
		(start 103.7463 -59.1439)
		(end 103.7209 -59.1439)
		(width 0.1016)
		(layer "F.Cu")
		(net "CLK_100M_CPU_MPLL0_DP")
	)
	(segment
		(start 103.7209 -59.1439)
		(end 101.8794 -59.1439)
		(width 0.1397)
		(layer "F.Cu")
		(net "CLK_100M_CPU_MPLL0_DP")
	)
	(segment
		(start 106.540808 -52.072032)
		(end 106.672888 -52.204112)
		(width 0.1016)
		(layer "F.Cu")
		(net "CLK_100M_CPU_MPLL0_DP")
	)
	(segment
		(start 106.37266 -53.6829)
		(end 106.81716 -54.1274)
		(width 0.1016)
		(layer "F.Cu")
		(net "CLK_100M_CPU_MPLL0_DP")
	)
	(segment
		(start 103.81615 -59.07405)
		(end 103.7463 -59.1439)
		(width 0.1016)
		(layer "F.Cu")
		(net "CLK_100M_CPU_MPLL0_DP")
	)
	(segment
		(start 105.500678 -59.07405)
		(end 103.81615 -59.07405)
		(width 0.1016)
		(layer "F.Cu")
		(net "CLK_100M_CPU_MPLL0_DP")
	)
	(segment
		(start 106.81716 -54.1274)
		(end 107.2388 -54.1274)
		(width 0.1016)
		(layer "F.Cu")
		(net "CLK_100M_CPU_MPLL0_DP")
	)
	(segment
		(start 107.7087 -54.5973)
		(end 107.7087 -56.866028)
		(width 0.1016)
		(layer "F.Cu")
		(net "CLK_100M_CPU_MPLL0_DP")
	)
	(segment
		(start 101.8794 -59.1439)
		(end 100.134166 -60.889134)
		(width 0.1397)
		(layer "F.Cu")
		(net "CLK_100M_CPU_MPLL0_DP")
	)
	(segment
		(start 106.540808 -51.839114)
		(end 106.540808 -52.072032)
		(width 0.1016)
		(layer "F.Cu")
		(net "CLK_100M_CPU_MPLL0_DP")
	)
	(segment
		(start 106.37266 -53.265324)
		(end 106.37266 -53.6829)
		(width 0.1016)
		(layer "F.Cu")
		(net "CLK_100M_CPU_MPLL0_DP")
	)
	(segment
		(start 106.672888 -52.965096)
		(end 106.37266 -53.265324)
		(width 0.1016)
		(layer "F.Cu")
		(net "CLK_100M_CPU_MPLL0_DP")
	)
	(segment
		(start 107.2388 -54.1274)
		(end 107.7087 -54.5973)
		(width 0.1016)
		(layer "F.Cu")
		(net "CLK_100M_CPU_MPLL0_DP")
	)
	(via
		(at 50.658014 -47.636938)
		(size 0.508)
		(drill 0.254)
		(layers "F.Cu" "B.Cu")
		(net "CLK_100M_CPU_MPLL0_DP")
	)
	(via
		(at 100.134166 -61.246512)
		(size 0.508)
		(drill 0.254)
		(layers "F.Cu" "B.Cu")
		(net "CLK_100M_CPU_MPLL0_DP")
	)
	(segment
		(start 48.668178 -47.897288)
		(end 48.693578 -47.922688)
		(width 0.1397)
		(layer "B.Cu")
		(net "CLK_100M_CPU_MPLL0_DP")
	)
	(segment
		(start 50.372264 -47.922688)
		(end 50.658014 -47.636938)
		(width 0.1397)
		(layer "B.Cu")
		(net "CLK_100M_CPU_MPLL0_DP")
	)
	(segment
		(start 48.693578 -47.922688)
		(end 50.372264 -47.922688)
		(width 0.1397)
		(layer "B.Cu")
		(net "CLK_100M_CPU_MPLL0_DP")
	)
	(segment
		(start 93.596206 -58.4962)
		(end 94.605094 -58.4962)
		(width 0.1143)
		(layer "In9.Cu")
		(net "CLK_100M_CPU_MPLL0_DP")
	)
	(segment
		(start 89.748106 -62.3443)
		(end 93.596206 -58.4962)
		(width 0.1143)
		(layer "In9.Cu")
		(net "CLK_100M_CPU_MPLL0_DP")
	)
	(segment
		(start 50.658014 -47.636938)
		(end 50.359564 -47.935388)
		(width 0.1143)
		(layer "In9.Cu")
		(net "CLK_100M_CPU_MPLL0_DP")
	)
	(segment
		(start 96.431354 -61.722)
		(end 99.273106 -61.722)
		(width 0.1143)
		(layer "In9.Cu")
		(net "CLK_100M_CPU_MPLL0_DP")
	)
	(segment
		(start 49.514506 -47.935388)
		(end 48.83785 -48.612044)
		(width 0.1143)
		(layer "In9.Cu")
		(net "CLK_100M_CPU_MPLL0_DP")
	)
	(segment
		(start 48.83785 -49.381156)
		(end 49.824894 -50.3682)
		(width 0.1143)
		(layer "In9.Cu")
		(net "CLK_100M_CPU_MPLL0_DP")
	)
	(segment
		(start 55.965344 -54.27345)
		(end 57.158636 -54.27345)
		(width 0.1143)
		(layer "In9.Cu")
		(net "CLK_100M_CPU_MPLL0_DP")
	)
	(segment
		(start 61.044836 -58.15965)
		(end 65.127632 -58.15965)
		(width 0.1143)
		(layer "In9.Cu")
		(net "CLK_100M_CPU_MPLL0_DP")
	)
	(segment
		(start 52.060094 -50.3682)
		(end 55.965344 -54.27345)
		(width 0.1143)
		(layer "In9.Cu")
		(net "CLK_100M_CPU_MPLL0_DP")
	)
	(segment
		(start 95.5548 -60.845446)
		(end 96.431354 -61.722)
		(width 0.1143)
		(layer "In9.Cu")
		(net "CLK_100M_CPU_MPLL0_DP")
	)
	(segment
		(start 50.359564 -47.935388)
		(end 49.514506 -47.935388)
		(width 0.1143)
		(layer "In9.Cu")
		(net "CLK_100M_CPU_MPLL0_DP")
	)
	(segment
		(start 65.127632 -58.15965)
		(end 69.312282 -62.3443)
		(width 0.1143)
		(layer "In9.Cu")
		(net "CLK_100M_CPU_MPLL0_DP")
	)
	(segment
		(start 49.824894 -50.3682)
		(end 52.060094 -50.3682)
		(width 0.1143)
		(layer "In9.Cu")
		(net "CLK_100M_CPU_MPLL0_DP")
	)
	(segment
		(start 94.605094 -58.4962)
		(end 95.5548 -59.445906)
		(width 0.1143)
		(layer "In9.Cu")
		(net "CLK_100M_CPU_MPLL0_DP")
	)
	(segment
		(start 57.158636 -54.27345)
		(end 61.044836 -58.15965)
		(width 0.1143)
		(layer "In9.Cu")
		(net "CLK_100M_CPU_MPLL0_DP")
	)
	(segment
		(start 48.83785 -48.612044)
		(end 48.83785 -49.381156)
		(width 0.1143)
		(layer "In9.Cu")
		(net "CLK_100M_CPU_MPLL0_DP")
	)
	(segment
		(start 99.273106 -61.722)
		(end 99.748594 -61.246512)
		(width 0.1143)
		(layer "In9.Cu")
		(net "CLK_100M_CPU_MPLL0_DP")
	)
	(segment
		(start 99.748594 -61.246512)
		(end 100.134166 -61.246512)
		(width 0.1143)
		(layer "In9.Cu")
		(net "CLK_100M_CPU_MPLL0_DP")
	)
	(segment
		(start 69.312282 -62.3443)
		(end 89.748106 -62.3443)
		(width 0.1143)
		(layer "In9.Cu")
		(net "CLK_100M_CPU_MPLL0_DP")
	)
	(segment
		(start 95.5548 -59.445906)
		(end 95.5548 -60.845446)
		(width 0.1143)
		(layer "In9.Cu")
		(net "CLK_100M_CPU_MPLL0_DP")
	)
	(segment
		(start 137.649966 -62.59322)
		(end 137.649966 -63.683896)
		(width 0.1778)
		(layer "F.Cu")
		(net "M_A_DQ49")
	)
	(segment
		(start 100.9904 -56.4896)
		(end 100.4824 -56.9976)
		(width 0.1016)
		(layer "F.Cu")
		(net "M_A_DQ49")
	)
	(segment
		(start 100.9904 -53.721)
		(end 100.9904 -56.4896)
		(width 0.1016)
		(layer "F.Cu")
		(net "M_A_DQ49")
	)
	(segment
		(start 137.8204 -64.26327)
		(end 137.41527 -64.6684)
		(width 0.1778)
		(layer "F.Cu")
		(net "M_A_DQ49")
	)
	(segment
		(start 137.649966 -63.683896)
		(end 137.8204 -63.85433)
		(width 0.1778)
		(layer "F.Cu")
		(net "M_A_DQ49")
	)
	(segment
		(start 137.8204 -63.85433)
		(end 137.8204 -64.26327)
		(width 0.1778)
		(layer "F.Cu")
		(net "M_A_DQ49")
	)
	(segment
		(start 100.249228 -52.448714)
		(end 100.249228 -52.979828)
		(width 0.1016)
		(layer "F.Cu")
		(net "M_A_DQ49")
	)
	(segment
		(start 100.249228 -52.979828)
		(end 100.9904 -53.721)
		(width 0.1016)
		(layer "F.Cu")
		(net "M_A_DQ49")
	)
	(segment
		(start 137.41527 -64.6684)
		(end 137.41527 -64.7192)
		(width 0.1778)
		(layer "F.Cu")
		(net "M_A_DQ49")
	)
	(via
		(at 100.4824 -56.9976)
		(size 0.4318)
		(drill 0.2032)
		(layers "F.Cu" "B.Cu")
		(net "M_A_DQ49")
	)
	(via
		(at 137.41527 -64.7192)
		(size 0.4318)
		(drill 0.2032)
		(layers "F.Cu" "B.Cu")
		(net "M_A_DQ49")
	)
	(segment
		(start 137.94994 -63.52286)
		(end 137.8204 -63.6524)
		(width 0.1778)
		(layer "B.Cu")
		(net "M_A_DQ49")
	)
	(segment
		(start 137.94994 -62.599824)
		(end 137.94994 -63.52286)
		(width 0.1778)
		(layer "B.Cu")
		(net "M_A_DQ49")
	)
	(segment
		(start 137.8204 -63.6524)
		(end 137.8204 -64.31407)
		(width 0.1778)
		(layer "B.Cu")
		(net "M_A_DQ49")
	)
	(segment
		(start 137.8204 -64.31407)
		(end 137.41527 -64.7192)
		(width 0.1778)
		(layer "B.Cu")
		(net "M_A_DQ49")
	)
	(segment
		(start 114.9858 -64.7954)
		(end 114.9858 -65.13195)
		(width 0.1524)
		(layer "In4.Cu")
		(net "M_A_DQ49")
	)
	(segment
		(start 114.223546 -64.008254)
		(end 114.719608 -64.008254)
		(width 0.1524)
		(layer "In4.Cu")
		(net "M_A_DQ49")
	)
	(segment
		(start 102.355904 -59.8678)
		(end 103.946452 -61.458348)
		(width 0.1524)
		(layer "In4.Cu")
		(net "M_A_DQ49")
	)
	(segment
		(start 115.1382 -64.643)
		(end 114.9858 -64.7954)
		(width 0.1524)
		(layer "In4.Cu")
		(net "M_A_DQ49")
	)
	(segment
		(start 114.719608 -64.008254)
		(end 114.719862 -64.008)
		(width 0.1524)
		(layer "In4.Cu")
		(net "M_A_DQ49")
	)
	(segment
		(start 102.108 -59.8678)
		(end 102.355904 -59.8678)
		(width 0.1524)
		(layer "In4.Cu")
		(net "M_A_DQ49")
	)
	(segment
		(start 108.257086 -64.008)
		(end 109.552486 -65.3034)
		(width 0.1524)
		(layer "In4.Cu")
		(net "M_A_DQ49")
	)
	(segment
		(start 104.484424 -62.013846)
		(end 104.484424 -63.539624)
		(width 0.1524)
		(layer "In4.Cu")
		(net "M_A_DQ49")
	)
	(segment
		(start 116.459 -64.643)
		(end 115.1382 -64.643)
		(width 0.1524)
		(layer "In4.Cu")
		(net "M_A_DQ49")
	)
	(segment
		(start 115.15725 -65.3034)
		(end 117.560852 -65.3034)
		(width 0.1524)
		(layer "In4.Cu")
		(net "M_A_DQ49")
	)
	(segment
		(start 114.0714 -65.151)
		(end 114.0714 -64.1604)
		(width 0.1524)
		(layer "In4.Cu")
		(net "M_A_DQ49")
	)
	(segment
		(start 103.946452 -61.475874)
		(end 104.484424 -62.013846)
		(width 0.1524)
		(layer "In4.Cu")
		(net "M_A_DQ49")
	)
	(segment
		(start 115.4176 -63.5762)
		(end 115.57 -63.4238)
		(width 0.1524)
		(layer "In4.Cu")
		(net "M_A_DQ49")
	)
	(segment
		(start 116.459 -63.4238)
		(end 116.6114 -63.5762)
		(width 0.1524)
		(layer "In4.Cu")
		(net "M_A_DQ49")
	)
	(segment
		(start 104.9528 -64.008)
		(end 108.257086 -64.008)
		(width 0.1524)
		(layer "In4.Cu")
		(net "M_A_DQ49")
	)
	(segment
		(start 114.0714 -64.1604)
		(end 114.223546 -64.008254)
		(width 0.1524)
		(layer "In4.Cu")
		(net "M_A_DQ49")
	)
	(segment
		(start 115.2652 -64.008)
		(end 115.4176 -63.8556)
		(width 0.1524)
		(layer "In4.Cu")
		(net "M_A_DQ49")
	)
	(segment
		(start 135.644636 -61.6966)
		(end 137.8839 -63.935864)
		(width 0.1524)
		(layer "In4.Cu")
		(net "M_A_DQ49")
	)
	(segment
		(start 109.552486 -65.3034)
		(end 113.919 -65.3034)
		(width 0.1524)
		(layer "In4.Cu")
		(net "M_A_DQ49")
	)
	(segment
		(start 116.6114 -64.4906)
		(end 116.459 -64.643)
		(width 0.1524)
		(layer "In4.Cu")
		(net "M_A_DQ49")
	)
	(segment
		(start 115.4176 -63.8556)
		(end 115.4176 -63.5762)
		(width 0.1524)
		(layer "In4.Cu")
		(net "M_A_DQ49")
	)
	(segment
		(start 116.6114 -63.5762)
		(end 116.6114 -64.4906)
		(width 0.1524)
		(layer "In4.Cu")
		(net "M_A_DQ49")
	)
	(segment
		(start 137.8839 -63.935864)
		(end 137.8839 -64.2493)
		(width 0.1524)
		(layer "In4.Cu")
		(net "M_A_DQ49")
	)
	(segment
		(start 137.41527 -64.71793)
		(end 137.41527 -64.7192)
		(width 0.1524)
		(layer "In4.Cu")
		(net "M_A_DQ49")
	)
	(segment
		(start 115.57 -63.4238)
		(end 116.459 -63.4238)
		(width 0.1524)
		(layer "In4.Cu")
		(net "M_A_DQ49")
	)
	(segment
		(start 100.4824 -56.9976)
		(end 100.4824 -58.2422)
		(width 0.1524)
		(layer "In4.Cu")
		(net "M_A_DQ49")
	)
	(segment
		(start 114.719862 -64.008)
		(end 115.2652 -64.008)
		(width 0.1524)
		(layer "In4.Cu")
		(net "M_A_DQ49")
	)
	(segment
		(start 104.484424 -63.539624)
		(end 104.9528 -64.008)
		(width 0.1524)
		(layer "In4.Cu")
		(net "M_A_DQ49")
	)
	(segment
		(start 103.946452 -61.458348)
		(end 103.946452 -61.475874)
		(width 0.1524)
		(layer "In4.Cu")
		(net "M_A_DQ49")
	)
	(segment
		(start 100.4824 -58.2422)
		(end 102.108 -59.8678)
		(width 0.1524)
		(layer "In4.Cu")
		(net "M_A_DQ49")
	)
	(segment
		(start 121.167652 -61.6966)
		(end 135.644636 -61.6966)
		(width 0.1524)
		(layer "In4.Cu")
		(net "M_A_DQ49")
	)
	(segment
		(start 114.9858 -65.13195)
		(end 115.15725 -65.3034)
		(width 0.1524)
		(layer "In4.Cu")
		(net "M_A_DQ49")
	)
	(segment
		(start 137.8839 -64.2493)
		(end 137.41527 -64.71793)
		(width 0.1524)
		(layer "In4.Cu")
		(net "M_A_DQ49")
	)
	(segment
		(start 113.919 -65.3034)
		(end 114.0714 -65.151)
		(width 0.1524)
		(layer "In4.Cu")
		(net "M_A_DQ49")
	)
	(segment
		(start 117.560852 -65.3034)
		(end 121.167652 -61.6966)
		(width 0.1524)
		(layer "In4.Cu")
		(net "M_A_DQ49")
	)
	(segment
		(start 118.745 -48.5902)
		(end 114.910362 -48.5902)
		(width 0.1016)
		(layer "F.Cu")
		(net "M_A_ECC0")
	)
	(segment
		(start 119.253 -48.0822)
		(end 118.745 -48.5902)
		(width 0.1016)
		(layer "F.Cu")
		(net "M_A_ECC0")
	)
	(segment
		(start 119.253 -48.006)
		(end 119.253 -48.0822)
		(width 0.1016)
		(layer "F.Cu")
		(net "M_A_ECC0")
	)
	(segment
		(start 168.850056 -62.59322)
		(end 168.850056 -63.105284)
		(width 0.1778)
		(layer "F.Cu")
		(net "M_A_ECC0")
	)
	(segment
		(start 112.282224 -45.962824)
		(end 111.111538 -45.962824)
		(width 0.1016)
		(layer "F.Cu")
		(net "M_A_ECC0")
	)
	(segment
		(start 168.850056 -63.105284)
		(end 168.59758 -63.35776)
		(width 0.1778)
		(layer "F.Cu")
		(net "M_A_ECC0")
	)
	(segment
		(start 114.342164 -48.022764)
		(end 112.282224 -45.962824)
		(width 0.1016)
		(layer "F.Cu")
		(net "M_A_ECC0")
	)
	(segment
		(start 168.59758 -63.35776)
		(end 168.59758 -63.616586)
		(width 0.1778)
		(layer "F.Cu")
		(net "M_A_ECC0")
	)
	(segment
		(start 114.910362 -48.5902)
		(end 114.342164 -48.022764)
		(width 0.1016)
		(layer "F.Cu")
		(net "M_A_ECC0")
	)
	(segment
		(start 111.111538 -45.962824)
		(end 110.749588 -45.600874)
		(width 0.1016)
		(layer "F.Cu")
		(net "M_A_ECC0")
	)
	(segment
		(start 168.59758 -63.616586)
		(end 169.037 -64.056006)
		(width 0.1778)
		(layer "F.Cu")
		(net "M_A_ECC0")
	)
	(via
		(at 119.253 -48.006)
		(size 0.4318)
		(drill 0.2032)
		(layers "F.Cu" "B.Cu")
		(net "M_A_ECC0")
	)
	(via
		(at 169.037 -64.056006)
		(size 0.4318)
		(drill 0.2032)
		(layers "F.Cu" "B.Cu")
		(net "M_A_ECC0")
	)
	(segment
		(start 169.749978 -63.581026)
		(end 169.274998 -64.056006)
		(width 0.1778)
		(layer "B.Cu")
		(net "M_A_ECC0")
	)
	(segment
		(start 169.749978 -62.599824)
		(end 169.749978 -63.581026)
		(width 0.1778)
		(layer "B.Cu")
		(net "M_A_ECC0")
	)
	(segment
		(start 169.274998 -64.056006)
		(end 169.037 -64.056006)
		(width 0.1778)
		(layer "B.Cu")
		(net "M_A_ECC0")
	)
	(segment
		(start 148.5646 -54.737)
		(end 148.3614 -54.5338)
		(width 0.1524)
		(layer "In2.Cu")
		(net "M_A_ECC0")
	)
	(segment
		(start 150.95474 -54.2798)
		(end 150.95474 -54.5846)
		(width 0.1524)
		(layer "In2.Cu")
		(net "M_A_ECC0")
	)
	(segment
		(start 169.037 -64.056006)
		(end 168.6306 -64.056006)
		(width 0.1524)
		(layer "In2.Cu")
		(net "M_A_ECC0")
	)
	(segment
		(start 151.71674 -54.737)
		(end 151.56434 -54.5846)
		(width 0.1524)
		(layer "In2.Cu")
		(net "M_A_ECC0")
	)
	(segment
		(start 144.11325 -49.216056)
		(end 120.590056 -49.216056)
		(width 0.1524)
		(layer "In2.Cu")
		(net "M_A_ECC0")
	)
	(segment
		(start 149.73554 -54.2798)
		(end 149.73554 -54.5846)
		(width 0.1524)
		(layer "In2.Cu")
		(net "M_A_ECC0")
	)
	(segment
		(start 149.88794 -54.1274)
		(end 149.73554 -54.2798)
		(width 0.1524)
		(layer "In2.Cu")
		(net "M_A_ECC0")
	)
	(segment
		(start 149.58314 -54.737)
		(end 148.5646 -54.737)
		(width 0.1524)
		(layer "In2.Cu")
		(net "M_A_ECC0")
	)
	(segment
		(start 151.10714 -54.1274)
		(end 150.95474 -54.2798)
		(width 0.1524)
		(layer "In2.Cu")
		(net "M_A_ECC0")
	)
	(segment
		(start 147.93722 -51.54422)
		(end 147.93722 -51.008534)
		(width 0.1524)
		(layer "In2.Cu")
		(net "M_A_ECC0")
	)
	(segment
		(start 150.49754 -54.737)
		(end 150.34514 -54.5846)
		(width 0.1524)
		(layer "In2.Cu")
		(net "M_A_ECC0")
	)
	(segment
		(start 120.590056 -49.216056)
		(end 119.38 -48.006)
		(width 0.1016)
		(layer "In2.Cu")
		(net "M_A_ECC0")
	)
	(segment
		(start 168.4782 -64.208406)
		(end 168.4782 -64.77)
		(width 0.1524)
		(layer "In2.Cu")
		(net "M_A_ECC0")
	)
	(segment
		(start 150.34514 -54.5846)
		(end 150.34514 -54.2798)
		(width 0.1524)
		(layer "In2.Cu")
		(net "M_A_ECC0")
	)
	(segment
		(start 151.56434 -54.2798)
		(end 151.41194 -54.1274)
		(width 0.1524)
		(layer "In2.Cu")
		(net "M_A_ECC0")
	)
	(segment
		(start 148.3614 -54.5338)
		(end 148.3614 -53.3146)
		(width 0.1524)
		(layer "In2.Cu")
		(net "M_A_ECC0")
	)
	(segment
		(start 150.34514 -54.2798)
		(end 150.19274 -54.1274)
		(width 0.1524)
		(layer "In2.Cu")
		(net "M_A_ECC0")
	)
	(segment
		(start 146.507708 -50.0634)
		(end 145.8976 -50.673)
		(width 0.1524)
		(layer "In2.Cu")
		(net "M_A_ECC0")
	)
	(segment
		(start 167.6781 -64.9224)
		(end 167.5257 -64.77)
		(width 0.1524)
		(layer "In2.Cu")
		(net "M_A_ECC0")
	)
	(segment
		(start 167.005 -60.833)
		(end 160.655 -54.483)
		(width 0.1524)
		(layer "In2.Cu")
		(net "M_A_ECC0")
	)
	(segment
		(start 167.005 -62.7634)
		(end 167.005 -60.833)
		(width 0.1524)
		(layer "In2.Cu")
		(net "M_A_ECC0")
	)
	(segment
		(start 148.3614 -53.3146)
		(end 148.8567 -52.8193)
		(width 0.1524)
		(layer "In2.Cu")
		(net "M_A_ECC0")
	)
	(segment
		(start 148.8567 -52.8193)
		(end 148.8567 -52.4637)
		(width 0.1524)
		(layer "In2.Cu")
		(net "M_A_ECC0")
	)
	(segment
		(start 168.3258 -64.9224)
		(end 167.6781 -64.9224)
		(width 0.1524)
		(layer "In2.Cu")
		(net "M_A_ECC0")
	)
	(segment
		(start 150.95474 -54.5846)
		(end 150.80234 -54.737)
		(width 0.1524)
		(layer "In2.Cu")
		(net "M_A_ECC0")
	)
	(segment
		(start 167.5257 -64.77)
		(end 167.5257 -63.2841)
		(width 0.1524)
		(layer "In2.Cu")
		(net "M_A_ECC0")
	)
	(segment
		(start 149.73554 -54.5846)
		(end 149.58314 -54.737)
		(width 0.1524)
		(layer "In2.Cu")
		(net "M_A_ECC0")
	)
	(segment
		(start 168.4782 -64.77)
		(end 168.3258 -64.9224)
		(width 0.1524)
		(layer "In2.Cu")
		(net "M_A_ECC0")
	)
	(segment
		(start 167.5257 -63.2841)
		(end 167.005 -62.7634)
		(width 0.1524)
		(layer "In2.Cu")
		(net "M_A_ECC0")
	)
	(segment
		(start 148.8567 -52.4637)
		(end 147.93722 -51.54422)
		(width 0.1524)
		(layer "In2.Cu")
		(net "M_A_ECC0")
	)
	(segment
		(start 153.87955 -54.483)
		(end 153.625296 -54.737)
		(width 0.1524)
		(layer "In2.Cu")
		(net "M_A_ECC0")
	)
	(segment
		(start 151.41194 -54.1274)
		(end 151.10714 -54.1274)
		(width 0.1524)
		(layer "In2.Cu")
		(net "M_A_ECC0")
	)
	(segment
		(start 146.992086 -50.0634)
		(end 146.507708 -50.0634)
		(width 0.1524)
		(layer "In2.Cu")
		(net "M_A_ECC0")
	)
	(segment
		(start 153.625296 -54.737)
		(end 151.71674 -54.737)
		(width 0.1524)
		(layer "In2.Cu")
		(net "M_A_ECC0")
	)
	(segment
		(start 151.56434 -54.5846)
		(end 151.56434 -54.2798)
		(width 0.1524)
		(layer "In2.Cu")
		(net "M_A_ECC0")
	)
	(segment
		(start 147.93722 -51.008534)
		(end 146.992086 -50.0634)
		(width 0.1524)
		(layer "In2.Cu")
		(net "M_A_ECC0")
	)
	(segment
		(start 145.570194 -50.673)
		(end 144.11325 -49.216056)
		(width 0.1524)
		(layer "In2.Cu")
		(net "M_A_ECC0")
	)
	(segment
		(start 145.8976 -50.673)
		(end 145.570194 -50.673)
		(width 0.1524)
		(layer "In2.Cu")
		(net "M_A_ECC0")
	)
	(segment
		(start 160.655 -54.483)
		(end 153.87955 -54.483)
		(width 0.1524)
		(layer "In2.Cu")
		(net "M_A_ECC0")
	)
	(segment
		(start 119.38 -48.006)
		(end 119.253 -48.006)
		(width 0.1016)
		(layer "In2.Cu")
		(net "M_A_ECC0")
	)
	(segment
		(start 150.19274 -54.1274)
		(end 149.88794 -54.1274)
		(width 0.1524)
		(layer "In2.Cu")
		(net "M_A_ECC0")
	)
	(segment
		(start 168.6306 -64.056006)
		(end 168.4782 -64.208406)
		(width 0.1524)
		(layer "In2.Cu")
		(net "M_A_ECC0")
	)
	(segment
		(start 150.80234 -54.737)
		(end 150.49754 -54.737)
		(width 0.1524)
		(layer "In2.Cu")
		(net "M_A_ECC0")
	)
	(segment
		(start 40.7416 -49.784)
		(end 39.116 -49.784)
		(width 0.508)
		(layer "F.Cu")
		(net "P3V3_CLK_R_PCI")
	)
	(segment
		(start 40.767 -49.7586)
		(end 40.7416 -49.784)
		(width 0.508)
		(layer "F.Cu")
		(net "P3V3_CLK_R_PCI")
	)
	(segment
		(start 37.9984 -49.784)
		(end 39.116 -49.784)
		(width 0.508)
		(layer "F.Cu")
		(net "P3V3_CLK_R_PCI")
	)
	(via
		(at 39.116 -49.784)
		(size 0.7112)
		(drill 0.3556)
		(layers "F.Cu" "B.Cu")
		(net "P3V3_CLK_R_PCI")
	)
	(segment
		(start 158.224728 -63.65494)
		(end 158.224728 -66.087752)
		(width 0.2413)
		(layer "F.Cu")
		(net "M_A_MA6")
	)
	(segment
		(start 158.049976 -62.59322)
		(end 158.049976 -63.480188)
		(width 0.2413)
		(layer "F.Cu")
		(net "M_A_MA6")
	)
	(segment
		(start 158.049976 -63.480188)
		(end 158.224728 -63.65494)
		(width 0.2413)
		(layer "F.Cu")
		(net "M_A_MA6")
	)
	(segment
		(start 158.224728 -66.087752)
		(end 158.224982 -66.088006)
		(width 0.2413)
		(layer "F.Cu")
		(net "M_A_MA6")
	)
	(segment
		(start 107.226608 -48.059594)
		(end 107.671108 -47.615094)
		(width 0.1016)
		(layer "F.Cu")
		(net "M_A_MA6")
	)
	(segment
		(start 107.226608 -48.1584)
		(end 107.226608 -48.059594)
		(width 0.1016)
		(layer "F.Cu")
		(net "M_A_MA6")
	)
	(via
		(at 158.224982 -66.088006)
		(size 0.4318)
		(drill 0.2032)
		(layers "F.Cu" "B.Cu")
		(net "M_A_MA6")
	)
	(via
		(at 107.226608 -48.1584)
		(size 0.4318)
		(drill 0.2032)
		(layers "F.Cu" "B.Cu")
		(net "M_A_MA6")
	)
	(segment
		(start 158.092648 -69.618352)
		(end 158.092648 -67.973448)
		(width 0.2413)
		(layer "B.Cu")
		(net "M_A_MA6")
	)
	(segment
		(start 157.74797 -67.62877)
		(end 157.74797 -66.525648)
		(width 0.2413)
		(layer "B.Cu")
		(net "M_A_MA6")
	)
	(segment
		(start 158.049976 -69.661024)
		(end 158.092648 -69.618352)
		(width 0.2413)
		(layer "B.Cu")
		(net "M_A_MA6")
	)
	(segment
		(start 158.092648 -67.973448)
		(end 157.74797 -67.62877)
		(width 0.2413)
		(layer "B.Cu")
		(net "M_A_MA6")
	)
	(segment
		(start 157.74797 -66.525648)
		(end 158.185612 -66.088006)
		(width 0.2413)
		(layer "B.Cu")
		(net "M_A_MA6")
	)
	(segment
		(start 158.049976 -70.79996)
		(end 158.049976 -69.661024)
		(width 0.2413)
		(layer "B.Cu")
		(net "M_A_MA6")
	)
	(segment
		(start 158.185612 -66.088006)
		(end 158.224982 -66.088006)
		(width 0.2413)
		(layer "B.Cu")
		(net "M_A_MA6")
	)
	(segment
		(start 108.478828 -50.395378)
		(end 110.28045 -52.197)
		(width 0.1016)
		(layer "In9.Cu")
		(net "M_A_MA6")
	)
	(segment
		(start 156.834586 -61.416438)
		(end 157.9118 -62.493652)
		(width 0.1905)
		(layer "In9.Cu")
		(net "M_A_MA6")
	)
	(segment
		(start 144.32915 -52.0446)
		(end 148.541486 -52.0446)
		(width 0.1905)
		(layer "In9.Cu")
		(net "M_A_MA6")
	)
	(segment
		(start 153.029666 -56.53278)
		(end 153.303986 -56.53278)
		(width 0.1905)
		(layer "In9.Cu")
		(net "M_A_MA6")
	)
	(segment
		(start 156.18714 -60.10275)
		(end 156.474922 -60.10275)
		(width 0.1905)
		(layer "In9.Cu")
		(net "M_A_MA6")
	)
	(segment
		(start 107.226608 -48.553878)
		(end 108.478828 -49.806098)
		(width 0.1016)
		(layer "In9.Cu")
		(net "M_A_MA6")
	)
	(segment
		(start 117.4115 -52.1589)
		(end 118.05285 -51.51755)
		(width 0.1905)
		(layer "In9.Cu")
		(net "M_A_MA6")
	)
	(segment
		(start 156.834586 -60.462414)
		(end 156.834586 -61.416438)
		(width 0.1905)
		(layer "In9.Cu")
		(net "M_A_MA6")
	)
	(segment
		(start 153.303986 -56.53278)
		(end 154.47645 -57.705244)
		(width 0.1905)
		(layer "In9.Cu")
		(net "M_A_MA6")
	)
	(segment
		(start 118.05285 -51.51755)
		(end 143.8021 -51.51755)
		(width 0.1905)
		(layer "In9.Cu")
		(net "M_A_MA6")
	)
	(segment
		(start 158.224728 -66.087752)
		(end 158.224982 -66.088006)
		(width 0.1905)
		(layer "In9.Cu")
		(net "M_A_MA6")
	)
	(segment
		(start 154.47645 -57.705244)
		(end 154.47645 -58.39206)
		(width 0.1905)
		(layer "In9.Cu")
		(net "M_A_MA6")
	)
	(segment
		(start 112.1156 -52.197)
		(end 112.1537 -52.1589)
		(width 0.1016)
		(layer "In9.Cu")
		(net "M_A_MA6")
	)
	(segment
		(start 112.1537 -52.1589)
		(end 117.4115 -52.1589)
		(width 0.1905)
		(layer "In9.Cu")
		(net "M_A_MA6")
	)
	(segment
		(start 157.9118 -65.2526)
		(end 158.224728 -65.565528)
		(width 0.1905)
		(layer "In9.Cu")
		(net "M_A_MA6")
	)
	(segment
		(start 110.28045 -52.197)
		(end 112.1156 -52.197)
		(width 0.1016)
		(layer "In9.Cu")
		(net "M_A_MA6")
	)
	(segment
		(start 156.474922 -60.10275)
		(end 156.834586 -60.462414)
		(width 0.1905)
		(layer "In9.Cu")
		(net "M_A_MA6")
	)
	(segment
		(start 154.47645 -58.39206)
		(end 156.18714 -60.10275)
		(width 0.1905)
		(layer "In9.Cu")
		(net "M_A_MA6")
	)
	(segment
		(start 107.226608 -48.1584)
		(end 107.226608 -48.553878)
		(width 0.1016)
		(layer "In9.Cu")
		(net "M_A_MA6")
	)
	(segment
		(start 157.9118 -62.493652)
		(end 157.9118 -65.2526)
		(width 0.1905)
		(layer "In9.Cu")
		(net "M_A_MA6")
	)
	(segment
		(start 143.8021 -51.51755)
		(end 144.32915 -52.0446)
		(width 0.1905)
		(layer "In9.Cu")
		(net "M_A_MA6")
	)
	(segment
		(start 158.224728 -65.565528)
		(end 158.224728 -66.087752)
		(width 0.1905)
		(layer "In9.Cu")
		(net "M_A_MA6")
	)
	(segment
		(start 108.478828 -49.806098)
		(end 108.478828 -50.395378)
		(width 0.1016)
		(layer "In9.Cu")
		(net "M_A_MA6")
	)
	(segment
		(start 148.541486 -52.0446)
		(end 153.029666 -56.53278)
		(width 0.1905)
		(layer "In9.Cu")
		(net "M_A_MA6")
	)
	(via
		(at 41.5544 -46.887638)
		(size 0.7112)
		(drill 0.3556)
		(layers "F.Cu" "B.Cu")
		(net "XTAL_CLK_GEN_IN")
	)
	(segment
		(start 41.76395 -47.097188)
		(end 43.04919 -47.097188)
		(width 0.1143)
		(layer "B.Cu")
		(net "XTAL_CLK_GEN_IN")
	)
	(segment
		(start 41.3512 -46.2788)
		(end 40.3352 -45.2628)
		(width 0.1143)
		(layer "B.Cu")
		(net "XTAL_CLK_GEN_IN")
	)
	(segment
		(start 41.3512 -46.684438)
		(end 41.3512 -46.2788)
		(width 0.1143)
		(layer "B.Cu")
		(net "XTAL_CLK_GEN_IN")
	)
	(segment
		(start 41.5544 -46.887638)
		(end 41.3512 -46.684438)
		(width 0.1143)
		(layer "B.Cu")
		(net "XTAL_CLK_GEN_IN")
	)
	(segment
		(start 37.547296 -44.8818)
		(end 35.941 -46.488096)
		(width 0.1143)
		(layer "B.Cu")
		(net "XTAL_CLK_GEN_IN")
	)
	(segment
		(start 41.5544 -46.887638)
		(end 41.76395 -47.097188)
		(width 0.1143)
		(layer "B.Cu")
		(net "XTAL_CLK_GEN_IN")
	)
	(segment
		(start 38.227 -44.8818)
		(end 37.547296 -44.8818)
		(width 0.1143)
		(layer "B.Cu")
		(net "XTAL_CLK_GEN_IN")
	)
	(segment
		(start 38.608 -45.2628)
		(end 38.227 -44.8818)
		(width 0.1143)
		(layer "B.Cu")
		(net "XTAL_CLK_GEN_IN")
	)
	(segment
		(start 40.3352 -45.2628)
		(end 38.608 -45.2628)
		(width 0.1143)
		(layer "B.Cu")
		(net "XTAL_CLK_GEN_IN")
	)
	(segment
		(start 3.8862 -47.0408)
		(end 2.7432 -48.1838)
		(width 0.1397)
		(layer "B.Cu")
		(net "CLK_100M_CLKBUFF_NGFF_DP")
	)
	(segment
		(start 19.888962 -43.39336)
		(end 19.469862 -43.39336)
		(width 0.1397)
		(layer "B.Cu")
		(net "CLK_100M_CLKBUFF_NGFF_DP")
	)
	(segment
		(start 13.3096 -46.3296)
		(end 12.5984 -47.0408)
		(width 0.1397)
		(layer "B.Cu")
		(net "CLK_100M_CLKBUFF_NGFF_DP")
	)
	(segment
		(start 2.94386 -51.03622)
		(end 2.94386 -51.45532)
		(width 0.1397)
		(layer "B.Cu")
		(net "CLK_100M_CLKBUFF_NGFF_DP")
	)
	(segment
		(start 26.20645 -39.40175)
		(end 22.4155 -43.1927)
		(width 0.1397)
		(layer "B.Cu")
		(net "CLK_100M_CLKBUFF_NGFF_DP")
	)
	(segment
		(start 35.56 -36.12134)
		(end 34.31159 -37.36975)
		(width 0.1397)
		(layer "B.Cu")
		(net "CLK_100M_CLKBUFF_NGFF_DP")
	)
	(segment
		(start 37.2872 -23.495)
		(end 36.5252 -23.495)
		(width 0.1397)
		(layer "B.Cu")
		(net "CLK_100M_CLKBUFF_NGFF_DP")
	)
	(segment
		(start 2.94386 -52.27574)
		(end 2.94386 -52.69484)
		(width 0.1397)
		(layer "B.Cu")
		(net "CLK_100M_CLKBUFF_NGFF_DP")
	)
	(segment
		(start 12.5984 -47.0408)
		(end 3.8862 -47.0408)
		(width 0.1397)
		(layer "B.Cu")
		(net "CLK_100M_CLKBUFF_NGFF_DP")
	)
	(segment
		(start 3.660648 -53.94833)
		(end 3.660648 -54.232048)
		(width 0.1397)
		(layer "B.Cu")
		(net "CLK_100M_CLKBUFF_NGFF_DP")
	)
	(segment
		(start 34.31159 -37.36975)
		(end 31.44139 -37.36975)
		(width 0.1397)
		(layer "B.Cu")
		(net "CLK_100M_CLKBUFF_NGFF_DP")
	)
	(segment
		(start 3.660648 -54.232048)
		(end 3.957066 -54.528466)
		(width 0.1397)
		(layer "B.Cu")
		(net "CLK_100M_CLKBUFF_NGFF_DP")
	)
	(segment
		(start 3.957066 -54.528466)
		(end 4.780534 -54.528466)
		(width 0.1397)
		(layer "B.Cu")
		(net "CLK_100M_CLKBUFF_NGFF_DP")
	)
	(segment
		(start 2.7432 -53.3146)
		(end 3.080512 -53.651912)
		(width 0.1397)
		(layer "B.Cu")
		(net "CLK_100M_CLKBUFF_NGFF_DP")
	)
	(segment
		(start 2.7432 -52.07508)
		(end 2.94386 -52.27574)
		(width 0.1397)
		(layer "B.Cu")
		(net "CLK_100M_CLKBUFF_NGFF_DP")
	)
	(segment
		(start 4.780534 -54.528466)
		(end 4.85902 -54.44998)
		(width 0.1397)
		(layer "B.Cu")
		(net "CLK_100M_CLKBUFF_NGFF_DP")
	)
	(segment
		(start 22.4155 -43.1927)
		(end 20.089622 -43.1927)
		(width 0.1397)
		(layer "B.Cu")
		(net "CLK_100M_CLKBUFF_NGFF_DP")
	)
	(segment
		(start 17.9959 -43.1927)
		(end 14.859 -46.3296)
		(width 0.1397)
		(layer "B.Cu")
		(net "CLK_100M_CLKBUFF_NGFF_DP")
	)
	(segment
		(start 36.195 -23.3172)
		(end 35.941 -23.3172)
		(width 0.1397)
		(layer "B.Cu")
		(net "CLK_100M_CLKBUFF_NGFF_DP")
	)
	(segment
		(start 31.44139 -37.36975)
		(end 29.40939 -39.40175)
		(width 0.1397)
		(layer "B.Cu")
		(net "CLK_100M_CLKBUFF_NGFF_DP")
	)
	(segment
		(start 36.5252 -23.495)
		(end 36.449 -23.5712)
		(width 0.1397)
		(layer "B.Cu")
		(net "CLK_100M_CLKBUFF_NGFF_DP")
	)
	(segment
		(start 2.7432 -48.1838)
		(end 2.7432 -50.83556)
		(width 0.1397)
		(layer "B.Cu")
		(net "CLK_100M_CLKBUFF_NGFF_DP")
	)
	(segment
		(start 36.449 -23.5712)
		(end 36.195 -23.3172)
		(width 0.1397)
		(layer "B.Cu")
		(net "CLK_100M_CLKBUFF_NGFF_DP")
	)
	(segment
		(start 2.7432 -50.83556)
		(end 2.94386 -51.03622)
		(width 0.1397)
		(layer "B.Cu")
		(net "CLK_100M_CLKBUFF_NGFF_DP")
	)
	(segment
		(start 2.7432 -51.65598)
		(end 2.7432 -52.07508)
		(width 0.1397)
		(layer "B.Cu")
		(net "CLK_100M_CLKBUFF_NGFF_DP")
	)
	(segment
		(start 20.089622 -43.1927)
		(end 19.888962 -43.39336)
		(width 0.1397)
		(layer "B.Cu")
		(net "CLK_100M_CLKBUFF_NGFF_DP")
	)
	(segment
		(start 2.94386 -51.45532)
		(end 2.7432 -51.65598)
		(width 0.1397)
		(layer "B.Cu")
		(net "CLK_100M_CLKBUFF_NGFF_DP")
	)
	(segment
		(start 3.080512 -53.651912)
		(end 3.364484 -53.651912)
		(width 0.1397)
		(layer "B.Cu")
		(net "CLK_100M_CLKBUFF_NGFF_DP")
	)
	(segment
		(start 29.40939 -39.40175)
		(end 26.20645 -39.40175)
		(width 0.1397)
		(layer "B.Cu")
		(net "CLK_100M_CLKBUFF_NGFF_DP")
	)
	(segment
		(start 14.859 -46.3296)
		(end 13.3096 -46.3296)
		(width 0.1397)
		(layer "B.Cu")
		(net "CLK_100M_CLKBUFF_NGFF_DP")
	)
	(segment
		(start 35.56 -23.6982)
		(end 35.56 -36.12134)
		(width 0.1397)
		(layer "B.Cu")
		(net "CLK_100M_CLKBUFF_NGFF_DP")
	)
	(segment
		(start 19.469862 -43.39336)
		(end 19.269202 -43.1927)
		(width 0.1397)
		(layer "B.Cu")
		(net "CLK_100M_CLKBUFF_NGFF_DP")
	)
	(segment
		(start 35.941 -23.3172)
		(end 35.56 -23.6982)
		(width 0.1397)
		(layer "B.Cu")
		(net "CLK_100M_CLKBUFF_NGFF_DP")
	)
	(segment
		(start 2.7432 -52.8955)
		(end 2.7432 -53.3146)
		(width 0.1397)
		(layer "B.Cu")
		(net "CLK_100M_CLKBUFF_NGFF_DP")
	)
	(segment
		(start 4.85902 -54.44998)
		(end 5.575046 -54.44998)
		(width 0.1397)
		(layer "B.Cu")
		(net "CLK_100M_CLKBUFF_NGFF_DP")
	)
	(segment
		(start 3.364484 -53.651912)
		(end 3.660648 -53.94833)
		(width 0.1397)
		(layer "B.Cu")
		(net "CLK_100M_CLKBUFF_NGFF_DP")
	)
	(segment
		(start 19.269202 -43.1927)
		(end 17.9959 -43.1927)
		(width 0.1397)
		(layer "B.Cu")
		(net "CLK_100M_CLKBUFF_NGFF_DP")
	)
	(segment
		(start 2.94386 -52.69484)
		(end 2.7432 -52.8955)
		(width 0.1397)
		(layer "B.Cu")
		(net "CLK_100M_CLKBUFF_NGFF_DP")
	)
	(segment
		(start 104.6607 -57.1754)
		(end 104.267 -56.7817)
		(width 0.1016)
		(layer "F.Cu")
		(net "M_A_DQS_DP5")
	)
	(segment
		(start 141.250162 -62.59322)
		(end 141.250162 -63.33617)
		(width 0.1778)
		(layer "F.Cu")
		(net "M_A_DQS_DP5")
	)
	(segment
		(start 103.656384 -51.53533)
		(end 103.569008 -51.447954)
		(width 0.1016)
		(layer "F.Cu")
		(net "M_A_DQS_DP5")
	)
	(segment
		(start 104.267 -53.9242)
		(end 103.656384 -53.313584)
		(width 0.1016)
		(layer "F.Cu")
		(net "M_A_DQS_DP5")
	)
	(segment
		(start 141.397736 -66.407284)
		(end 141.132814 -66.672206)
		(width 0.1778)
		(layer "F.Cu")
		(net "M_A_DQS_DP5")
	)
	(segment
		(start 104.267 -56.7817)
		(end 104.267 -53.9242)
		(width 0.1016)
		(layer "F.Cu")
		(net "M_A_DQS_DP5")
	)
	(segment
		(start 103.656384 -53.313584)
		(end 103.656384 -51.53533)
		(width 0.1016)
		(layer "F.Cu")
		(net "M_A_DQS_DP5")
	)
	(segment
		(start 141.397736 -63.483744)
		(end 141.397736 -66.407284)
		(width 0.1778)
		(layer "F.Cu")
		(net "M_A_DQS_DP5")
	)
	(segment
		(start 141.250162 -63.33617)
		(end 141.397736 -63.483744)
		(width 0.1778)
		(layer "F.Cu")
		(net "M_A_DQS_DP5")
	)
	(via
		(at 104.6607 -57.1754)
		(size 0.4318)
		(drill 0.2032)
		(layers "F.Cu" "B.Cu")
		(net "M_A_DQS_DP5")
	)
	(via
		(at 141.132814 -66.672206)
		(size 0.4318)
		(drill 0.2032)
		(layers "F.Cu" "B.Cu")
		(net "M_A_DQS_DP5")
	)
	(segment
		(start 141.250162 -70.79996)
		(end 141.250162 -70.008242)
		(width 0.1778)
		(layer "B.Cu")
		(net "M_A_DQS_DP5")
	)
	(segment
		(start 141.250162 -70.008242)
		(end 141.397736 -69.860668)
		(width 0.1778)
		(layer "B.Cu")
		(net "M_A_DQS_DP5")
	)
	(segment
		(start 141.397736 -69.860668)
		(end 141.397736 -66.937128)
		(width 0.1778)
		(layer "B.Cu")
		(net "M_A_DQS_DP5")
	)
	(segment
		(start 141.397736 -66.937128)
		(end 141.132814 -66.672206)
		(width 0.1778)
		(layer "B.Cu")
		(net "M_A_DQS_DP5")
	)
	(segment
		(start 125.580902 -60.0202)
		(end 125.264926 -59.704224)
		(width 0.1524)
		(layer "In2.Cu")
		(net "M_A_DQS_DP5")
	)
	(segment
		(start 123.802902 -60.0202)
		(end 123.486926 -59.704224)
		(width 0.1524)
		(layer "In2.Cu")
		(net "M_A_DQS_DP5")
	)
	(segment
		(start 135.58901 -59.4614)
		(end 132.167376 -59.4614)
		(width 0.1524)
		(layer "In2.Cu")
		(net "M_A_DQS_DP5")
	)
	(segment
		(start 124.33935 -60.0202)
		(end 123.802902 -60.0202)
		(width 0.1524)
		(layer "In2.Cu")
		(net "M_A_DQS_DP5")
	)
	(segment
		(start 126.585726 -58.715402)
		(end 126.433326 -58.867802)
		(width 0.1524)
		(layer "In2.Cu")
		(net "M_A_DQS_DP5")
	)
	(segment
		(start 127.169926 -58.715402)
		(end 126.585726 -58.715402)
		(width 0.1524)
		(layer "In2.Cu")
		(net "M_A_DQS_DP5")
	)
	(segment
		(start 126.433326 -58.867802)
		(end 126.433326 -59.704224)
		(width 0.1524)
		(layer "In2.Cu")
		(net "M_A_DQS_DP5")
	)
	(segment
		(start 131.421378 -58.715402)
		(end 128.643126 -58.715402)
		(width 0.1524)
		(layer "In2.Cu")
		(net "M_A_DQS_DP5")
	)
	(segment
		(start 125.264926 -58.867802)
		(end 125.112526 -58.715402)
		(width 0.1524)
		(layer "In2.Cu")
		(net "M_A_DQS_DP5")
	)
	(segment
		(start 126.11735 -60.0202)
		(end 125.580902 -60.0202)
		(width 0.1524)
		(layer "In2.Cu")
		(net "M_A_DQS_DP5")
	)
	(segment
		(start 128.490726 -58.867802)
		(end 128.490726 -59.272424)
		(width 0.1524)
		(layer "In2.Cu")
		(net "M_A_DQS_DP5")
	)
	(segment
		(start 135.97001 -59.0804)
		(end 135.58901 -59.4614)
		(width 0.1524)
		(layer "In2.Cu")
		(net "M_A_DQS_DP5")
	)
	(segment
		(start 124.807726 -58.715402)
		(end 124.655326 -58.867802)
		(width 0.1524)
		(layer "In2.Cu")
		(net "M_A_DQS_DP5")
	)
	(segment
		(start 128.643126 -58.715402)
		(end 128.490726 -58.867802)
		(width 0.1524)
		(layer "In2.Cu")
		(net "M_A_DQS_DP5")
	)
	(segment
		(start 105.807002 -58.715402)
		(end 104.8639 -57.7723)
		(width 0.1524)
		(layer "In2.Cu")
		(net "M_A_DQS_DP5")
	)
	(segment
		(start 125.264926 -59.704224)
		(end 125.264926 -58.867802)
		(width 0.1524)
		(layer "In2.Cu")
		(net "M_A_DQS_DP5")
	)
	(segment
		(start 104.8639 -57.7723)
		(end 104.8639 -57.3786)
		(width 0.1016)
		(layer "In2.Cu")
		(net "M_A_DQS_DP5")
	)
	(segment
		(start 141.410436 -66.000376)
		(end 141.68247 -65.728342)
		(width 0.1524)
		(layer "In2.Cu")
		(net "M_A_DQS_DP5")
	)
	(segment
		(start 126.433326 -59.704224)
		(end 126.11735 -60.0202)
		(width 0.1524)
		(layer "In2.Cu")
		(net "M_A_DQS_DP5")
	)
	(segment
		(start 125.112526 -58.715402)
		(end 124.807726 -58.715402)
		(width 0.1524)
		(layer "In2.Cu")
		(net "M_A_DQS_DP5")
	)
	(segment
		(start 123.486926 -58.867802)
		(end 123.334526 -58.715402)
		(width 0.1524)
		(layer "In2.Cu")
		(net "M_A_DQS_DP5")
	)
	(segment
		(start 104.8639 -57.3786)
		(end 104.6607 -57.1754)
		(width 0.1016)
		(layer "In2.Cu")
		(net "M_A_DQS_DP5")
	)
	(segment
		(start 123.334526 -58.715402)
		(end 105.807002 -58.715402)
		(width 0.1524)
		(layer "In2.Cu")
		(net "M_A_DQS_DP5")
	)
	(segment
		(start 141.68247 -62.180978)
		(end 138.581892 -59.0804)
		(width 0.1524)
		(layer "In2.Cu")
		(net "M_A_DQS_DP5")
	)
	(segment
		(start 127.638302 -59.5884)
		(end 127.322326 -59.272424)
		(width 0.1524)
		(layer "In2.Cu")
		(net "M_A_DQS_DP5")
	)
	(segment
		(start 141.132814 -66.672206)
		(end 141.410436 -66.394584)
		(width 0.1524)
		(layer "In2.Cu")
		(net "M_A_DQS_DP5")
	)
	(segment
		(start 127.322326 -59.272424)
		(end 127.322326 -58.867802)
		(width 0.1524)
		(layer "In2.Cu")
		(net "M_A_DQS_DP5")
	)
	(segment
		(start 141.68247 -65.728342)
		(end 141.68247 -62.180978)
		(width 0.1524)
		(layer "In2.Cu")
		(net "M_A_DQS_DP5")
	)
	(segment
		(start 141.410436 -66.394584)
		(end 141.410436 -66.000376)
		(width 0.1524)
		(layer "In2.Cu")
		(net "M_A_DQS_DP5")
	)
	(segment
		(start 132.167376 -59.4614)
		(end 131.421378 -58.715402)
		(width 0.1524)
		(layer "In2.Cu")
		(net "M_A_DQS_DP5")
	)
	(segment
		(start 128.490726 -59.272424)
		(end 128.17475 -59.5884)
		(width 0.1524)
		(layer "In2.Cu")
		(net "M_A_DQS_DP5")
	)
	(segment
		(start 124.655326 -58.867802)
		(end 124.655326 -59.704224)
		(width 0.1524)
		(layer "In2.Cu")
		(net "M_A_DQS_DP5")
	)
	(segment
		(start 138.581892 -59.0804)
		(end 135.97001 -59.0804)
		(width 0.1524)
		(layer "In2.Cu")
		(net "M_A_DQS_DP5")
	)
	(segment
		(start 127.322326 -58.867802)
		(end 127.169926 -58.715402)
		(width 0.1524)
		(layer "In2.Cu")
		(net "M_A_DQS_DP5")
	)
	(segment
		(start 124.655326 -59.704224)
		(end 124.33935 -60.0202)
		(width 0.1524)
		(layer "In2.Cu")
		(net "M_A_DQS_DP5")
	)
	(segment
		(start 123.486926 -59.704224)
		(end 123.486926 -58.867802)
		(width 0.1524)
		(layer "In2.Cu")
		(net "M_A_DQS_DP5")
	)
	(segment
		(start 128.17475 -59.5884)
		(end 127.638302 -59.5884)
		(width 0.1524)
		(layer "In2.Cu")
		(net "M_A_DQS_DP5")
	)
	(segment
		(start 49.5046 -49.149)
		(end 48.9712 -49.149)
		(width 0.508)
		(layer "F.Cu")
		(net "P1V5_CLK_SCR_LVIO")
	)
	(segment
		(start 48.9712 -48.2854)
		(end 49.022 -48.2346)
		(width 0.508)
		(layer "F.Cu")
		(net "P1V5_CLK_SCR_LVIO")
	)
	(segment
		(start 49.69002 -48.96358)
		(end 49.5046 -49.149)
		(width 0.508)
		(layer "F.Cu")
		(net "P1V5_CLK_SCR_LVIO")
	)
	(segment
		(start 48.9712 -49.149)
		(end 48.9712 -49.9618)
		(width 0.508)
		(layer "F.Cu")
		(net "P1V5_CLK_SCR_LVIO")
	)
	(segment
		(start 48.9712 -49.9618)
		(end 49.1744 -50.165)
		(width 0.508)
		(layer "F.Cu")
		(net "P1V5_CLK_SCR_LVIO")
	)
	(segment
		(start 49.1744 -50.165)
		(end 50.317654 -50.165)
		(width 0.508)
		(layer "F.Cu")
		(net "P1V5_CLK_SCR_LVIO")
	)
	(segment
		(start 50.317654 -50.165)
		(end 50.3428 -50.139854)
		(width 0.508)
		(layer "F.Cu")
		(net "P1V5_CLK_SCR_LVIO")
	)
	(segment
		(start 48.9712 -49.149)
		(end 48.9712 -48.2854)
		(width 0.508)
		(layer "F.Cu")
		(net "P1V5_CLK_SCR_LVIO")
	)
	(via
		(at 49.69002 -48.96358)
		(size 0.508)
		(drill 0.254)
		(layers "F.Cu" "B.Cu")
		(net "P1V5_CLK_SCR_LVIO")
	)
	(via
		(at 49.022 -48.2346)
		(size 0.7112)
		(drill 0.3556)
		(layers "F.Cu" "B.Cu")
		(net "P1V5_CLK_SCR_LVIO")
	)
	(segment
		(start 48.668178 -49.097184)
		(end 49.556416 -49.097184)
		(width 0.2032)
		(layer "B.Cu")
		(net "P1V5_CLK_SCR_LVIO")
	)
	(segment
		(start 49.556416 -49.097184)
		(end 49.69002 -48.96358)
		(width 0.2032)
		(layer "B.Cu")
		(net "P1V5_CLK_SCR_LVIO")
	)
	(segment
		(start 22.27326 -42.8498)
		(end 17.85366 -42.8498)
		(width 0.1397)
		(layer "B.Cu")
		(net "CLK_100M_CLKBUFF_NGFF_DN")
	)
	(segment
		(start 35.79876 -22.9743)
		(end 35.2171 -23.55596)
		(width 0.1397)
		(layer "B.Cu")
		(net "CLK_100M_CLKBUFF_NGFF_DN")
	)
	(segment
		(start 35.2171 -23.55596)
		(end 35.2171 -35.9791)
		(width 0.1397)
		(layer "B.Cu")
		(net "CLK_100M_CLKBUFF_NGFF_DN")
	)
	(segment
		(start 17.85366 -42.8498)
		(end 14.71676 -45.9867)
		(width 0.1397)
		(layer "B.Cu")
		(net "CLK_100M_CLKBUFF_NGFF_DN")
	)
	(segment
		(start 3.74396 -46.6979)
		(end 2.4003 -48.04156)
		(width 0.1397)
		(layer "B.Cu")
		(net "CLK_100M_CLKBUFF_NGFF_DN")
	)
	(segment
		(start 36.1315 -22.9743)
		(end 35.79876 -22.9743)
		(width 0.1397)
		(layer "B.Cu")
		(net "CLK_100M_CLKBUFF_NGFF_DN")
	)
	(segment
		(start 2.4003 -53.45684)
		(end 3.814826 -54.871366)
		(width 0.1397)
		(layer "B.Cu")
		(net "CLK_100M_CLKBUFF_NGFF_DN")
	)
	(segment
		(start 3.814826 -54.871366)
		(end 4.7498 -54.871366)
		(width 0.1397)
		(layer "B.Cu")
		(net "CLK_100M_CLKBUFF_NGFF_DN")
	)
	(segment
		(start 34.16935 -37.02685)
		(end 31.29915 -37.02685)
		(width 0.1397)
		(layer "B.Cu")
		(net "CLK_100M_CLKBUFF_NGFF_DN")
	)
	(segment
		(start 4.7498 -54.871366)
		(end 4.828286 -54.949852)
		(width 0.1397)
		(layer "B.Cu")
		(net "CLK_100M_CLKBUFF_NGFF_DN")
	)
	(segment
		(start 37.2872 -22.733)
		(end 36.5252 -22.733)
		(width 0.1397)
		(layer "B.Cu")
		(net "CLK_100M_CLKBUFF_NGFF_DN")
	)
	(segment
		(start 29.26715 -39.05885)
		(end 26.06421 -39.05885)
		(width 0.1397)
		(layer "B.Cu")
		(net "CLK_100M_CLKBUFF_NGFF_DN")
	)
	(segment
		(start 31.29915 -37.02685)
		(end 29.26715 -39.05885)
		(width 0.1397)
		(layer "B.Cu")
		(net "CLK_100M_CLKBUFF_NGFF_DN")
	)
	(segment
		(start 4.828286 -54.949852)
		(end 5.575046 -54.949852)
		(width 0.1397)
		(layer "B.Cu")
		(net "CLK_100M_CLKBUFF_NGFF_DN")
	)
	(segment
		(start 36.449 -22.6568)
		(end 36.1315 -22.9743)
		(width 0.1397)
		(layer "B.Cu")
		(net "CLK_100M_CLKBUFF_NGFF_DN")
	)
	(segment
		(start 35.2171 -35.9791)
		(end 34.16935 -37.02685)
		(width 0.1397)
		(layer "B.Cu")
		(net "CLK_100M_CLKBUFF_NGFF_DN")
	)
	(segment
		(start 2.4003 -48.04156)
		(end 2.4003 -53.45684)
		(width 0.1397)
		(layer "B.Cu")
		(net "CLK_100M_CLKBUFF_NGFF_DN")
	)
	(segment
		(start 36.5252 -22.733)
		(end 36.449 -22.6568)
		(width 0.1397)
		(layer "B.Cu")
		(net "CLK_100M_CLKBUFF_NGFF_DN")
	)
	(segment
		(start 13.16736 -45.9867)
		(end 12.45616 -46.6979)
		(width 0.1397)
		(layer "B.Cu")
		(net "CLK_100M_CLKBUFF_NGFF_DN")
	)
	(segment
		(start 26.06421 -39.05885)
		(end 22.27326 -42.8498)
		(width 0.1397)
		(layer "B.Cu")
		(net "CLK_100M_CLKBUFF_NGFF_DN")
	)
	(segment
		(start 14.71676 -45.9867)
		(end 13.16736 -45.9867)
		(width 0.1397)
		(layer "B.Cu")
		(net "CLK_100M_CLKBUFF_NGFF_DN")
	)
	(segment
		(start 12.45616 -46.6979)
		(end 3.74396 -46.6979)
		(width 0.1397)
		(layer "B.Cu")
		(net "CLK_100M_CLKBUFF_NGFF_DN")
	)
	(segment
		(start 144.2212 -69.575172)
		(end 144.2212 -68.707)
		(width 0.1778)
		(layer "F.Cu")
		(net "M_A_DQ39")
	)
	(segment
		(start 96.89084 -49.639982)
		(end 97.366328 -49.164494)
		(width 0.1016)
		(layer "F.Cu")
		(net "M_A_DQ39")
	)
	(segment
		(start 96.89084 -49.68494)
		(end 96.89084 -49.639982)
		(width 0.1016)
		(layer "F.Cu")
		(net "M_A_DQ39")
	)
	(segment
		(start 143.950182 -70.806564)
		(end 143.950182 -69.84619)
		(width 0.1778)
		(layer "F.Cu")
		(net "M_A_DQ39")
	)
	(segment
		(start 143.950182 -69.84619)
		(end 144.2212 -69.575172)
		(width 0.1778)
		(layer "F.Cu")
		(net "M_A_DQ39")
	)
	(via
		(at 144.2212 -68.707)
		(size 0.4318)
		(drill 0.2032)
		(layers "F.Cu" "B.Cu")
		(net "M_A_DQ39")
	)
	(via
		(at 96.89084 -49.68494)
		(size 0.4318)
		(drill 0.2032)
		(layers "F.Cu" "B.Cu")
		(net "M_A_DQ39")
	)
	(segment
		(start 144.850104 -70.79996)
		(end 144.850104 -70.021704)
		(width 0.1778)
		(layer "B.Cu")
		(net "M_A_DQ39")
	)
	(segment
		(start 144.2212 -69.3928)
		(end 144.2212 -68.707)
		(width 0.1778)
		(layer "B.Cu")
		(net "M_A_DQ39")
	)
	(segment
		(start 144.850104 -70.021704)
		(end 144.2212 -69.3928)
		(width 0.1778)
		(layer "B.Cu")
		(net "M_A_DQ39")
	)
	(segment
		(start 97.3074 -54.4322)
		(end 97.155 -54.2798)
		(width 0.1016)
		(layer "In4.Cu")
		(net "M_A_DQ39")
	)
	(segment
		(start 144.399 -68.58)
		(end 144.399 -68.349114)
		(width 0.1524)
		(layer "In4.Cu")
		(net "M_A_DQ39")
	)
	(segment
		(start 140.8938 -68.196714)
		(end 140.7414 -68.349114)
		(width 0.1524)
		(layer "In4.Cu")
		(net "M_A_DQ39")
	)
	(segment
		(start 97.541334 -51.658266)
		(end 97.541334 -50.5968)
		(width 0.1016)
		(layer "In4.Cu")
		(net "M_A_DQ39")
	)
	(segment
		(start 103.2002 -55.6006)
		(end 102.616 -55.0164)
		(width 0.1524)
		(layer "In4.Cu")
		(net "M_A_DQ39")
	)
	(segment
		(start 139.7127 -63.4365)
		(end 135.9408 -59.6646)
		(width 0.1524)
		(layer "In4.Cu")
		(net "M_A_DQ39")
	)
	(segment
		(start 105.1814 -59.4614)
		(end 104.648 -58.928)
		(width 0.1524)
		(layer "In4.Cu")
		(net "M_A_DQ39")
	)
	(segment
		(start 139.9286 -65.3796)
		(end 140.8176 -65.3796)
		(width 0.1524)
		(layer "In4.Cu")
		(net "M_A_DQ39")
	)
	(segment
		(start 130.127248 -59.0804)
		(end 129.746248 -59.4614)
		(width 0.1524)
		(layer "In4.Cu")
		(net "M_A_DQ39")
	)
	(segment
		(start 139.7762 -65.532)
		(end 139.9286 -65.3796)
		(width 0.1524)
		(layer "In4.Cu")
		(net "M_A_DQ39")
	)
	(segment
		(start 140.8176 -65.3796)
		(end 141.0462 -65.151)
		(width 0.1524)
		(layer "In4.Cu")
		(net "M_A_DQ39")
	)
	(segment
		(start 106.078528 -59.1058)
		(end 105.722928 -59.4614)
		(width 0.1524)
		(layer "In4.Cu")
		(net "M_A_DQ39")
	)
	(segment
		(start 126.179072 -59.4614)
		(end 125.823472 -59.1058)
		(width 0.1524)
		(layer "In4.Cu")
		(net "M_A_DQ39")
	)
	(segment
		(start 101.2952 -53.6956)
		(end 99.2124 -53.6956)
		(width 0.1016)
		(layer "In4.Cu")
		(net "M_A_DQ39")
	)
	(segment
		(start 138.43 -68.244212)
		(end 138.43 -67.787012)
		(width 0.1524)
		(layer "In4.Cu")
		(net "M_A_DQ39")
	)
	(segment
		(start 140.589 -68.7832)
		(end 140.1064 -68.7832)
		(width 0.1524)
		(layer "In4.Cu")
		(net "M_A_DQ39")
	)
	(segment
		(start 103.2002 -58.0136)
		(end 103.2002 -55.6006)
		(width 0.1524)
		(layer "In4.Cu")
		(net "M_A_DQ39")
	)
	(segment
		(start 139.7762 -66.0654)
		(end 139.7762 -65.532)
		(width 0.1524)
		(layer "In4.Cu")
		(net "M_A_DQ39")
	)
	(segment
		(start 104.648 -58.5978)
		(end 104.3686 -58.3184)
		(width 0.1524)
		(layer "In4.Cu")
		(net "M_A_DQ39")
	)
	(segment
		(start 144.399 -68.349114)
		(end 144.2466 -68.196714)
		(width 0.1524)
		(layer "In4.Cu")
		(net "M_A_DQ39")
	)
	(segment
		(start 140.1064 -68.7832)
		(end 139.719812 -68.396612)
		(width 0.1524)
		(layer "In4.Cu")
		(net "M_A_DQ39")
	)
	(segment
		(start 98.9076 -54.4322)
		(end 97.3074 -54.4322)
		(width 0.1016)
		(layer "In4.Cu")
		(net "M_A_DQ39")
	)
	(segment
		(start 97.155 -52.0446)
		(end 97.541334 -51.658266)
		(width 0.1016)
		(layer "In4.Cu")
		(net "M_A_DQ39")
	)
	(segment
		(start 139.5984 -66.2432)
		(end 139.7762 -66.0654)
		(width 0.1524)
		(layer "In4.Cu")
		(net "M_A_DQ39")
	)
	(segment
		(start 138.5824 -67.634612)
		(end 139.7 -67.634612)
		(width 0.1524)
		(layer "In4.Cu")
		(net "M_A_DQ39")
	)
	(segment
		(start 99.2124 -53.6956)
		(end 99.06 -53.848)
		(width 0.1016)
		(layer "In4.Cu")
		(net "M_A_DQ39")
	)
	(segment
		(start 139.719812 -68.396612)
		(end 138.5824 -68.396612)
		(width 0.1524)
		(layer "In4.Cu")
		(net "M_A_DQ39")
	)
	(segment
		(start 104.3686 -58.3184)
		(end 103.505 -58.3184)
		(width 0.1524)
		(layer "In4.Cu")
		(net "M_A_DQ39")
	)
	(segment
		(start 104.648 -58.928)
		(end 104.648 -58.5978)
		(width 0.1524)
		(layer "In4.Cu")
		(net "M_A_DQ39")
	)
	(segment
		(start 139.7 -67.634612)
		(end 139.8524 -67.482212)
		(width 0.1524)
		(layer "In4.Cu")
		(net "M_A_DQ39")
	)
	(segment
		(start 103.505 -58.3184)
		(end 103.2002 -58.0136)
		(width 0.1524)
		(layer "In4.Cu")
		(net "M_A_DQ39")
	)
	(segment
		(start 138.7602 -66.802)
		(end 138.7602 -66.4718)
		(width 0.1524)
		(layer "In4.Cu")
		(net "M_A_DQ39")
	)
	(segment
		(start 99.06 -54.2798)
		(end 98.9076 -54.4322)
		(width 0.1016)
		(layer "In4.Cu")
		(net "M_A_DQ39")
	)
	(segment
		(start 144.2212 -68.707)
		(end 144.272 -68.707)
		(width 0.1524)
		(layer "In4.Cu")
		(net "M_A_DQ39")
	)
	(segment
		(start 139.8524 -67.2084)
		(end 139.6238 -66.9798)
		(width 0.1524)
		(layer "In4.Cu")
		(net "M_A_DQ39")
	)
	(segment
		(start 131.975352 -59.6646)
		(end 131.391152 -59.0804)
		(width 0.1524)
		(layer "In4.Cu")
		(net "M_A_DQ39")
	)
	(segment
		(start 144.2466 -68.196714)
		(end 140.8938 -68.196714)
		(width 0.1524)
		(layer "In4.Cu")
		(net "M_A_DQ39")
	)
	(segment
		(start 138.9888 -66.2432)
		(end 139.5984 -66.2432)
		(width 0.1524)
		(layer "In4.Cu")
		(net "M_A_DQ39")
	)
	(segment
		(start 125.823472 -59.1058)
		(end 106.078528 -59.1058)
		(width 0.1524)
		(layer "In4.Cu")
		(net "M_A_DQ39")
	)
	(segment
		(start 140.6525 -63.4365)
		(end 139.7127 -63.4365)
		(width 0.1524)
		(layer "In4.Cu")
		(net "M_A_DQ39")
	)
	(segment
		(start 140.7414 -68.349114)
		(end 140.7414 -68.6308)
		(width 0.1524)
		(layer "In4.Cu")
		(net "M_A_DQ39")
	)
	(segment
		(start 99.06 -53.848)
		(end 99.06 -54.2798)
		(width 0.1016)
		(layer "In4.Cu")
		(net "M_A_DQ39")
	)
	(segment
		(start 138.5824 -68.396612)
		(end 138.43 -68.244212)
		(width 0.1524)
		(layer "In4.Cu")
		(net "M_A_DQ39")
	)
	(segment
		(start 141.0462 -65.151)
		(end 141.0462 -63.8302)
		(width 0.1524)
		(layer "In4.Cu")
		(net "M_A_DQ39")
	)
	(segment
		(start 138.938 -66.9798)
		(end 138.7602 -66.802)
		(width 0.1524)
		(layer "In4.Cu")
		(net "M_A_DQ39")
	)
	(segment
		(start 105.722928 -59.4614)
		(end 105.1814 -59.4614)
		(width 0.1524)
		(layer "In4.Cu")
		(net "M_A_DQ39")
	)
	(segment
		(start 138.43 -67.787012)
		(end 138.5824 -67.634612)
		(width 0.1524)
		(layer "In4.Cu")
		(net "M_A_DQ39")
	)
	(segment
		(start 97.155 -54.2798)
		(end 97.155 -52.0446)
		(width 0.1016)
		(layer "In4.Cu")
		(net "M_A_DQ39")
	)
	(segment
		(start 140.7414 -68.6308)
		(end 140.589 -68.7832)
		(width 0.1524)
		(layer "In4.Cu")
		(net "M_A_DQ39")
	)
	(segment
		(start 139.6238 -66.9798)
		(end 138.938 -66.9798)
		(width 0.1524)
		(layer "In4.Cu")
		(net "M_A_DQ39")
	)
	(segment
		(start 131.391152 -59.0804)
		(end 130.127248 -59.0804)
		(width 0.1524)
		(layer "In4.Cu")
		(net "M_A_DQ39")
	)
	(segment
		(start 138.7602 -66.4718)
		(end 138.9888 -66.2432)
		(width 0.1524)
		(layer "In4.Cu")
		(net "M_A_DQ39")
	)
	(segment
		(start 139.8524 -67.482212)
		(end 139.8524 -67.2084)
		(width 0.1524)
		(layer "In4.Cu")
		(net "M_A_DQ39")
	)
	(segment
		(start 102.616 -55.0164)
		(end 101.2952 -53.6956)
		(width 0.1016)
		(layer "In4.Cu")
		(net "M_A_DQ39")
	)
	(segment
		(start 144.272 -68.707)
		(end 144.399 -68.58)
		(width 0.1524)
		(layer "In4.Cu")
		(net "M_A_DQ39")
	)
	(segment
		(start 97.541334 -50.5968)
		(end 96.89084 -49.946306)
		(width 0.1016)
		(layer "In4.Cu")
		(net "M_A_DQ39")
	)
	(segment
		(start 141.0462 -63.8302)
		(end 140.6525 -63.4365)
		(width 0.1524)
		(layer "In4.Cu")
		(net "M_A_DQ39")
	)
	(segment
		(start 129.746248 -59.4614)
		(end 126.179072 -59.4614)
		(width 0.1524)
		(layer "In4.Cu")
		(net "M_A_DQ39")
	)
	(segment
		(start 135.9408 -59.6646)
		(end 131.975352 -59.6646)
		(width 0.1524)
		(layer "In4.Cu")
		(net "M_A_DQ39")
	)
	(segment
		(start 96.89084 -49.946306)
		(end 96.89084 -49.68494)
		(width 0.1016)
		(layer "In4.Cu")
		(net "M_A_DQ39")
	)
	(via
		(at 42.037 -40.005)
		(size 0.7112)
		(drill 0.3556)
		(layers "F.Cu" "B.Cu")
		(net "P1V5_CLK_VDDDIF")
	)
	(segment
		(start 46.7614 -45.031152)
		(end 46.7614 -43.9674)
		(width 0.2032)
		(layer "B.Cu")
		(net "P1V5_CLK_VDDDIF")
	)
	(segment
		(start 43.2816 -40.569642)
		(end 43.2816 -42.3926)
		(width 0.508)
		(layer "B.Cu")
		(net "P1V5_CLK_VDDDIF")
	)
	(segment
		(start 46.101 -43.307)
		(end 45.8978 -43.307)
		(width 0.3048)
		(layer "B.Cu")
		(net "P1V5_CLK_VDDDIF")
	)
	(segment
		(start 45.0342 -42.799)
		(end 45.212 -42.6212)
		(width 0.508)
		(layer "B.Cu")
		(net "P1V5_CLK_VDDDIF")
	)
	(segment
		(start 43.8404 -42.9514)
		(end 44.196 -42.9514)
		(width 0.508)
		(layer "B.Cu")
		(net "P1V5_CLK_VDDDIF")
	)
	(segment
		(start 45.8978 -43.307)
		(end 45.212 -42.6212)
		(width 0.3048)
		(layer "B.Cu")
		(net "P1V5_CLK_VDDDIF")
	)
	(segment
		(start 43.2816 -42.3926)
		(end 43.8404 -42.9514)
		(width 0.508)
		(layer "B.Cu")
		(net "P1V5_CLK_VDDDIF")
	)
	(segment
		(start 44.3484 -42.799)
		(end 45.0342 -42.799)
		(width 0.508)
		(layer "B.Cu")
		(net "P1V5_CLK_VDDDIF")
	)
	(segment
		(start 46.458632 -46.087792)
		(end 46.458632 -45.33392)
		(width 0.2032)
		(layer "B.Cu")
		(net "P1V5_CLK_VDDDIF")
	)
	(segment
		(start 46.7614 -43.9674)
		(end 46.101 -43.307)
		(width 0.2032)
		(layer "B.Cu")
		(net "P1V5_CLK_VDDDIF")
	)
	(segment
		(start 42.716958 -40.005)
		(end 43.2816 -40.569642)
		(width 0.508)
		(layer "B.Cu")
		(net "P1V5_CLK_VDDDIF")
	)
	(segment
		(start 42.037 -40.005)
		(end 40.6654 -40.005)
		(width 0.508)
		(layer "B.Cu")
		(net "P1V5_CLK_VDDDIF")
	)
	(segment
		(start 42.037 -40.005)
		(end 42.716958 -40.005)
		(width 0.508)
		(layer "B.Cu")
		(net "P1V5_CLK_VDDDIF")
	)
	(segment
		(start 46.458632 -45.33392)
		(end 46.7614 -45.031152)
		(width 0.2032)
		(layer "B.Cu")
		(net "P1V5_CLK_VDDDIF")
	)
	(segment
		(start 44.196 -42.9514)
		(end 44.3484 -42.799)
		(width 0.508)
		(layer "B.Cu")
		(net "P1V5_CLK_VDDDIF")
	)
	(segment
		(start 103.6828 -57.6326)
		(end 103.6574 -57.6326)
		(width 0.1016)
		(layer "F.Cu")
		(net "M_A_DQ47")
	)
	(segment
		(start 103.2002 -54.2544)
		(end 102.964488 -54.018688)
		(width 0.1016)
		(layer "F.Cu")
		(net "M_A_DQ47")
	)
	(segment
		(start 102.964488 -54.018688)
		(end 102.964488 -51.841654)
		(width 0.1016)
		(layer "F.Cu")
		(net "M_A_DQ47")
	)
	(segment
		(start 139.750038 -69.506846)
		(end 139.450064 -69.206872)
		(width 0.1778)
		(layer "F.Cu")
		(net "M_A_DQ47")
	)
	(segment
		(start 139.750038 -70.806564)
		(end 139.750038 -69.506846)
		(width 0.1778)
		(layer "F.Cu")
		(net "M_A_DQ47")
	)
	(segment
		(start 103.2002 -57.1754)
		(end 103.2002 -54.2544)
		(width 0.1016)
		(layer "F.Cu")
		(net "M_A_DQ47")
	)
	(segment
		(start 139.450064 -68.888864)
		(end 139.3952 -68.834)
		(width 0.1778)
		(layer "F.Cu")
		(net "M_A_DQ47")
	)
	(segment
		(start 139.450064 -69.206872)
		(end 139.450064 -68.888864)
		(width 0.1778)
		(layer "F.Cu")
		(net "M_A_DQ47")
	)
	(segment
		(start 103.6574 -57.6326)
		(end 103.2002 -57.1754)
		(width 0.1016)
		(layer "F.Cu")
		(net "M_A_DQ47")
	)
	(via
		(at 103.6828 -57.6326)
		(size 0.4318)
		(drill 0.2032)
		(layers "F.Cu" "B.Cu")
		(net "M_A_DQ47")
	)
	(via
		(at 139.3952 -68.834)
		(size 0.4318)
		(drill 0.2032)
		(layers "F.Cu" "B.Cu")
		(net "M_A_DQ47")
	)
	(segment
		(start 139.450064 -68.888864)
		(end 139.3952 -68.834)
		(width 0.1778)
		(layer "B.Cu")
		(net "M_A_DQ47")
	)
	(segment
		(start 139.450064 -70.79996)
		(end 139.450064 -68.888864)
		(width 0.1778)
		(layer "B.Cu")
		(net "M_A_DQ47")
	)
	(segment
		(start 128.3462 -63.627)
		(end 128.4986 -63.4746)
		(width 0.1524)
		(layer "In2.Cu")
		(net "M_A_DQ47")
	)
	(segment
		(start 130.014218 -64.4144)
		(end 130.014218 -63.627)
		(width 0.1524)
		(layer "In2.Cu")
		(net "M_A_DQ47")
	)
	(segment
		(start 128.4986 -63.4746)
		(end 129.252218 -63.4746)
		(width 0.1524)
		(layer "In2.Cu")
		(net "M_A_DQ47")
	)
	(segment
		(start 105.172002 -59.883802)
		(end 120.996202 -59.883802)
		(width 0.1524)
		(layer "In2.Cu")
		(net "M_A_DQ47")
	)
	(segment
		(start 138.9126 -67.40271)
		(end 138.7602 -67.55511)
		(width 0.1524)
		(layer "In2.Cu")
		(net "M_A_DQ47")
	)
	(segment
		(start 130.014218 -63.627)
		(end 130.166618 -63.4746)
		(width 0.1524)
		(layer "In2.Cu")
		(net "M_A_DQ47")
	)
	(segment
		(start 136.8044 -62.4078)
		(end 139.7762 -62.4078)
		(width 0.1524)
		(layer "In2.Cu")
		(net "M_A_DQ47")
	)
	(segment
		(start 139.404598 -68.01231)
		(end 139.556998 -68.16471)
		(width 0.1524)
		(layer "In2.Cu")
		(net "M_A_DQ47")
	)
	(segment
		(start 139.556998 -67.25031)
		(end 139.404598 -67.40271)
		(width 0.1524)
		(layer "In2.Cu")
		(net "M_A_DQ47")
	)
	(segment
		(start 139.556998 -68.16471)
		(end 139.556998 -68.672202)
		(width 0.1524)
		(layer "In2.Cu")
		(net "M_A_DQ47")
	)
	(segment
		(start 103.6828 -57.6326)
		(end 103.6828 -58.3946)
		(width 0.1524)
		(layer "In2.Cu")
		(net "M_A_DQ47")
	)
	(segment
		(start 127.6096 -63.5508)
		(end 127.6096 -64.5414)
		(width 0.1524)
		(layer "In2.Cu")
		(net "M_A_DQ47")
	)
	(segment
		(start 138.7602 -67.85991)
		(end 138.9126 -68.01231)
		(width 0.1524)
		(layer "In2.Cu")
		(net "M_A_DQ47")
	)
	(segment
		(start 122.655584 -61.543184)
		(end 125.601984 -61.543184)
		(width 0.1524)
		(layer "In2.Cu")
		(net "M_A_DQ47")
	)
	(segment
		(start 127.6096 -64.5414)
		(end 127.762 -64.6938)
		(width 0.1524)
		(layer "In2.Cu")
		(net "M_A_DQ47")
	)
	(segment
		(start 129.252218 -63.4746)
		(end 129.404618 -63.627)
		(width 0.1524)
		(layer "In2.Cu")
		(net "M_A_DQ47")
	)
	(segment
		(start 135.7376 -63.4746)
		(end 136.8044 -62.4078)
		(width 0.1524)
		(layer "In2.Cu")
		(net "M_A_DQ47")
	)
	(segment
		(start 103.6828 -58.3946)
		(end 105.172002 -59.883802)
		(width 0.1524)
		(layer "In2.Cu")
		(net "M_A_DQ47")
	)
	(segment
		(start 125.601984 -61.543184)
		(end 127.6096 -63.5508)
		(width 0.1524)
		(layer "In2.Cu")
		(net "M_A_DQ47")
	)
	(segment
		(start 129.557018 -64.5668)
		(end 129.861818 -64.5668)
		(width 0.1524)
		(layer "In2.Cu")
		(net "M_A_DQ47")
	)
	(segment
		(start 141.0208 -64.9478)
		(end 139.556998 -66.411602)
		(width 0.1524)
		(layer "In2.Cu")
		(net "M_A_DQ47")
	)
	(segment
		(start 120.996202 -59.883802)
		(end 122.655584 -61.543184)
		(width 0.1524)
		(layer "In2.Cu")
		(net "M_A_DQ47")
	)
	(segment
		(start 129.404618 -63.627)
		(end 129.404618 -64.4144)
		(width 0.1524)
		(layer "In2.Cu")
		(net "M_A_DQ47")
	)
	(segment
		(start 128.1938 -64.6938)
		(end 128.3462 -64.5414)
		(width 0.1524)
		(layer "In2.Cu")
		(net "M_A_DQ47")
	)
	(segment
		(start 129.861818 -64.5668)
		(end 130.014218 -64.4144)
		(width 0.1524)
		(layer "In2.Cu")
		(net "M_A_DQ47")
	)
	(segment
		(start 139.556998 -66.411602)
		(end 139.556998 -67.25031)
		(width 0.1524)
		(layer "In2.Cu")
		(net "M_A_DQ47")
	)
	(segment
		(start 141.0208 -63.6524)
		(end 141.0208 -64.9478)
		(width 0.1524)
		(layer "In2.Cu")
		(net "M_A_DQ47")
	)
	(segment
		(start 139.7762 -62.4078)
		(end 141.0208 -63.6524)
		(width 0.1524)
		(layer "In2.Cu")
		(net "M_A_DQ47")
	)
	(segment
		(start 138.7602 -67.55511)
		(end 138.7602 -67.85991)
		(width 0.1524)
		(layer "In2.Cu")
		(net "M_A_DQ47")
	)
	(segment
		(start 130.166618 -63.4746)
		(end 135.7376 -63.4746)
		(width 0.1524)
		(layer "In2.Cu")
		(net "M_A_DQ47")
	)
	(segment
		(start 127.762 -64.6938)
		(end 128.1938 -64.6938)
		(width 0.1524)
		(layer "In2.Cu")
		(net "M_A_DQ47")
	)
	(segment
		(start 138.9126 -68.01231)
		(end 139.404598 -68.01231)
		(width 0.1524)
		(layer "In2.Cu")
		(net "M_A_DQ47")
	)
	(segment
		(start 139.556998 -68.672202)
		(end 139.3952 -68.834)
		(width 0.1524)
		(layer "In2.Cu")
		(net "M_A_DQ47")
	)
	(segment
		(start 139.404598 -67.40271)
		(end 138.9126 -67.40271)
		(width 0.1524)
		(layer "In2.Cu")
		(net "M_A_DQ47")
	)
	(segment
		(start 129.404618 -64.4144)
		(end 129.557018 -64.5668)
		(width 0.1524)
		(layer "In2.Cu")
		(net "M_A_DQ47")
	)
	(segment
		(start 128.3462 -64.5414)
		(end 128.3462 -63.627)
		(width 0.1524)
		(layer "In2.Cu")
		(net "M_A_DQ47")
	)
	(via
		(at 38.5064 -47.5488)
		(size 0.7112)
		(drill 0.3556)
		(layers "F.Cu" "B.Cu")
		(net "P3V3_CLK_XTAL")
	)
	(segment
		(start 37.6174 -48.387)
		(end 38.4556 -47.5488)
		(width 0.508)
		(layer "B.Cu")
		(net "P3V3_CLK_XTAL")
	)
	(segment
		(start 38.5318 -47.5234)
		(end 38.5064 -47.5488)
		(width 0.508)
		(layer "B.Cu")
		(net "P3V3_CLK_XTAL")
	)
	(segment
		(start 39.6494 -47.5234)
		(end 38.5318 -47.5234)
		(width 0.508)
		(layer "B.Cu")
		(net "P3V3_CLK_XTAL")
	)
	(segment
		(start 39.7002 -47.5742)
		(end 39.6494 -47.5234)
		(width 0.3048)
		(layer "B.Cu")
		(net "P3V3_CLK_XTAL")
	)
	(segment
		(start 43.04919 -47.497238)
		(end 40.742362 -47.497238)
		(width 0.2032)
		(layer "B.Cu")
		(net "P3V3_CLK_XTAL")
	)
	(segment
		(start 38.4556 -47.5488)
		(end 38.5064 -47.5488)
		(width 0.508)
		(layer "B.Cu")
		(net "P3V3_CLK_XTAL")
	)
	(segment
		(start 40.6654 -47.5742)
		(end 39.7002 -47.5742)
		(width 0.3048)
		(layer "B.Cu")
		(net "P3V3_CLK_XTAL")
	)
	(segment
		(start 40.742362 -47.497238)
		(end 40.6654 -47.5742)
		(width 0.2032)
		(layer "B.Cu")
		(net "P3V3_CLK_XTAL")
	)
	(segment
		(start 159.653478 -66.996056)
		(end 159.215328 -67.434206)
		(width 0.2413)
		(layer "F.Cu")
		(net "M_A_MA7")
	)
	(segment
		(start 108.829094 -49.545494)
		(end 108.909866 -49.626266)
		(width 0.1016)
		(layer "F.Cu")
		(net "M_A_MA7")
	)
	(segment
		(start 159.215328 -67.434206)
		(end 159.169354 -67.434206)
		(width 0.2413)
		(layer "F.Cu")
		(net "M_A_MA7")
	)
	(segment
		(start 159.653478 -65.622678)
		(end 159.653478 -66.996056)
		(width 0.2413)
		(layer "F.Cu")
		(net "M_A_MA7")
	)
	(segment
		(start 108.433108 -49.545494)
		(end 108.829094 -49.545494)
		(width 0.1016)
		(layer "F.Cu")
		(net "M_A_MA7")
	)
	(segment
		(start 108.909866 -49.626266)
		(end 108.92282 -49.626266)
		(width 0.1016)
		(layer "F.Cu")
		(net "M_A_MA7")
	)
	(segment
		(start 158.650178 -64.619378)
		(end 159.653478 -65.622678)
		(width 0.2413)
		(layer "F.Cu")
		(net "M_A_MA7")
	)
	(segment
		(start 158.650178 -62.59322)
		(end 158.650178 -64.619378)
		(width 0.2413)
		(layer "F.Cu")
		(net "M_A_MA7")
	)
	(via
		(at 108.92282 -49.626266)
		(size 0.4318)
		(drill 0.2032)
		(layers "F.Cu" "B.Cu")
		(net "M_A_MA7")
	)
	(via
		(at 159.169354 -67.434206)
		(size 0.4318)
		(drill 0.2032)
		(layers "F.Cu" "B.Cu")
		(net "M_A_MA7")
	)
	(segment
		(start 159.131254 -67.4624)
		(end 159.14116 -67.4624)
		(width 0.2413)
		(layer "B.Cu")
		(net "M_A_MA7")
	)
	(segment
		(start 158.650178 -70.79996)
		(end 158.650178 -67.943476)
		(width 0.2413)
		(layer "B.Cu")
		(net "M_A_MA7")
	)
	(segment
		(start 159.14116 -67.4624)
		(end 159.169354 -67.434206)
		(width 0.2413)
		(layer "B.Cu")
		(net "M_A_MA7")
	)
	(segment
		(start 158.650178 -67.943476)
		(end 159.131254 -67.4624)
		(width 0.2413)
		(layer "B.Cu")
		(net "M_A_MA7")
	)
	(segment
		(start 158.72587 -65.58407)
		(end 158.3436 -65.2018)
		(width 0.1905)
		(layer "In9.Cu")
		(net "M_A_MA7")
	)
	(segment
		(start 117.78615 -51.22545)
		(end 117.2464 -51.7652)
		(width 0.1016)
		(layer "In9.Cu")
		(net "M_A_MA7")
	)
	(segment
		(start 108.790232 -49.758854)
		(end 108.92282 -49.626266)
		(width 0.1016)
		(layer "In9.Cu")
		(net "M_A_MA7")
	)
	(segment
		(start 150.84679 -53.469794)
		(end 150.84679 -52.86121)
		(width 0.1905)
		(layer "In9.Cu")
		(net "M_A_MA7")
	)
	(segment
		(start 157.261814 -60.263786)
		(end 155.78455 -58.786522)
		(width 0.1905)
		(layer "In9.Cu")
		(net "M_A_MA7")
	)
	(segment
		(start 118.11635 -50.89525)
		(end 117.78615 -51.22545)
		(width 0.1905)
		(layer "In9.Cu")
		(net "M_A_MA7")
	)
	(segment
		(start 108.790232 -50.243232)
		(end 108.790232 -49.758854)
		(width 0.1016)
		(layer "In9.Cu")
		(net "M_A_MA7")
	)
	(segment
		(start 149.40788 -51.4223)
		(end 144.58696 -51.4223)
		(width 0.1905)
		(layer "In9.Cu")
		(net "M_A_MA7")
	)
	(segment
		(start 144.58696 -51.4223)
		(end 144.05991 -50.89525)
		(width 0.1905)
		(layer "In9.Cu")
		(net "M_A_MA7")
	)
	(segment
		(start 158.3436 -65.2018)
		(end 158.3436 -62.2808)
		(width 0.1905)
		(layer "In9.Cu")
		(net "M_A_MA7")
	)
	(segment
		(start 157.261814 -61.199014)
		(end 157.261814 -60.263786)
		(width 0.1905)
		(layer "In9.Cu")
		(net "M_A_MA7")
	)
	(segment
		(start 159.169354 -67.434206)
		(end 159.169354 -67.429634)
		(width 0.1905)
		(layer "In9.Cu")
		(net "M_A_MA7")
	)
	(segment
		(start 155.78455 -58.133234)
		(end 153.561796 -55.91048)
		(width 0.1905)
		(layer "In9.Cu")
		(net "M_A_MA7")
	)
	(segment
		(start 117.2464 -51.7652)
		(end 110.3122 -51.7652)
		(width 0.1016)
		(layer "In9.Cu")
		(net "M_A_MA7")
	)
	(segment
		(start 158.3436 -62.2808)
		(end 157.261814 -61.199014)
		(width 0.1905)
		(layer "In9.Cu")
		(net "M_A_MA7")
	)
	(segment
		(start 159.169354 -67.429634)
		(end 158.72587 -66.98615)
		(width 0.1905)
		(layer "In9.Cu")
		(net "M_A_MA7")
	)
	(segment
		(start 153.561796 -55.91048)
		(end 153.287476 -55.91048)
		(width 0.1905)
		(layer "In9.Cu")
		(net "M_A_MA7")
	)
	(segment
		(start 153.287476 -55.91048)
		(end 150.84679 -53.469794)
		(width 0.1905)
		(layer "In9.Cu")
		(net "M_A_MA7")
	)
	(segment
		(start 110.3122 -51.7652)
		(end 108.790232 -50.243232)
		(width 0.1016)
		(layer "In9.Cu")
		(net "M_A_MA7")
	)
	(segment
		(start 144.05991 -50.89525)
		(end 118.11635 -50.89525)
		(width 0.1905)
		(layer "In9.Cu")
		(net "M_A_MA7")
	)
	(segment
		(start 155.78455 -58.786522)
		(end 155.78455 -58.133234)
		(width 0.1905)
		(layer "In9.Cu")
		(net "M_A_MA7")
	)
	(segment
		(start 158.72587 -66.98615)
		(end 158.72587 -65.58407)
		(width 0.1905)
		(layer "In9.Cu")
		(net "M_A_MA7")
	)
	(segment
		(start 150.84679 -52.86121)
		(end 149.40788 -51.4223)
		(width 0.1905)
		(layer "In9.Cu")
		(net "M_A_MA7")
	)
	(segment
		(start 105.4354 -32.4866)
		(end 105.4354 -32.5628)
		(width 0.1016)
		(layer "F.Cu")
		(net "M_B_DQ32")
	)
	(segment
		(start 105.4354 -32.5628)
		(end 105.004108 -32.994092)
		(width 0.1016)
		(layer "F.Cu")
		(net "M_B_DQ32")
	)
	(segment
		(start 105.004108 -32.994092)
		(end 105.004108 -33.010094)
		(width 0.1016)
		(layer "F.Cu")
		(net "M_B_DQ32")
	)
	(segment
		(start 170.6499 -9.897364)
		(end 170.6499 -8.675878)
		(width 0.1778)
		(layer "F.Cu")
		(net "M_B_DQ32")
	)
	(segment
		(start 170.6499 -8.675878)
		(end 170.50893 -8.534908)
		(width 0.1778)
		(layer "F.Cu")
		(net "M_B_DQ32")
	)
	(segment
		(start 170.50893 -8.534908)
		(end 170.50893 -8.43026)
		(width 0.1778)
		(layer "F.Cu")
		(net "M_B_DQ32")
	)
	(via
		(at 105.4354 -32.4866)
		(size 0.4318)
		(drill 0.2032)
		(layers "F.Cu" "B.Cu")
		(net "M_B_DQ32")
	)
	(via
		(at 170.50893 -8.43026)
		(size 0.4318)
		(drill 0.2032)
		(layers "F.Cu" "B.Cu")
		(net "M_B_DQ32")
	)
	(segment
		(start 170.349926 -9.89076)
		(end 170.349926 -8.589264)
		(width 0.1778)
		(layer "B.Cu")
		(net "M_B_DQ32")
	)
	(segment
		(start 170.349926 -8.589264)
		(end 170.50893 -8.43026)
		(width 0.1778)
		(layer "B.Cu")
		(net "M_B_DQ32")
	)
	(segment
		(start 160.169606 -21.943822)
		(end 159.954214 -21.943822)
		(width 0.1524)
		(layer "In4.Cu")
		(net "M_B_DQ32")
	)
	(segment
		(start 159.498792 -21.4884)
		(end 159.2834 -21.4884)
		(width 0.1524)
		(layer "In4.Cu")
		(net "M_B_DQ32")
	)
	(segment
		(start 162.973258 -19.14017)
		(end 162.757358 -19.35607)
		(width 0.1524)
		(layer "In4.Cu")
		(net "M_B_DQ32")
	)
	(segment
		(start 162.541966 -19.35607)
		(end 162.086544 -18.900648)
		(width 0.1524)
		(layer "In4.Cu")
		(net "M_B_DQ32")
	)
	(segment
		(start 162.110674 -20.002754)
		(end 161.894774 -20.218654)
		(width 0.1524)
		(layer "In4.Cu")
		(net "M_B_DQ32")
	)
	(segment
		(start 162.110674 -19.787362)
		(end 162.110674 -20.002754)
		(width 0.1524)
		(layer "In4.Cu")
		(net "M_B_DQ32")
	)
	(segment
		(start 161.008568 -19.763232)
		(end 160.792668 -19.979132)
		(width 0.1524)
		(layer "In4.Cu")
		(net "M_B_DQ32")
	)
	(segment
		(start 106.945684 -28.969716)
		(end 107.823 -28.0924)
		(width 0.1016)
		(layer "In4.Cu")
		(net "M_B_DQ32")
	)
	(segment
		(start 159.954214 -21.943822)
		(end 159.498792 -21.4884)
		(width 0.1524)
		(layer "In4.Cu")
		(net "M_B_DQ32")
	)
	(segment
		(start 161.679382 -20.218654)
		(end 161.22396 -19.763232)
		(width 0.1524)
		(layer "In4.Cu")
		(net "M_B_DQ32")
	)
	(segment
		(start 161.655252 -19.33194)
		(end 162.110674 -19.787362)
		(width 0.1524)
		(layer "In4.Cu")
		(net "M_B_DQ32")
	)
	(segment
		(start 170.50893 -12.555474)
		(end 166.935404 -16.129)
		(width 0.1524)
		(layer "In4.Cu")
		(net "M_B_DQ32")
	)
	(segment
		(start 106.465116 -30.139132)
		(end 106.4641 -30.138116)
		(width 0.1016)
		(layer "In4.Cu")
		(net "M_B_DQ32")
	)
	(segment
		(start 161.655252 -19.116548)
		(end 161.655252 -19.33194)
		(width 0.1524)
		(layer "In4.Cu")
		(net "M_B_DQ32")
	)
	(segment
		(start 162.517836 -18.469356)
		(end 162.973258 -18.924778)
		(width 0.1524)
		(layer "In4.Cu")
		(net "M_B_DQ32")
	)
	(segment
		(start 155.142438 -26.250392)
		(end 154.939492 -26.0477)
		(width 0.1524)
		(layer "In4.Cu")
		(net "M_B_DQ32")
	)
	(segment
		(start 166.935404 -16.129)
		(end 164.6428 -16.129)
		(width 0.1524)
		(layer "In4.Cu")
		(net "M_B_DQ32")
	)
	(segment
		(start 155.370784 -25.616408)
		(end 155.57373 -25.8191)
		(width 0.1524)
		(layer "In4.Cu")
		(net "M_B_DQ32")
	)
	(segment
		(start 161.24809 -20.649946)
		(end 161.24809 -20.865338)
		(width 0.1524)
		(layer "In4.Cu")
		(net "M_B_DQ32")
	)
	(segment
		(start 164.6428 -16.129)
		(end 162.517836 -18.253964)
		(width 0.1524)
		(layer "In4.Cu")
		(net "M_B_DQ32")
	)
	(segment
		(start 154.7241 -26.0477)
		(end 154.305 -26.4668)
		(width 0.1524)
		(layer "In4.Cu")
		(net "M_B_DQ32")
	)
	(segment
		(start 160.145984 -20.625816)
		(end 159.930084 -20.841716)
		(width 0.1524)
		(layer "In4.Cu")
		(net "M_B_DQ32")
	)
	(segment
		(start 107.823 -28.0924)
		(end 109.8042 -28.0924)
		(width 0.1016)
		(layer "In4.Cu")
		(net "M_B_DQ32")
	)
	(segment
		(start 162.973258 -18.924778)
		(end 162.973258 -19.14017)
		(width 0.1524)
		(layer "In4.Cu")
		(net "M_B_DQ32")
	)
	(segment
		(start 111.4298 -26.4668)
		(end 110.871 -27.0256)
		(width 0.1524)
		(layer "In4.Cu")
		(net "M_B_DQ32")
	)
	(segment
		(start 160.361376 -20.625816)
		(end 160.145984 -20.625816)
		(width 0.1524)
		(layer "In4.Cu")
		(net "M_B_DQ32")
	)
	(segment
		(start 161.24809 -20.865338)
		(end 161.03219 -21.081238)
		(width 0.1524)
		(layer "In4.Cu")
		(net "M_B_DQ32")
	)
	(segment
		(start 155.57373 -26.034492)
		(end 155.35783 -26.250392)
		(width 0.1524)
		(layer "In4.Cu")
		(net "M_B_DQ32")
	)
	(segment
		(start 105.4608 -32.4612)
		(end 105.4608 -32.443928)
		(width 0.1016)
		(layer "In4.Cu")
		(net "M_B_DQ32")
	)
	(segment
		(start 161.03219 -21.081238)
		(end 160.816798 -21.081238)
		(width 0.1524)
		(layer "In4.Cu")
		(net "M_B_DQ32")
	)
	(segment
		(start 161.22396 -19.763232)
		(end 161.008568 -19.763232)
		(width 0.1524)
		(layer "In4.Cu")
		(net "M_B_DQ32")
	)
	(segment
		(start 170.50893 -8.43026)
		(end 170.50893 -12.555474)
		(width 0.1524)
		(layer "In4.Cu")
		(net "M_B_DQ32")
	)
	(segment
		(start 159.930084 -21.057108)
		(end 160.385506 -21.51253)
		(width 0.1524)
		(layer "In4.Cu")
		(net "M_B_DQ32")
	)
	(segment
		(start 160.385506 -21.727922)
		(end 160.169606 -21.943822)
		(width 0.1524)
		(layer "In4.Cu")
		(net "M_B_DQ32")
	)
	(segment
		(start 154.939492 -26.0477)
		(end 154.7241 -26.0477)
		(width 0.1524)
		(layer "In4.Cu")
		(net "M_B_DQ32")
	)
	(segment
		(start 109.8042 -28.0924)
		(end 110.871 -27.0256)
		(width 0.1016)
		(layer "In4.Cu")
		(net "M_B_DQ32")
	)
	(segment
		(start 155.35783 -26.250392)
		(end 155.142438 -26.250392)
		(width 0.1524)
		(layer "In4.Cu")
		(net "M_B_DQ32")
	)
	(segment
		(start 106.465116 -31.439612)
		(end 106.465116 -30.139132)
		(width 0.1016)
		(layer "In4.Cu")
		(net "M_B_DQ32")
	)
	(segment
		(start 159.930084 -20.841716)
		(end 159.930084 -21.057108)
		(width 0.1524)
		(layer "In4.Cu")
		(net "M_B_DQ32")
	)
	(segment
		(start 106.469688 -29.856684)
		(end 106.469688 -29.445712)
		(width 0.1016)
		(layer "In4.Cu")
		(net "M_B_DQ32")
	)
	(segment
		(start 106.4641 -29.862272)
		(end 106.469688 -29.856684)
		(width 0.1016)
		(layer "In4.Cu")
		(net "M_B_DQ32")
	)
	(segment
		(start 106.4641 -30.138116)
		(end 106.4641 -29.862272)
		(width 0.1016)
		(layer "In4.Cu")
		(net "M_B_DQ32")
	)
	(segment
		(start 161.894774 -20.218654)
		(end 161.679382 -20.218654)
		(width 0.1524)
		(layer "In4.Cu")
		(net "M_B_DQ32")
	)
	(segment
		(start 106.469688 -29.445712)
		(end 106.727498 -29.187902)
		(width 0.1016)
		(layer "In4.Cu")
		(net "M_B_DQ32")
	)
	(segment
		(start 105.4354 -32.4866)
		(end 105.4608 -32.4612)
		(width 0.1016)
		(layer "In4.Cu")
		(net "M_B_DQ32")
	)
	(segment
		(start 162.517836 -18.253964)
		(end 162.517836 -18.469356)
		(width 0.1524)
		(layer "In4.Cu")
		(net "M_B_DQ32")
	)
	(segment
		(start 106.730038 -29.187902)
		(end 106.945684 -28.972256)
		(width 0.1016)
		(layer "In4.Cu")
		(net "M_B_DQ32")
	)
	(segment
		(start 160.816798 -21.081238)
		(end 160.361376 -20.625816)
		(width 0.1524)
		(layer "In4.Cu")
		(net "M_B_DQ32")
	)
	(segment
		(start 160.792668 -20.194524)
		(end 161.24809 -20.649946)
		(width 0.1524)
		(layer "In4.Cu")
		(net "M_B_DQ32")
	)
	(segment
		(start 105.4608 -32.443928)
		(end 106.465116 -31.439612)
		(width 0.1016)
		(layer "In4.Cu")
		(net "M_B_DQ32")
	)
	(segment
		(start 155.370784 -25.401016)
		(end 155.370784 -25.616408)
		(width 0.1524)
		(layer "In4.Cu")
		(net "M_B_DQ32")
	)
	(segment
		(start 106.945684 -28.972256)
		(end 106.945684 -28.969716)
		(width 0.1016)
		(layer "In4.Cu")
		(net "M_B_DQ32")
	)
	(segment
		(start 160.385506 -21.51253)
		(end 160.385506 -21.727922)
		(width 0.1524)
		(layer "In4.Cu")
		(net "M_B_DQ32")
	)
	(segment
		(start 162.757358 -19.35607)
		(end 162.541966 -19.35607)
		(width 0.1524)
		(layer "In4.Cu")
		(net "M_B_DQ32")
	)
	(segment
		(start 160.792668 -19.979132)
		(end 160.792668 -20.194524)
		(width 0.1524)
		(layer "In4.Cu")
		(net "M_B_DQ32")
	)
	(segment
		(start 155.57373 -25.8191)
		(end 155.57373 -26.034492)
		(width 0.1524)
		(layer "In4.Cu")
		(net "M_B_DQ32")
	)
	(segment
		(start 159.2834 -21.4884)
		(end 155.370784 -25.401016)
		(width 0.1524)
		(layer "In4.Cu")
		(net "M_B_DQ32")
	)
	(segment
		(start 162.086544 -18.900648)
		(end 161.871152 -18.900648)
		(width 0.1524)
		(layer "In4.Cu")
		(net "M_B_DQ32")
	)
	(segment
		(start 161.871152 -18.900648)
		(end 161.655252 -19.116548)
		(width 0.1524)
		(layer "In4.Cu")
		(net "M_B_DQ32")
	)
	(segment
		(start 106.727498 -29.187902)
		(end 106.730038 -29.187902)
		(width 0.1016)
		(layer "In4.Cu")
		(net "M_B_DQ32")
	)
	(segment
		(start 154.305 -26.4668)
		(end 111.4298 -26.4668)
		(width 0.1524)
		(layer "In4.Cu")
		(net "M_B_DQ32")
	)
	(via
		(at 39.115238 -44.69765)
		(size 0.7112)
		(drill 0.3556)
		(layers "F.Cu" "B.Cu")
		(net "XTAL_CLK_GEN_OUT")
	)
	(segment
		(start 35.941 -43.4721)
		(end 36.157154 -43.688254)
		(width 0.1143)
		(layer "B.Cu")
		(net "XTAL_CLK_GEN_OUT")
	)
	(segment
		(start 38.3032 -43.561)
		(end 38.3032 -43.885612)
		(width 0.1143)
		(layer "B.Cu")
		(net "XTAL_CLK_GEN_OUT")
	)
	(segment
		(start 38.3032 -42.8244)
		(end 38.1508 -42.672)
		(width 0.1143)
		(layer "B.Cu")
		(net "XTAL_CLK_GEN_OUT")
	)
	(segment
		(start 38.3032 -43.561)
		(end 38.3032 -42.8244)
		(width 0.1143)
		(layer "B.Cu")
		(net "XTAL_CLK_GEN_OUT")
	)
	(segment
		(start 38.3032 -43.885612)
		(end 39.115238 -44.69765)
		(width 0.1143)
		(layer "B.Cu")
		(net "XTAL_CLK_GEN_OUT")
	)
	(segment
		(start 35.941 -42.665904)
		(end 35.941 -43.4721)
		(width 0.1143)
		(layer "B.Cu")
		(net "XTAL_CLK_GEN_OUT")
	)
	(segment
		(start 36.157154 -43.688254)
		(end 38.175946 -43.688254)
		(width 0.1143)
		(layer "B.Cu")
		(net "XTAL_CLK_GEN_OUT")
	)
	(segment
		(start 38.175946 -43.688254)
		(end 38.3032 -43.561)
		(width 0.1143)
		(layer "B.Cu")
		(net "XTAL_CLK_GEN_OUT")
	)
	(segment
		(start 85.171788 -34.330386)
		(end 85.166962 -34.335212)
		(width 0.1143)
		(layer "F.Cu")
		(net "GBE_SMBALRT#")
	)
	(segment
		(start 54.595268 -17.079468)
		(end 53.926486 -16.410686)
		(width 0.1143)
		(layer "F.Cu")
		(net "GBE_SMBALRT#")
	)
	(segment
		(start 85.171788 -33.472374)
		(end 85.171788 -34.330386)
		(width 0.1143)
		(layer "F.Cu")
		(net "GBE_SMBALRT#")
	)
	(segment
		(start 53.926486 -16.410686)
		(end 53.48224 -16.410686)
		(width 0.1143)
		(layer "F.Cu")
		(net "GBE_SMBALRT#")
	)
	(via
		(at 54.595268 -17.079468)
		(size 0.508)
		(drill 0.254)
		(layers "F.Cu" "B.Cu")
		(net "GBE_SMBALRT#")
	)
	(via
		(at 75.5904 -28.70835)
		(size 0.7112)
		(drill 0.3556)
		(layers "F.Cu" "B.Cu")
		(net "GBE_SMBALRT#")
	)
	(via
		(at 85.166962 -34.335212)
		(size 0.4318)
		(drill 0.2032)
		(layers "F.Cu" "B.Cu")
		(net "GBE_SMBALRT#")
	)
	(segment
		(start 81.516982 -33.528762)
		(end 80.544162 -33.528762)
		(width 0.1143)
		(layer "B.Cu")
		(net "GBE_SMBALRT#")
	)
	(segment
		(start 80.544162 -33.528762)
		(end 79.8322 -32.8168)
		(width 0.1143)
		(layer "B.Cu")
		(net "GBE_SMBALRT#")
	)
	(segment
		(start 79.2099 -32.1945)
		(end 79.8322 -32.8168)
		(width 0.1143)
		(layer "B.Cu")
		(net "GBE_SMBALRT#")
	)
	(segment
		(start 74.4728 -27.94)
		(end 75.24115 -28.70835)
		(width 0.1143)
		(layer "B.Cu")
		(net "GBE_SMBALRT#")
	)
	(segment
		(start 83.160616 -33.54578)
		(end 82.984594 -33.369758)
		(width 0.1143)
		(layer "B.Cu")
		(net "GBE_SMBALRT#")
	)
	(segment
		(start 84.7725 -33.94075)
		(end 84.478114 -33.94075)
		(width 0.1143)
		(layer "B.Cu")
		(net "GBE_SMBALRT#")
	)
	(segment
		(start 77.889354 -32.1945)
		(end 79.2099 -32.1945)
		(width 0.1143)
		(layer "B.Cu")
		(net "GBE_SMBALRT#")
	)
	(segment
		(start 82.984594 -33.369758)
		(end 81.675986 -33.369758)
		(width 0.1143)
		(layer "B.Cu")
		(net "GBE_SMBALRT#")
	)
	(segment
		(start 84.478114 -33.94075)
		(end 84.083144 -33.54578)
		(width 0.1143)
		(layer "B.Cu")
		(net "GBE_SMBALRT#")
	)
	(segment
		(start 81.675986 -33.369758)
		(end 81.516982 -33.528762)
		(width 0.1143)
		(layer "B.Cu")
		(net "GBE_SMBALRT#")
	)
	(segment
		(start 76.6572 -29.77515)
		(end 76.6572 -30.962346)
		(width 0.1143)
		(layer "B.Cu")
		(net "GBE_SMBALRT#")
	)
	(segment
		(start 85.166962 -34.335212)
		(end 84.7725 -33.94075)
		(width 0.1143)
		(layer "B.Cu")
		(net "GBE_SMBALRT#")
	)
	(segment
		(start 76.6572 -30.962346)
		(end 77.889354 -32.1945)
		(width 0.1143)
		(layer "B.Cu")
		(net "GBE_SMBALRT#")
	)
	(segment
		(start 75.5904 -28.70835)
		(end 76.6572 -29.77515)
		(width 0.1143)
		(layer "B.Cu")
		(net "GBE_SMBALRT#")
	)
	(segment
		(start 84.083144 -33.54578)
		(end 83.160616 -33.54578)
		(width 0.1143)
		(layer "B.Cu")
		(net "GBE_SMBALRT#")
	)
	(segment
		(start 75.24115 -28.70835)
		(end 75.5904 -28.70835)
		(width 0.1143)
		(layer "B.Cu")
		(net "GBE_SMBALRT#")
	)
	(segment
		(start 78.78191 -34.464752)
		(end 78.715108 -34.39795)
		(width 0.0889)
		(layer "In7.Cu")
		(net "GBE_SMBALRT#")
	)
	(segment
		(start 53.68925 -22.16785)
		(end 53.2257 -21.7043)
		(width 0.0889)
		(layer "In7.Cu")
		(net "GBE_SMBALRT#")
	)
	(segment
		(start 77.691742 -33.855152)
		(end 77.691742 -32.944562)
		(width 0.0889)
		(layer "In7.Cu")
		(net "GBE_SMBALRT#")
	)
	(segment
		(start 54.1909 -22.16785)
		(end 53.68925 -22.16785)
		(width 0.0889)
		(layer "In7.Cu")
		(net "GBE_SMBALRT#")
	)
	(segment
		(start 77.691742 -32.944562)
		(end 77.806296 -32.830008)
		(width 0.0889)
		(layer "In7.Cu")
		(net "GBE_SMBALRT#")
	)
	(segment
		(start 74.318368 -27.95905)
		(end 70.863968 -27.95905)
		(width 0.0889)
		(layer "In7.Cu")
		(net "GBE_SMBALRT#")
	)
	(segment
		(start 78.23454 -34.39795)
		(end 77.691742 -33.855152)
		(width 0.0889)
		(layer "In7.Cu")
		(net "GBE_SMBALRT#")
	)
	(segment
		(start 80.861408 -34.464752)
		(end 78.78191 -34.464752)
		(width 0.0889)
		(layer "In7.Cu")
		(net "GBE_SMBALRT#")
	)
	(segment
		(start 76.129896 -30.565344)
		(end 76.129896 -29.770578)
		(width 0.0889)
		(layer "In7.Cu")
		(net "GBE_SMBALRT#")
	)
	(segment
		(start 77.806296 -32.241744)
		(end 76.129896 -30.565344)
		(width 0.0889)
		(layer "In7.Cu")
		(net "GBE_SMBALRT#")
	)
	(segment
		(start 82.219546 -35.102292)
		(end 81.498948 -35.102292)
		(width 0.0889)
		(layer "In7.Cu")
		(net "GBE_SMBALRT#")
	)
	(segment
		(start 53.2257 -18.448782)
		(end 54.173882 -17.5006)
		(width 0.0889)
		(layer "In7.Cu")
		(net "GBE_SMBALRT#")
	)
	(segment
		(start 54.174136 -17.5006)
		(end 54.595268 -17.079468)
		(width 0.0889)
		(layer "In7.Cu")
		(net "GBE_SMBALRT#")
	)
	(segment
		(start 82.599784 -34.722308)
		(end 82.219546 -35.102292)
		(width 0.0889)
		(layer "In7.Cu")
		(net "GBE_SMBALRT#")
	)
	(segment
		(start 66.494914 -24.505158)
		(end 65.978786 -25.021286)
		(width 0.0889)
		(layer "In7.Cu")
		(net "GBE_SMBALRT#")
	)
	(segment
		(start 84.360004 -34.335212)
		(end 83.972908 -34.722308)
		(width 0.0889)
		(layer "In7.Cu")
		(net "GBE_SMBALRT#")
	)
	(segment
		(start 85.166962 -34.335212)
		(end 84.360004 -34.335212)
		(width 0.0889)
		(layer "In7.Cu")
		(net "GBE_SMBALRT#")
	)
	(segment
		(start 65.978786 -25.021286)
		(end 63.30188 -25.021286)
		(width 0.0889)
		(layer "In7.Cu")
		(net "GBE_SMBALRT#")
	)
	(segment
		(start 83.972908 -34.722308)
		(end 82.599784 -34.722308)
		(width 0.0889)
		(layer "In7.Cu")
		(net "GBE_SMBALRT#")
	)
	(segment
		(start 60.308744 -22.02815)
		(end 54.3306 -22.02815)
		(width 0.0889)
		(layer "In7.Cu")
		(net "GBE_SMBALRT#")
	)
	(segment
		(start 53.2257 -21.7043)
		(end 53.2257 -18.448782)
		(width 0.0889)
		(layer "In7.Cu")
		(net "GBE_SMBALRT#")
	)
	(segment
		(start 81.498948 -35.102292)
		(end 80.861408 -34.464752)
		(width 0.0889)
		(layer "In7.Cu")
		(net "GBE_SMBALRT#")
	)
	(segment
		(start 54.173882 -17.5006)
		(end 54.174136 -17.5006)
		(width 0.0889)
		(layer "In7.Cu")
		(net "GBE_SMBALRT#")
	)
	(segment
		(start 63.30188 -25.021286)
		(end 60.308744 -22.02815)
		(width 0.0889)
		(layer "In7.Cu")
		(net "GBE_SMBALRT#")
	)
	(segment
		(start 77.806296 -32.830008)
		(end 77.806296 -32.241744)
		(width 0.0889)
		(layer "In7.Cu")
		(net "GBE_SMBALRT#")
	)
	(segment
		(start 76.129896 -29.770578)
		(end 74.318368 -27.95905)
		(width 0.0889)
		(layer "In7.Cu")
		(net "GBE_SMBALRT#")
	)
	(segment
		(start 78.715108 -34.39795)
		(end 78.23454 -34.39795)
		(width 0.0889)
		(layer "In7.Cu")
		(net "GBE_SMBALRT#")
	)
	(segment
		(start 54.3306 -22.02815)
		(end 54.1909 -22.16785)
		(width 0.0889)
		(layer "In7.Cu")
		(net "GBE_SMBALRT#")
	)
	(segment
		(start 70.863968 -27.95905)
		(end 67.410076 -24.505158)
		(width 0.0889)
		(layer "In7.Cu")
		(net "GBE_SMBALRT#")
	)
	(segment
		(start 67.410076 -24.505158)
		(end 66.494914 -24.505158)
		(width 0.0889)
		(layer "In7.Cu")
		(net "GBE_SMBALRT#")
	)
	(segment
		(start 178.449986 -62.59322)
		(end 178.449986 -63.375286)
		(width 0.1778)
		(layer "F.Cu")
		(net "M_A_DQ16")
	)
	(segment
		(start 108.052108 -45.628814)
		(end 108.099606 -45.628814)
		(width 0.1016)
		(layer "F.Cu")
		(net "M_A_DQ16")
	)
	(segment
		(start 108.43768 -45.29074)
		(end 108.45038 -45.29074)
		(width 0.1016)
		(layer "F.Cu")
		(net "M_A_DQ16")
	)
	(segment
		(start 108.099606 -45.628814)
		(end 108.43768 -45.29074)
		(width 0.1016)
		(layer "F.Cu")
		(net "M_A_DQ16")
	)
	(segment
		(start 178.449986 -63.375286)
		(end 178.861212 -63.786512)
		(width 0.1778)
		(layer "F.Cu")
		(net "M_A_DQ16")
	)
	(segment
		(start 178.861212 -63.786512)
		(end 178.861212 -64.056006)
		(width 0.1778)
		(layer "F.Cu")
		(net "M_A_DQ16")
	)
	(via
		(at 108.45038 -45.29074)
		(size 0.4318)
		(drill 0.2032)
		(layers "F.Cu" "B.Cu")
		(net "M_A_DQ16")
	)
	(via
		(at 178.861212 -64.056006)
		(size 0.4318)
		(drill 0.2032)
		(layers "F.Cu" "B.Cu")
		(net "M_A_DQ16")
	)
	(segment
		(start 179.350162 -62.599824)
		(end 179.350162 -63.567056)
		(width 0.1778)
		(layer "B.Cu")
		(net "M_A_DQ16")
	)
	(segment
		(start 179.350162 -63.567056)
		(end 178.861212 -64.056006)
		(width 0.1778)
		(layer "B.Cu")
		(net "M_A_DQ16")
	)
	(segment
		(start 151.675592 -50.165508)
		(end 151.459692 -49.949608)
		(width 0.1524)
		(layer "In4.Cu")
		(net "M_A_DQ16")
	)
	(segment
		(start 153.900378 -52.59197)
		(end 153.900378 -52.39004)
		(width 0.1524)
		(layer "In4.Cu")
		(net "M_A_DQ16")
	)
	(segment
		(start 152.011126 -51.770534)
		(end 152.538176 -51.243484)
		(width 0.1524)
		(layer "In4.Cu")
		(net "M_A_DQ16")
	)
	(segment
		(start 124.551694 -48.0568)
		(end 124.246894 -48.0568)
		(width 0.1524)
		(layer "In4.Cu")
		(net "M_A_DQ16")
	)
	(segment
		(start 154.789124 -53.467)
		(end 154.115008 -53.467)
		(width 0.1524)
		(layer "In4.Cu")
		(net "M_A_DQ16")
	)
	(segment
		(start 120.330722 -47.9044)
		(end 120.178322 -48.0568)
		(width 0.1524)
		(layer "In4.Cu")
		(net "M_A_DQ16")
	)
	(segment
		(start 178.861212 -63.062612)
		(end 175.3235 -59.5249)
		(width 0.1524)
		(layer "In4.Cu")
		(net "M_A_DQ16")
	)
	(segment
		(start 153.356564 -52.2732)
		(end 152.2984 -52.2732)
		(width 0.1524)
		(layer "In4.Cu")
		(net "M_A_DQ16")
	)
	(segment
		(start 114.4524 -48.4632)
		(end 111.524034 -45.534834)
		(width 0.1016)
		(layer "In4.Cu")
		(net "M_A_DQ16")
	)
	(segment
		(start 151.675846 -51.027838)
		(end 151.459946 -50.811938)
		(width 0.1524)
		(layer "In4.Cu")
		(net "M_A_DQ16")
	)
	(segment
		(start 116.08562 -48.387)
		(end 116.08562 -48.2092)
		(width 0.1524)
		(layer "In4.Cu")
		(net "M_A_DQ16")
	)
	(segment
		(start 123.332494 -48.0568)
		(end 123.027694 -48.0568)
		(width 0.1524)
		(layer "In4.Cu")
		(net "M_A_DQ16")
	)
	(segment
		(start 154.115008 -53.467)
		(end 153.677874 -53.029866)
		(width 0.1524)
		(layer "In4.Cu")
		(net "M_A_DQ16")
	)
	(segment
		(start 152.538176 -51.028092)
		(end 152.322276 -50.812192)
		(width 0.1524)
		(layer "In4.Cu")
		(net "M_A_DQ16")
	)
	(segment
		(start 164.338 -54.7116)
		(end 164.338 -54.1274)
		(width 0.1524)
		(layer "In4.Cu")
		(net "M_A_DQ16")
	)
	(segment
		(start 124.094494 -47.7012)
		(end 123.942094 -47.5488)
		(width 0.1524)
		(layer "In4.Cu")
		(net "M_A_DQ16")
	)
	(segment
		(start 120.178322 -48.0568)
		(end 120.178322 -48.387)
		(width 0.1524)
		(layer "In4.Cu")
		(net "M_A_DQ16")
	)
	(segment
		(start 124.704094 -47.9044)
		(end 124.551694 -48.0568)
		(width 0.1524)
		(layer "In4.Cu")
		(net "M_A_DQ16")
	)
	(segment
		(start 115.47602 -48.387)
		(end 115.32362 -48.5394)
		(width 0.1524)
		(layer "In4.Cu")
		(net "M_A_DQ16")
	)
	(segment
		(start 123.637294 -47.5488)
		(end 123.484894 -47.7012)
		(width 0.1524)
		(layer "In4.Cu")
		(net "M_A_DQ16")
	)
	(segment
		(start 123.942094 -47.5488)
		(end 123.637294 -47.5488)
		(width 0.1524)
		(layer "In4.Cu")
		(net "M_A_DQ16")
	)
	(segment
		(start 165.619938 -53.975)
		(end 165.1 -53.975)
		(width 0.1524)
		(layer "In4.Cu")
		(net "M_A_DQ16")
	)
	(segment
		(start 124.704094 -47.704756)
		(end 124.704094 -47.9044)
		(width 0.1524)
		(layer "In4.Cu")
		(net "M_A_DQ16")
	)
	(segment
		(start 151.459946 -50.596546)
		(end 151.675592 -50.3809)
		(width 0.1524)
		(layer "In4.Cu")
		(net "M_A_DQ16")
	)
	(segment
		(start 151.2443 -49.949608)
		(end 151.028654 -50.165254)
		(width 0.1524)
		(layer "In4.Cu")
		(net "M_A_DQ16")
	)
	(segment
		(start 153.677874 -52.814474)
		(end 153.900378 -52.59197)
		(width 0.1524)
		(layer "In4.Cu")
		(net "M_A_DQ16")
	)
	(segment
		(start 164.338 -54.1274)
		(end 164.1856 -53.975)
		(width 0.1524)
		(layer "In4.Cu")
		(net "M_A_DQ16")
	)
	(segment
		(start 152.106884 -50.812192)
		(end 151.891238 -51.027838)
		(width 0.1524)
		(layer "In4.Cu")
		(net "M_A_DQ16")
	)
	(segment
		(start 124.094494 -47.9044)
		(end 124.094494 -47.7012)
		(width 0.1524)
		(layer "In4.Cu")
		(net "M_A_DQ16")
	)
	(segment
		(start 122.449844 -47.552356)
		(end 121.4628 -48.5394)
		(width 0.1524)
		(layer "In4.Cu")
		(net "M_A_DQ16")
	)
	(segment
		(start 151.459692 -49.949608)
		(end 151.2443 -49.949608)
		(width 0.1524)
		(layer "In4.Cu")
		(net "M_A_DQ16")
	)
	(segment
		(start 109.967776 -45.4914)
		(end 108.65104 -45.4914)
		(width 0.1016)
		(layer "In4.Cu")
		(net "M_A_DQ16")
	)
	(segment
		(start 143.850106 -48.0568)
		(end 125.466094 -48.0568)
		(width 0.1524)
		(layer "In4.Cu")
		(net "M_A_DQ16")
	)
	(segment
		(start 164.9476 -54.7116)
		(end 164.7952 -54.864)
		(width 0.1524)
		(layer "In4.Cu")
		(net "M_A_DQ16")
	)
	(segment
		(start 123.484894 -47.7012)
		(end 123.484894 -47.9044)
		(width 0.1524)
		(layer "In4.Cu")
		(net "M_A_DQ16")
	)
	(segment
		(start 152.322276 -50.812192)
		(end 152.106884 -50.812192)
		(width 0.1524)
		(layer "In4.Cu")
		(net "M_A_DQ16")
	)
	(segment
		(start 122.875294 -47.704756)
		(end 122.722894 -47.552356)
		(width 0.1524)
		(layer "In4.Cu")
		(net "M_A_DQ16")
	)
	(segment
		(start 120.787922 -48.387)
		(end 120.787922 -48.0568)
		(width 0.1524)
		(layer "In4.Cu")
		(net "M_A_DQ16")
	)
	(segment
		(start 178.861212 -64.056006)
		(end 178.861212 -63.062612)
		(width 0.1524)
		(layer "In4.Cu")
		(net "M_A_DQ16")
	)
	(segment
		(start 123.027694 -48.0568)
		(end 122.875294 -47.9044)
		(width 0.1524)
		(layer "In4.Cu")
		(net "M_A_DQ16")
	)
	(segment
		(start 123.484894 -47.9044)
		(end 123.332494 -48.0568)
		(width 0.1524)
		(layer "In4.Cu")
		(net "M_A_DQ16")
	)
	(segment
		(start 153.469086 -52.160678)
		(end 153.356564 -52.2732)
		(width 0.1524)
		(layer "In4.Cu")
		(net "M_A_DQ16")
	)
	(segment
		(start 164.9476 -54.1274)
		(end 164.9476 -54.7116)
		(width 0.1524)
		(layer "In4.Cu")
		(net "M_A_DQ16")
	)
	(segment
		(start 125.313694 -47.704756)
		(end 125.161294 -47.552356)
		(width 0.1524)
		(layer "In4.Cu")
		(net "M_A_DQ16")
	)
	(segment
		(start 150.381208 -49.7332)
		(end 145.526506 -49.7332)
		(width 0.1524)
		(layer "In4.Cu")
		(net "M_A_DQ16")
	)
	(segment
		(start 164.7952 -54.864)
		(end 164.4904 -54.864)
		(width 0.1524)
		(layer "In4.Cu")
		(net "M_A_DQ16")
	)
	(segment
		(start 122.875294 -47.9044)
		(end 122.875294 -47.704756)
		(width 0.1524)
		(layer "In4.Cu")
		(net "M_A_DQ16")
	)
	(segment
		(start 155.297124 -53.975)
		(end 154.789124 -53.467)
		(width 0.1524)
		(layer "In4.Cu")
		(net "M_A_DQ16")
	)
	(segment
		(start 151.028654 -50.165254)
		(end 150.813262 -50.165254)
		(width 0.1524)
		(layer "In4.Cu")
		(net "M_A_DQ16")
	)
	(segment
		(start 120.178322 -48.387)
		(end 120.025922 -48.5394)
		(width 0.1524)
		(layer "In4.Cu")
		(net "M_A_DQ16")
	)
	(segment
		(start 153.677874 -53.029866)
		(end 153.677874 -52.814474)
		(width 0.1524)
		(layer "In4.Cu")
		(net "M_A_DQ16")
	)
	(segment
		(start 152.538176 -51.243484)
		(end 152.538176 -51.028092)
		(width 0.1524)
		(layer "In4.Cu")
		(net "M_A_DQ16")
	)
	(segment
		(start 115.62842 -48.0568)
		(end 115.47602 -48.2092)
		(width 0.1524)
		(layer "In4.Cu")
		(net "M_A_DQ16")
	)
	(segment
		(start 150.813262 -50.165254)
		(end 150.381208 -49.7332)
		(width 0.1524)
		(layer "In4.Cu")
		(net "M_A_DQ16")
	)
	(segment
		(start 153.671016 -52.160678)
		(end 153.469086 -52.160678)
		(width 0.1524)
		(layer "In4.Cu")
		(net "M_A_DQ16")
	)
	(segment
		(start 122.722894 -47.552356)
		(end 122.449844 -47.552356)
		(width 0.1524)
		(layer "In4.Cu")
		(net "M_A_DQ16")
	)
	(segment
		(start 110.01121 -45.534834)
		(end 109.967776 -45.4914)
		(width 0.1016)
		(layer "In4.Cu")
		(net "M_A_DQ16")
	)
	(segment
		(start 125.466094 -48.0568)
		(end 125.313694 -47.9044)
		(width 0.1524)
		(layer "In4.Cu")
		(net "M_A_DQ16")
	)
	(segment
		(start 116.23802 -48.5394)
		(end 116.08562 -48.387)
		(width 0.1524)
		(layer "In4.Cu")
		(net "M_A_DQ16")
	)
	(segment
		(start 111.524034 -45.534834)
		(end 110.01121 -45.534834)
		(width 0.1016)
		(layer "In4.Cu")
		(net "M_A_DQ16")
	)
	(segment
		(start 145.526506 -49.7332)
		(end 143.850106 -48.0568)
		(width 0.1524)
		(layer "In4.Cu")
		(net "M_A_DQ16")
	)
	(segment
		(start 165.1 -53.975)
		(end 164.9476 -54.1274)
		(width 0.1524)
		(layer "In4.Cu")
		(net "M_A_DQ16")
	)
	(segment
		(start 120.940322 -48.5394)
		(end 120.787922 -48.387)
		(width 0.1524)
		(layer "In4.Cu")
		(net "M_A_DQ16")
	)
	(segment
		(start 151.891238 -51.027838)
		(end 151.675846 -51.027838)
		(width 0.1524)
		(layer "In4.Cu")
		(net "M_A_DQ16")
	)
	(segment
		(start 125.161294 -47.552356)
		(end 124.856494 -47.552356)
		(width 0.1524)
		(layer "In4.Cu")
		(net "M_A_DQ16")
	)
	(segment
		(start 116.08562 -48.2092)
		(end 115.93322 -48.0568)
		(width 0.1524)
		(layer "In4.Cu")
		(net "M_A_DQ16")
	)
	(segment
		(start 120.025922 -48.5394)
		(end 116.23802 -48.5394)
		(width 0.1524)
		(layer "In4.Cu")
		(net "M_A_DQ16")
	)
	(segment
		(start 171.169838 -59.5249)
		(end 165.619938 -53.975)
		(width 0.1524)
		(layer "In4.Cu")
		(net "M_A_DQ16")
	)
	(segment
		(start 175.3235 -59.5249)
		(end 171.169838 -59.5249)
		(width 0.1524)
		(layer "In4.Cu")
		(net "M_A_DQ16")
	)
	(segment
		(start 120.635522 -47.9044)
		(end 120.330722 -47.9044)
		(width 0.1524)
		(layer "In4.Cu")
		(net "M_A_DQ16")
	)
	(segment
		(start 152.2984 -52.2732)
		(end 152.011126 -51.985926)
		(width 0.1524)
		(layer "In4.Cu")
		(net "M_A_DQ16")
	)
	(segment
		(start 124.856494 -47.552356)
		(end 124.704094 -47.704756)
		(width 0.1524)
		(layer "In4.Cu")
		(net "M_A_DQ16")
	)
	(segment
		(start 120.787922 -48.0568)
		(end 120.635522 -47.9044)
		(width 0.1524)
		(layer "In4.Cu")
		(net "M_A_DQ16")
	)
	(segment
		(start 164.1856 -53.975)
		(end 155.297124 -53.975)
		(width 0.1524)
		(layer "In4.Cu")
		(net "M_A_DQ16")
	)
	(segment
		(start 152.011126 -51.985926)
		(end 152.011126 -51.770534)
		(width 0.1524)
		(layer "In4.Cu")
		(net "M_A_DQ16")
	)
	(segment
		(start 114.5286 -48.5394)
		(end 114.4524 -48.4632)
		(width 0.1524)
		(layer "In4.Cu")
		(net "M_A_DQ16")
	)
	(segment
		(start 115.93322 -48.0568)
		(end 115.62842 -48.0568)
		(width 0.1524)
		(layer "In4.Cu")
		(net "M_A_DQ16")
	)
	(segment
		(start 151.675592 -50.3809)
		(end 151.675592 -50.165508)
		(width 0.1524)
		(layer "In4.Cu")
		(net "M_A_DQ16")
	)
	(segment
		(start 121.4628 -48.5394)
		(end 120.940322 -48.5394)
		(width 0.1524)
		(layer "In4.Cu")
		(net "M_A_DQ16")
	)
	(segment
		(start 108.65104 -45.4914)
		(end 108.45038 -45.29074)
		(width 0.1016)
		(layer "In4.Cu")
		(net "M_A_DQ16")
	)
	(segment
		(start 153.900378 -52.39004)
		(end 153.671016 -52.160678)
		(width 0.1524)
		(layer "In4.Cu")
		(net "M_A_DQ16")
	)
	(segment
		(start 124.246894 -48.0568)
		(end 124.094494 -47.9044)
		(width 0.1524)
		(layer "In4.Cu")
		(net "M_A_DQ16")
	)
	(segment
		(start 115.32362 -48.5394)
		(end 114.5286 -48.5394)
		(width 0.1524)
		(layer "In4.Cu")
		(net "M_A_DQ16")
	)
	(segment
		(start 151.459946 -50.811938)
		(end 151.459946 -50.596546)
		(width 0.1524)
		(layer "In4.Cu")
		(net "M_A_DQ16")
	)
	(segment
		(start 125.313694 -47.9044)
		(end 125.313694 -47.704756)
		(width 0.1524)
		(layer "In4.Cu")
		(net "M_A_DQ16")
	)
	(segment
		(start 115.47602 -48.2092)
		(end 115.47602 -48.387)
		(width 0.1524)
		(layer "In4.Cu")
		(net "M_A_DQ16")
	)
	(segment
		(start 164.4904 -54.864)
		(end 164.338 -54.7116)
		(width 0.1524)
		(layer "In4.Cu")
		(net "M_A_DQ16")
	)
	(segment
		(start 91.821 -25.527)
		(end 92.083128 -25.527)
		(width 0.1016)
		(layer "F.Cu")
		(net "M_B_DQ4")
	)
	(segment
		(start 90.9066 -25.1968)
		(end 90.9828 -25.273)
		(width 0.1016)
		(layer "F.Cu")
		(net "M_B_DQ4")
	)
	(segment
		(start 91.567 -25.273)
		(end 91.821 -25.527)
		(width 0.1016)
		(layer "F.Cu")
		(net "M_B_DQ4")
	)
	(segment
		(start 90.9828 -25.273)
		(end 91.567 -25.273)
		(width 0.1016)
		(layer "F.Cu")
		(net "M_B_DQ4")
	)
	(segment
		(start 129.549906 -3.370072)
		(end 129.2098 -3.710178)
		(width 0.1778)
		(layer "F.Cu")
		(net "M_B_DQ4")
	)
	(segment
		(start 129.549906 -1.68402)
		(end 129.549906 -3.370072)
		(width 0.1778)
		(layer "F.Cu")
		(net "M_B_DQ4")
	)
	(segment
		(start 92.507562 -25.951434)
		(end 92.888308 -25.951434)
		(width 0.1016)
		(layer "F.Cu")
		(net "M_B_DQ4")
	)
	(segment
		(start 92.083128 -25.527)
		(end 92.507562 -25.951434)
		(width 0.1016)
		(layer "F.Cu")
		(net "M_B_DQ4")
	)
	(via
		(at 90.9066 -25.1968)
		(size 0.4318)
		(drill 0.2032)
		(layers "F.Cu" "B.Cu")
		(net "M_B_DQ4")
	)
	(via
		(at 129.2098 -3.710178)
		(size 0.4318)
		(drill 0.2032)
		(layers "F.Cu" "B.Cu")
		(net "M_B_DQ4")
	)
	(segment
		(start 129.159 -3.379978)
		(end 129.159 -3.659378)
		(width 0.1778)
		(layer "B.Cu")
		(net "M_B_DQ4")
	)
	(segment
		(start 129.159 -3.659378)
		(end 129.2098 -3.710178)
		(width 0.1778)
		(layer "B.Cu")
		(net "M_B_DQ4")
	)
	(segment
		(start 129.249932 -1.690624)
		(end 129.249932 -3.289046)
		(width 0.1778)
		(layer "B.Cu")
		(net "M_B_DQ4")
	)
	(segment
		(start 129.249932 -3.289046)
		(end 129.159 -3.379978)
		(width 0.1778)
		(layer "B.Cu")
		(net "M_B_DQ4")
	)
	(segment
		(start 119.507 -4.953)
		(end 119.3546 -4.8006)
		(width 0.1524)
		(layer "In7.Cu")
		(net "M_B_DQ4")
	)
	(segment
		(start 127.3302 -4.4196)
		(end 126.1364 -4.4196)
		(width 0.1524)
		(layer "In7.Cu")
		(net "M_B_DQ4")
	)
	(segment
		(start 121.9962 -4.826)
		(end 121.9962 -4.1656)
		(width 0.1524)
		(layer "In7.Cu")
		(net "M_B_DQ4")
	)
	(segment
		(start 123.937522 -4.826)
		(end 123.937522 -4.4958)
		(width 0.1524)
		(layer "In7.Cu")
		(net "M_B_DQ4")
	)
	(segment
		(start 118.5926 -4.953254)
		(end 118.237 -4.953254)
		(width 0.1524)
		(layer "In7.Cu")
		(net "M_B_DQ4")
	)
	(segment
		(start 128.7272 -3.862578)
		(end 128.7272 -4.7244)
		(width 0.1524)
		(layer "In7.Cu")
		(net "M_B_DQ4")
	)
	(segment
		(start 121.005346 -4.953)
		(end 119.507 -4.953)
		(width 0.1524)
		(layer "In7.Cu")
		(net "M_B_DQ4")
	)
	(segment
		(start 118.237 -4.953254)
		(end 118.0846 -4.800854)
		(width 0.1524)
		(layer "In7.Cu")
		(net "M_B_DQ4")
	)
	(segment
		(start 116.7892 -4.8006)
		(end 116.7892 -4.2291)
		(width 0.1524)
		(layer "In7.Cu")
		(net "M_B_DQ4")
	)
	(segment
		(start 127.9652 -3.8608)
		(end 127.635 -3.8608)
		(width 0.1524)
		(layer "In7.Cu")
		(net "M_B_DQ4")
	)
	(segment
		(start 121.208546 -4.7498)
		(end 121.005346 -4.953)
		(width 0.1524)
		(layer "In7.Cu")
		(net "M_B_DQ4")
	)
	(segment
		(start 126.1364 -4.4196)
		(end 125.857 -4.699)
		(width 0.1524)
		(layer "In7.Cu")
		(net "M_B_DQ4")
	)
	(segment
		(start 121.208546 -4.1656)
		(end 121.208546 -4.7498)
		(width 0.1524)
		(layer "In7.Cu")
		(net "M_B_DQ4")
	)
	(segment
		(start 121.360946 -4.0132)
		(end 121.208546 -4.1656)
		(width 0.1524)
		(layer "In7.Cu")
		(net "M_B_DQ4")
	)
	(segment
		(start 117.9322 -4.0132)
		(end 117.5766 -4.0132)
		(width 0.1524)
		(layer "In7.Cu")
		(net "M_B_DQ4")
	)
	(segment
		(start 128.8796 -3.710178)
		(end 128.7272 -3.862578)
		(width 0.1524)
		(layer "In7.Cu")
		(net "M_B_DQ4")
	)
	(segment
		(start 122.1486 -4.9784)
		(end 121.9962 -4.826)
		(width 0.1524)
		(layer "In7.Cu")
		(net "M_B_DQ4")
	)
	(segment
		(start 127.4826 -4.2672)
		(end 127.3302 -4.4196)
		(width 0.1524)
		(layer "In7.Cu")
		(net "M_B_DQ4")
	)
	(segment
		(start 97.072958 -15.154656)
		(end 93.31198 -18.915634)
		(width 0.1524)
		(layer "In7.Cu")
		(net "M_B_DQ4")
	)
	(segment
		(start 122.707146 -4.826)
		(end 122.554746 -4.9784)
		(width 0.1524)
		(layer "In7.Cu")
		(net "M_B_DQ4")
	)
	(segment
		(start 117.2718 -4.953)
		(end 116.9416 -4.953)
		(width 0.1524)
		(layer "In7.Cu")
		(net "M_B_DQ4")
	)
	(segment
		(start 121.9962 -4.1656)
		(end 121.8438 -4.0132)
		(width 0.1524)
		(layer "In7.Cu")
		(net "M_B_DQ4")
	)
	(segment
		(start 125.476 -4.699)
		(end 125.1966 -4.4196)
		(width 0.1524)
		(layer "In7.Cu")
		(net "M_B_DQ4")
	)
	(segment
		(start 124.394722 -4.9784)
		(end 124.089922 -4.9784)
		(width 0.1524)
		(layer "In7.Cu")
		(net "M_B_DQ4")
	)
	(segment
		(start 90.043 -24.6888)
		(end 90.043 -21.9964)
		(width 0.1016)
		(layer "In7.Cu")
		(net "M_B_DQ4")
	)
	(segment
		(start 123.785122 -4.3434)
		(end 122.859546 -4.3434)
		(width 0.1524)
		(layer "In7.Cu")
		(net "M_B_DQ4")
	)
	(segment
		(start 128.5748 -4.8768)
		(end 128.27 -4.8768)
		(width 0.1524)
		(layer "In7.Cu")
		(net "M_B_DQ4")
	)
	(segment
		(start 116.7892 -4.2291)
		(end 116.6368 -4.0767)
		(width 0.1524)
		(layer "In7.Cu")
		(net "M_B_DQ4")
	)
	(segment
		(start 116.2558 -4.0767)
		(end 116.1034 -4.2291)
		(width 0.1524)
		(layer "In7.Cu")
		(net "M_B_DQ4")
	)
	(segment
		(start 119.3546 -4.8006)
		(end 119.3546 -4.1402)
		(width 0.1524)
		(layer "In7.Cu")
		(net "M_B_DQ4")
	)
	(segment
		(start 93.123766 -18.915634)
		(end 93.31198 -18.915634)
		(width 0.1016)
		(layer "In7.Cu")
		(net "M_B_DQ4")
	)
	(segment
		(start 128.7272 -4.7244)
		(end 128.5748 -4.8768)
		(width 0.1524)
		(layer "In7.Cu")
		(net "M_B_DQ4")
	)
	(segment
		(start 125.1966 -4.4196)
		(end 124.699522 -4.4196)
		(width 0.1524)
		(layer "In7.Cu")
		(net "M_B_DQ4")
	)
	(segment
		(start 115.9002 -6.86054)
		(end 114.183922 -6.86054)
		(width 0.1524)
		(layer "In7.Cu")
		(net "M_B_DQ4")
	)
	(segment
		(start 119.2276 -4.0132)
		(end 118.872 -4.0132)
		(width 0.1524)
		(layer "In7.Cu")
		(net "M_B_DQ4")
	)
	(segment
		(start 90.9066 -25.1968)
		(end 90.551 -25.1968)
		(width 0.1016)
		(layer "In7.Cu")
		(net "M_B_DQ4")
	)
	(segment
		(start 121.8438 -4.0132)
		(end 121.360946 -4.0132)
		(width 0.1524)
		(layer "In7.Cu")
		(net "M_B_DQ4")
	)
	(segment
		(start 125.857 -4.699)
		(end 125.476 -4.699)
		(width 0.1524)
		(layer "In7.Cu")
		(net "M_B_DQ4")
	)
	(segment
		(start 90.043 -21.9964)
		(end 93.123766 -18.915634)
		(width 0.1016)
		(layer "In7.Cu")
		(net "M_B_DQ4")
	)
	(segment
		(start 127.4826 -4.0132)
		(end 127.4826 -4.2672)
		(width 0.1524)
		(layer "In7.Cu")
		(net "M_B_DQ4")
	)
	(segment
		(start 116.1034 -6.65734)
		(end 115.9002 -6.86054)
		(width 0.1524)
		(layer "In7.Cu")
		(net "M_B_DQ4")
	)
	(segment
		(start 117.4242 -4.1656)
		(end 117.4242 -4.8006)
		(width 0.1524)
		(layer "In7.Cu")
		(net "M_B_DQ4")
	)
	(segment
		(start 122.859546 -4.3434)
		(end 122.707146 -4.4958)
		(width 0.1524)
		(layer "In7.Cu")
		(net "M_B_DQ4")
	)
	(segment
		(start 128.1176 -4.0132)
		(end 127.9652 -3.8608)
		(width 0.1524)
		(layer "In7.Cu")
		(net "M_B_DQ4")
	)
	(segment
		(start 118.745 -4.800854)
		(end 118.5926 -4.953254)
		(width 0.1524)
		(layer "In7.Cu")
		(net "M_B_DQ4")
	)
	(segment
		(start 118.0846 -4.1656)
		(end 117.9322 -4.0132)
		(width 0.1524)
		(layer "In7.Cu")
		(net "M_B_DQ4")
	)
	(segment
		(start 124.547122 -4.572)
		(end 124.547122 -4.826)
		(width 0.1524)
		(layer "In7.Cu")
		(net "M_B_DQ4")
	)
	(segment
		(start 128.1176 -4.7244)
		(end 128.1176 -4.0132)
		(width 0.1524)
		(layer "In7.Cu")
		(net "M_B_DQ4")
	)
	(segment
		(start 114.183922 -6.86054)
		(end 105.889806 -15.154656)
		(width 0.1524)
		(layer "In7.Cu")
		(net "M_B_DQ4")
	)
	(segment
		(start 123.937522 -4.4958)
		(end 123.785122 -4.3434)
		(width 0.1524)
		(layer "In7.Cu")
		(net "M_B_DQ4")
	)
	(segment
		(start 119.3546 -4.1402)
		(end 119.2276 -4.0132)
		(width 0.1524)
		(layer "In7.Cu")
		(net "M_B_DQ4")
	)
	(segment
		(start 124.699522 -4.4196)
		(end 124.547122 -4.572)
		(width 0.1524)
		(layer "In7.Cu")
		(net "M_B_DQ4")
	)
	(segment
		(start 117.5766 -4.0132)
		(end 117.4242 -4.1656)
		(width 0.1524)
		(layer "In7.Cu")
		(net "M_B_DQ4")
	)
	(segment
		(start 128.27 -4.8768)
		(end 128.1176 -4.7244)
		(width 0.1524)
		(layer "In7.Cu")
		(net "M_B_DQ4")
	)
	(segment
		(start 124.089922 -4.9784)
		(end 123.937522 -4.826)
		(width 0.1524)
		(layer "In7.Cu")
		(net "M_B_DQ4")
	)
	(segment
		(start 105.889806 -15.154656)
		(end 97.072958 -15.154656)
		(width 0.1524)
		(layer "In7.Cu")
		(net "M_B_DQ4")
	)
	(segment
		(start 118.0846 -4.800854)
		(end 118.0846 -4.1656)
		(width 0.1524)
		(layer "In7.Cu")
		(net "M_B_DQ4")
	)
	(segment
		(start 118.872 -4.0132)
		(end 118.745 -4.1402)
		(width 0.1524)
		(layer "In7.Cu")
		(net "M_B_DQ4")
	)
	(segment
		(start 90.551 -25.1968)
		(end 90.043 -24.6888)
		(width 0.1016)
		(layer "In7.Cu")
		(net "M_B_DQ4")
	)
	(segment
		(start 118.745 -4.1402)
		(end 118.745 -4.800854)
		(width 0.1524)
		(layer "In7.Cu")
		(net "M_B_DQ4")
	)
	(segment
		(start 117.4242 -4.8006)
		(end 117.2718 -4.953)
		(width 0.1524)
		(layer "In7.Cu")
		(net "M_B_DQ4")
	)
	(segment
		(start 116.9416 -4.953)
		(end 116.7892 -4.8006)
		(width 0.1524)
		(layer "In7.Cu")
		(net "M_B_DQ4")
	)
	(segment
		(start 122.554746 -4.9784)
		(end 122.1486 -4.9784)
		(width 0.1524)
		(layer "In7.Cu")
		(net "M_B_DQ4")
	)
	(segment
		(start 124.547122 -4.826)
		(end 124.394722 -4.9784)
		(width 0.1524)
		(layer "In7.Cu")
		(net "M_B_DQ4")
	)
	(segment
		(start 116.1034 -4.2291)
		(end 116.1034 -6.65734)
		(width 0.1524)
		(layer "In7.Cu")
		(net "M_B_DQ4")
	)
	(segment
		(start 129.2098 -3.710178)
		(end 128.8796 -3.710178)
		(width 0.1524)
		(layer "In7.Cu")
		(net "M_B_DQ4")
	)
	(segment
		(start 127.635 -3.8608)
		(end 127.4826 -4.0132)
		(width 0.1524)
		(layer "In7.Cu")
		(net "M_B_DQ4")
	)
	(segment
		(start 122.707146 -4.4958)
		(end 122.707146 -4.826)
		(width 0.1524)
		(layer "In7.Cu")
		(net "M_B_DQ4")
	)
	(segment
		(start 116.6368 -4.0767)
		(end 116.2558 -4.0767)
		(width 0.1524)
		(layer "In7.Cu")
		(net "M_B_DQ4")
	)
	(segment
		(start 108.247942 -48.459136)
		(end 108.247942 -48.292258)
		(width 0.1016)
		(layer "F.Cu")
		(net "M_A_MA8")
	)
	(segment
		(start 158.70047 -66.601848)
		(end 159.177228 -66.12509)
		(width 0.2413)
		(layer "F.Cu")
		(net "M_A_MA8")
	)
	(segment
		(start 159.177228 -66.12509)
		(end 159.177228 -66.1162)
		(width 0.2413)
		(layer "F.Cu")
		(net "M_A_MA8")
	)
	(segment
		(start 108.2548 -48.2854)
		(end 108.2548 -47.793402)
		(width 0.1016)
		(layer "F.Cu")
		(net "M_A_MA8")
	)
	(segment
		(start 108.2548 -47.793402)
		(end 108.433108 -47.615094)
		(width 0.1016)
		(layer "F.Cu")
		(net "M_A_MA8")
	)
	(segment
		(start 108.247942 -48.292258)
		(end 108.2548 -48.2854)
		(width 0.1016)
		(layer "F.Cu")
		(net "M_A_MA8")
	)
	(segment
		(start 158.70047 -68.67017)
		(end 158.70047 -66.601848)
		(width 0.2413)
		(layer "F.Cu")
		(net "M_A_MA8")
	)
	(segment
		(start 158.950152 -70.806564)
		(end 158.950152 -68.919852)
		(width 0.2413)
		(layer "F.Cu")
		(net "M_A_MA8")
	)
	(segment
		(start 158.950152 -68.919852)
		(end 158.70047 -68.67017)
		(width 0.2413)
		(layer "F.Cu")
		(net "M_A_MA8")
	)
	(via
		(at 108.247942 -48.459136)
		(size 0.4318)
		(drill 0.2032)
		(layers "F.Cu" "B.Cu")
		(net "M_A_MA8")
	)
	(via
		(at 159.177228 -66.1162)
		(size 0.4318)
		(drill 0.2032)
		(layers "F.Cu" "B.Cu")
		(net "M_A_MA8")
	)
	(segment
		(start 158.950152 -62.599824)
		(end 158.950152 -64.665352)
		(width 0.2413)
		(layer "B.Cu")
		(net "M_A_MA8")
	)
	(segment
		(start 158.950152 -64.665352)
		(end 159.043878 -64.759078)
		(width 0.2413)
		(layer "B.Cu")
		(net "M_A_MA8")
	)
	(segment
		(start 159.043878 -64.759078)
		(end 159.043878 -65.98285)
		(width 0.2413)
		(layer "B.Cu")
		(net "M_A_MA8")
	)
	(segment
		(start 159.043878 -65.98285)
		(end 159.177228 -66.1162)
		(width 0.2413)
		(layer "B.Cu")
		(net "M_A_MA8")
	)
	(segment
		(start 158.8008 -62.0776)
		(end 157.857952 -61.134752)
		(width 0.1905)
		(layer "In9.Cu")
		(net "M_A_MA8")
	)
	(segment
		(start 108.301536 -48.459136)
		(end 108.247942 -48.459136)
		(width 0.1016)
		(layer "In9.Cu")
		(net "M_A_MA8")
	)
	(segment
		(start 159.177228 -65.578228)
		(end 158.8008 -65.2018)
		(width 0.1905)
		(layer "In9.Cu")
		(net "M_A_MA8")
	)
	(segment
		(start 154.00401 -55.13832)
		(end 153.395426 -55.13832)
		(width 0.1905)
		(layer "In9.Cu")
		(net "M_A_MA8")
	)
	(segment
		(start 117.6274 -50.8)
		(end 117.0178 -51.4096)
		(width 0.1016)
		(layer "In9.Cu")
		(net "M_A_MA8")
	)
	(segment
		(start 159.177228 -66.1162)
		(end 159.177228 -65.578228)
		(width 0.1905)
		(layer "In9.Cu")
		(net "M_A_MA8")
	)
	(segment
		(start 109.728 -50.5968)
		(end 109.728 -49.8856)
		(width 0.1016)
		(layer "In9.Cu")
		(net "M_A_MA8")
	)
	(segment
		(start 153.395426 -55.13832)
		(end 151.46909 -53.211984)
		(width 0.1905)
		(layer "In9.Cu")
		(net "M_A_MA8")
	)
	(segment
		(start 109.728 -49.8856)
		(end 108.301536 -48.459136)
		(width 0.1016)
		(layer "In9.Cu")
		(net "M_A_MA8")
	)
	(segment
		(start 151.46909 -52.6034)
		(end 149.66569 -50.8)
		(width 0.1905)
		(layer "In9.Cu")
		(net "M_A_MA8")
	)
	(segment
		(start 117.0178 -51.4096)
		(end 110.5408 -51.4096)
		(width 0.1016)
		(layer "In9.Cu")
		(net "M_A_MA8")
	)
	(segment
		(start 156.99105 -58.826146)
		(end 156.99105 -58.12536)
		(width 0.1905)
		(layer "In9.Cu")
		(net "M_A_MA8")
	)
	(segment
		(start 144.31772 -50.27295)
		(end 118.15445 -50.27295)
		(width 0.1905)
		(layer "In9.Cu")
		(net "M_A_MA8")
	)
	(segment
		(start 157.857952 -61.134752)
		(end 157.857952 -59.693048)
		(width 0.1905)
		(layer "In9.Cu")
		(net "M_A_MA8")
	)
	(segment
		(start 110.5408 -51.4096)
		(end 109.728 -50.5968)
		(width 0.1016)
		(layer "In9.Cu")
		(net "M_A_MA8")
	)
	(segment
		(start 144.84477 -50.8)
		(end 144.31772 -50.27295)
		(width 0.1905)
		(layer "In9.Cu")
		(net "M_A_MA8")
	)
	(segment
		(start 158.8008 -65.2018)
		(end 158.8008 -62.0776)
		(width 0.1905)
		(layer "In9.Cu")
		(net "M_A_MA8")
	)
	(segment
		(start 157.857952 -59.693048)
		(end 156.99105 -58.826146)
		(width 0.1905)
		(layer "In9.Cu")
		(net "M_A_MA8")
	)
	(segment
		(start 149.66569 -50.8)
		(end 144.84477 -50.8)
		(width 0.1905)
		(layer "In9.Cu")
		(net "M_A_MA8")
	)
	(segment
		(start 151.46909 -53.211984)
		(end 151.46909 -52.6034)
		(width 0.1905)
		(layer "In9.Cu")
		(net "M_A_MA8")
	)
	(segment
		(start 156.99105 -58.12536)
		(end 154.00401 -55.13832)
		(width 0.1905)
		(layer "In9.Cu")
		(net "M_A_MA8")
	)
	(segment
		(start 118.15445 -50.27295)
		(end 117.6274 -50.8)
		(width 0.1905)
		(layer "In9.Cu")
		(net "M_A_MA8")
	)
	(segment
		(start 140.949934 -1.68402)
		(end 140.949934 -2.402332)
		(width 0.1778)
		(layer "F.Cu")
		(net "M_B_DQS_DN2")
	)
	(segment
		(start 101.092 -24.765)
		(end 101.092 -25.282144)
		(width 0.1016)
		(layer "F.Cu")
		(net "M_B_DQS_DN2")
	)
	(segment
		(start 140.949934 -2.402332)
		(end 141.097508 -2.549906)
		(width 0.1778)
		(layer "F.Cu")
		(net "M_B_DQS_DN2")
	)
	(segment
		(start 141.097508 -2.549906)
		(end 141.097508 -5.55371)
		(width 0.1778)
		(layer "F.Cu")
		(net "M_B_DQS_DN2")
	)
	(segment
		(start 101.092 -25.282144)
		(end 101.556312 -25.746456)
		(width 0.1016)
		(layer "F.Cu")
		(net "M_B_DQS_DN2")
	)
	(segment
		(start 141.097508 -5.55371)
		(end 140.83284 -5.818378)
		(width 0.1778)
		(layer "F.Cu")
		(net "M_B_DQS_DN2")
	)
	(segment
		(start 101.556312 -26.869898)
		(end 101.638608 -26.952194)
		(width 0.1016)
		(layer "F.Cu")
		(net "M_B_DQS_DN2")
	)
	(segment
		(start 101.556312 -25.746456)
		(end 101.556312 -26.869898)
		(width 0.1016)
		(layer "F.Cu")
		(net "M_B_DQS_DN2")
	)
	(segment
		(start 100.8634 -24.5364)
		(end 101.092 -24.765)
		(width 0.1016)
		(layer "F.Cu")
		(net "M_B_DQS_DN2")
	)
	(via
		(at 100.8634 -24.5364)
		(size 0.4318)
		(drill 0.2032)
		(layers "F.Cu" "B.Cu")
		(net "M_B_DQS_DN2")
	)
	(via
		(at 140.83284 -5.818378)
		(size 0.4318)
		(drill 0.2032)
		(layers "F.Cu" "B.Cu")
		(net "M_B_DQS_DN2")
	)
	(segment
		(start 141.097508 -8.96747)
		(end 141.097508 -6.083046)
		(width 0.1778)
		(layer "B.Cu")
		(net "M_B_DQS_DN2")
	)
	(segment
		(start 141.097508 -6.083046)
		(end 140.83284 -5.818378)
		(width 0.1778)
		(layer "B.Cu")
		(net "M_B_DQS_DN2")
	)
	(segment
		(start 140.949934 -9.89076)
		(end 140.949934 -9.115044)
		(width 0.1778)
		(layer "B.Cu")
		(net "M_B_DQS_DN2")
	)
	(segment
		(start 140.949934 -9.115044)
		(end 141.097508 -8.96747)
		(width 0.1778)
		(layer "B.Cu")
		(net "M_B_DQS_DN2")
	)
	(segment
		(start 132.2578 -13.0556)
		(end 132.1054 -13.208)
		(width 0.1524)
		(layer "In4.Cu")
		(net "M_B_DQS_DN2")
	)
	(segment
		(start 141.0462 -5.818378)
		(end 141.1986 -5.970778)
		(width 0.1524)
		(layer "In4.Cu")
		(net "M_B_DQS_DN2")
	)
	(segment
		(start 132.1054 -13.208)
		(end 113.725452 -13.208)
		(width 0.1524)
		(layer "In4.Cu")
		(net "M_B_DQS_DN2")
	)
	(segment
		(start 133.389624 -12.446)
		(end 132.573776 -12.446)
		(width 0.1524)
		(layer "In4.Cu")
		(net "M_B_DQS_DN2")
	)
	(segment
		(start 138.031728 -11.0744)
		(end 135.644128 -13.462)
		(width 0.1524)
		(layer "In4.Cu")
		(net "M_B_DQS_DN2")
	)
	(segment
		(start 100.51669 -20.84451)
		(end 104.14 -17.2212)
		(width 0.1016)
		(layer "In4.Cu")
		(net "M_B_DQS_DN2")
	)
	(segment
		(start 141.1986 -6.642354)
		(end 140.9446 -6.896354)
		(width 0.1524)
		(layer "In4.Cu")
		(net "M_B_DQS_DN2")
	)
	(segment
		(start 109.712252 -17.2212)
		(end 104.14 -17.2212)
		(width 0.1524)
		(layer "In4.Cu")
		(net "M_B_DQS_DN2")
	)
	(segment
		(start 140.83284 -5.818378)
		(end 141.0462 -5.818378)
		(width 0.1524)
		(layer "In4.Cu")
		(net "M_B_DQS_DN2")
	)
	(segment
		(start 139.3444 -11.0744)
		(end 138.031728 -11.0744)
		(width 0.1524)
		(layer "In4.Cu")
		(net "M_B_DQS_DN2")
	)
	(segment
		(start 133.7056 -12.761976)
		(end 133.389624 -12.446)
		(width 0.1524)
		(layer "In4.Cu")
		(net "M_B_DQS_DN2")
	)
	(segment
		(start 133.7056 -13.335)
		(end 133.7056 -12.761976)
		(width 0.1524)
		(layer "In4.Cu")
		(net "M_B_DQS_DN2")
	)
	(segment
		(start 113.725452 -13.208)
		(end 109.712252 -17.2212)
		(width 0.1524)
		(layer "In4.Cu")
		(net "M_B_DQS_DN2")
	)
	(segment
		(start 132.2578 -12.761976)
		(end 132.2578 -13.0556)
		(width 0.1524)
		(layer "In4.Cu")
		(net "M_B_DQS_DN2")
	)
	(segment
		(start 140.9446 -9.4742)
		(end 139.3444 -11.0744)
		(width 0.1524)
		(layer "In4.Cu")
		(net "M_B_DQS_DN2")
	)
	(segment
		(start 140.9446 -6.896354)
		(end 140.9446 -9.4742)
		(width 0.1524)
		(layer "In4.Cu")
		(net "M_B_DQS_DN2")
	)
	(segment
		(start 100.51669 -24.18969)
		(end 100.51669 -20.84451)
		(width 0.1016)
		(layer "In4.Cu")
		(net "M_B_DQS_DN2")
	)
	(segment
		(start 135.644128 -13.462)
		(end 133.8326 -13.462)
		(width 0.1524)
		(layer "In4.Cu")
		(net "M_B_DQS_DN2")
	)
	(segment
		(start 100.8634 -24.5364)
		(end 100.51669 -24.18969)
		(width 0.1016)
		(layer "In4.Cu")
		(net "M_B_DQS_DN2")
	)
	(segment
		(start 133.8326 -13.462)
		(end 133.7056 -13.335)
		(width 0.1524)
		(layer "In4.Cu")
		(net "M_B_DQS_DN2")
	)
	(segment
		(start 141.1986 -5.970778)
		(end 141.1986 -6.642354)
		(width 0.1524)
		(layer "In4.Cu")
		(net "M_B_DQS_DN2")
	)
	(segment
		(start 132.573776 -12.446)
		(end 132.2578 -12.761976)
		(width 0.1524)
		(layer "In4.Cu")
		(net "M_B_DQS_DN2")
	)
	(segment
		(start 90.122248 -46.116494)
		(end 90.102436 -46.116494)
		(width 0.1397)
		(layer "F.Cu")
		(net "USB_P1_DP")
	)
	(segment
		(start 90.102436 -46.116494)
		(end 89.738708 -46.480222)
		(width 0.1397)
		(layer "F.Cu")
		(net "USB_P1_DP")
	)
	(via
		(at 83.1596 -13.9446)
		(size 0.508)
		(drill 0.254)
		(layers "F.Cu" "B.Cu")
		(net "USB_P1_DP")
	)
	(via
		(at 89.738708 -46.480222)
		(size 0.4318)
		(drill 0.2032)
		(layers "F.Cu" "B.Cu")
		(net "USB_P1_DP")
	)
	(segment
		(start 88.06434 -13.1318)
		(end 83.16214 -13.1318)
		(width 0.1397)
		(layer "B.Cu")
		(net "USB_P1_DP")
	)
	(segment
		(start 90.02141 -11.17473)
		(end 88.06434 -13.1318)
		(width 0.1397)
		(layer "B.Cu")
		(net "USB_P1_DP")
	)
	(segment
		(start 90.350086 -8.447024)
		(end 90.02141 -8.7757)
		(width 0.1397)
		(layer "B.Cu")
		(net "USB_P1_DP")
	)
	(segment
		(start 83.16214 -13.1318)
		(end 82.9183 -13.37564)
		(width 0.1397)
		(layer "B.Cu")
		(net "USB_P1_DP")
	)
	(segment
		(start 82.9183 -13.37564)
		(end 82.9183 -13.7033)
		(width 0.1397)
		(layer "B.Cu")
		(net "USB_P1_DP")
	)
	(segment
		(start 90.350086 -5.814568)
		(end 90.350086 -8.447024)
		(width 0.1397)
		(layer "B.Cu")
		(net "USB_P1_DP")
	)
	(segment
		(start 90.02141 -8.7757)
		(end 90.02141 -11.17473)
		(width 0.1397)
		(layer "B.Cu")
		(net "USB_P1_DP")
	)
	(segment
		(start 82.9183 -13.7033)
		(end 83.1596 -13.9446)
		(width 0.1397)
		(layer "B.Cu")
		(net "USB_P1_DP")
	)
	(segment
		(start 87.917528 -45.974)
		(end 87.388192 -45.974)
		(width 0.1016)
		(layer "In9.Cu")
		(net "USB_P1_DP")
	)
	(segment
		(start 88.273128 -46.189646)
		(end 88.133174 -46.189646)
		(width 0.1016)
		(layer "In9.Cu")
		(net "USB_P1_DP")
	)
	(segment
		(start 87.388192 -45.974)
		(end 87.289132 -45.87494)
		(width 0.1016)
		(layer "In9.Cu")
		(net "USB_P1_DP")
	)
	(segment
		(start 77.6478 -42.545)
		(end 76.28636 -41.18356)
		(width 0.1143)
		(layer "In9.Cu")
		(net "USB_P1_DP")
	)
	(segment
		(start 79.2226 -42.545)
		(end 77.6478 -42.545)
		(width 0.1143)
		(layer "In9.Cu")
		(net "USB_P1_DP")
	)
	(segment
		(start 81.6483 -44.9707)
		(end 81.40573 -44.72813)
		(width 0.1143)
		(layer "In9.Cu")
		(net "USB_P1_DP")
	)
	(segment
		(start 80.376776 -43.397424)
		(end 80.075024 -43.397424)
		(width 0.1143)
		(layer "In9.Cu")
		(net "USB_P1_DP")
	)
	(segment
		(start 80.861662 -44.184062)
		(end 80.619092 -43.941492)
		(width 0.1143)
		(layer "In9.Cu")
		(net "USB_P1_DP")
	)
	(segment
		(start 83.820508 -46.406308)
		(end 82.4484 -45.0342)
		(width 0.1016)
		(layer "In9.Cu")
		(net "USB_P1_DP")
	)
	(segment
		(start 75.0062 -37.47262)
		(end 75.0062 -35.0012)
		(width 0.1143)
		(layer "In9.Cu")
		(net "USB_P1_DP")
	)
	(segment
		(start 74.5998 -34.5948)
		(end 74.5998 -27.305)
		(width 0.1143)
		(layer "In9.Cu")
		(net "USB_P1_DP")
	)
	(segment
		(start 89.442798 -46.776132)
		(end 88.71966 -46.776132)
		(width 0.1016)
		(layer "In9.Cu")
		(net "USB_P1_DP")
	)
	(segment
		(start 82.8802 -14.224)
		(end 83.1596 -13.9446)
		(width 0.1143)
		(layer "In9.Cu")
		(net "USB_P1_DP")
	)
	(segment
		(start 74.1172 -22.031706)
		(end 76.451206 -19.6977)
		(width 0.1143)
		(layer "In9.Cu")
		(net "USB_P1_DP")
	)
	(segment
		(start 80.619092 -43.63974)
		(end 80.376776 -43.397424)
		(width 0.1143)
		(layer "In9.Cu")
		(net "USB_P1_DP")
	)
	(segment
		(start 76.28636 -38.75278)
		(end 75.0062 -37.47262)
		(width 0.1143)
		(layer "In9.Cu")
		(net "USB_P1_DP")
	)
	(segment
		(start 82.8802 -14.995906)
		(end 82.8802 -14.224)
		(width 0.1143)
		(layer "In9.Cu")
		(net "USB_P1_DP")
	)
	(segment
		(start 76.28636 -41.18356)
		(end 76.28636 -38.75278)
		(width 0.1143)
		(layer "In9.Cu")
		(net "USB_P1_DP")
	)
	(segment
		(start 74.1172 -26.8224)
		(end 74.1172 -22.031706)
		(width 0.1143)
		(layer "In9.Cu")
		(net "USB_P1_DP")
	)
	(segment
		(start 81.40573 -44.72813)
		(end 81.40573 -44.426378)
		(width 0.1143)
		(layer "In9.Cu")
		(net "USB_P1_DP")
	)
	(segment
		(start 89.738708 -46.480222)
		(end 89.442798 -46.776132)
		(width 0.1016)
		(layer "In9.Cu")
		(net "USB_P1_DP")
	)
	(segment
		(start 88.133174 -46.189646)
		(end 87.917528 -45.974)
		(width 0.1016)
		(layer "In9.Cu")
		(net "USB_P1_DP")
	)
	(segment
		(start 88.488774 -46.405038)
		(end 88.273128 -46.189646)
		(width 0.1016)
		(layer "In9.Cu")
		(net "USB_P1_DP")
	)
	(segment
		(start 86.885272 -45.974)
		(end 86.580472 -45.974)
		(width 0.1016)
		(layer "In9.Cu")
		(net "USB_P1_DP")
	)
	(segment
		(start 80.075024 -43.397424)
		(end 79.2226 -42.545)
		(width 0.1143)
		(layer "In9.Cu")
		(net "USB_P1_DP")
	)
	(segment
		(start 81.8896 -44.9707)
		(end 81.8642 -44.9707)
		(width 0.1016)
		(layer "In9.Cu")
		(net "USB_P1_DP")
	)
	(segment
		(start 86.148164 -46.406308)
		(end 83.820508 -46.406308)
		(width 0.1016)
		(layer "In9.Cu")
		(net "USB_P1_DP")
	)
	(segment
		(start 88.488774 -46.545246)
		(end 88.488774 -46.405038)
		(width 0.1016)
		(layer "In9.Cu")
		(net "USB_P1_DP")
	)
	(segment
		(start 81.9531 -45.0342)
		(end 81.8896 -44.9707)
		(width 0.1016)
		(layer "In9.Cu")
		(net "USB_P1_DP")
	)
	(segment
		(start 81.8642 -44.9707)
		(end 81.6483 -44.9707)
		(width 0.1143)
		(layer "In9.Cu")
		(net "USB_P1_DP")
	)
	(segment
		(start 74.5998 -27.305)
		(end 74.1172 -26.8224)
		(width 0.1143)
		(layer "In9.Cu")
		(net "USB_P1_DP")
	)
	(segment
		(start 80.619092 -43.941492)
		(end 80.619092 -43.63974)
		(width 0.1143)
		(layer "In9.Cu")
		(net "USB_P1_DP")
	)
	(segment
		(start 86.580472 -45.974)
		(end 86.148164 -46.406308)
		(width 0.1016)
		(layer "In9.Cu")
		(net "USB_P1_DP")
	)
	(segment
		(start 86.984332 -45.87494)
		(end 86.885272 -45.974)
		(width 0.1016)
		(layer "In9.Cu")
		(net "USB_P1_DP")
	)
	(segment
		(start 87.289132 -45.87494)
		(end 86.984332 -45.87494)
		(width 0.1016)
		(layer "In9.Cu")
		(net "USB_P1_DP")
	)
	(segment
		(start 75.0062 -35.0012)
		(end 74.5998 -34.5948)
		(width 0.1143)
		(layer "In9.Cu")
		(net "USB_P1_DP")
	)
	(segment
		(start 88.71966 -46.776132)
		(end 88.488774 -46.545246)
		(width 0.1016)
		(layer "In9.Cu")
		(net "USB_P1_DP")
	)
	(segment
		(start 76.451206 -19.6977)
		(end 78.178406 -19.6977)
		(width 0.1143)
		(layer "In9.Cu")
		(net "USB_P1_DP")
	)
	(segment
		(start 82.4484 -45.0342)
		(end 81.9531 -45.0342)
		(width 0.1016)
		(layer "In9.Cu")
		(net "USB_P1_DP")
	)
	(segment
		(start 81.40573 -44.426378)
		(end 81.163414 -44.184062)
		(width 0.1143)
		(layer "In9.Cu")
		(net "USB_P1_DP")
	)
	(segment
		(start 78.178406 -19.6977)
		(end 82.8802 -14.995906)
		(width 0.1143)
		(layer "In9.Cu")
		(net "USB_P1_DP")
	)
	(segment
		(start 81.163414 -44.184062)
		(end 80.861662 -44.184062)
		(width 0.1143)
		(layer "In9.Cu")
		(net "USB_P1_DP")
	)
	(segment
		(start 98.8568 -56.1848)
		(end 99.2632 -56.5912)
		(width 0.1016)
		(layer "F.Cu")
		(net "M_A_DQ55")
	)
	(segment
		(start 99.2632 -56.5912)
		(end 99.2632 -58.0771)
		(width 0.1016)
		(layer "F.Cu")
		(net "M_A_DQ55")
	)
	(segment
		(start 99.2632 -58.0771)
		(end 98.8441 -58.4962)
		(width 0.1016)
		(layer "F.Cu")
		(net "M_A_DQ55")
	)
	(segment
		(start 98.811588 -52.448714)
		(end 98.8568 -52.493926)
		(width 0.1016)
		(layer "F.Cu")
		(net "M_A_DQ55")
	)
	(segment
		(start 98.8568 -52.493926)
		(end 98.8568 -56.1848)
		(width 0.1016)
		(layer "F.Cu")
		(net "M_A_DQ55")
	)
	(segment
		(start 134.349998 -70.806564)
		(end 134.349998 -69.847206)
		(width 0.1778)
		(layer "F.Cu")
		(net "M_A_DQ55")
	)
	(segment
		(start 134.807198 -69.383402)
		(end 134.8486 -69.342)
		(width 0.1778)
		(layer "F.Cu")
		(net "M_A_DQ55")
	)
	(segment
		(start 134.807198 -69.390006)
		(end 134.807198 -69.383402)
		(width 0.1778)
		(layer "F.Cu")
		(net "M_A_DQ55")
	)
	(segment
		(start 134.349998 -69.847206)
		(end 134.807198 -69.390006)
		(width 0.1778)
		(layer "F.Cu")
		(net "M_A_DQ55")
	)
	(via
		(at 98.8441 -58.4962)
		(size 0.4318)
		(drill 0.2032)
		(layers "F.Cu" "B.Cu")
		(net "M_A_DQ55")
	)
	(via
		(at 134.8486 -69.342)
		(size 0.4318)
		(drill 0.2032)
		(layers "F.Cu" "B.Cu")
		(net "M_A_DQ55")
	)
	(segment
		(start 135.250174 -70.79996)
		(end 135.250174 -69.807582)
		(width 0.1778)
		(layer "B.Cu")
		(net "M_A_DQ55")
	)
	(segment
		(start 135.250174 -69.807582)
		(end 134.8486 -69.406008)
		(width 0.1778)
		(layer "B.Cu")
		(net "M_A_DQ55")
	)
	(segment
		(start 134.8486 -69.406008)
		(end 134.8486 -69.342)
		(width 0.1778)
		(layer "B.Cu")
		(net "M_A_DQ55")
	)
	(segment
		(start 103.964486 -66.711322)
		(end 108.086398 -66.711322)
		(width 0.1524)
		(layer "In4.Cu")
		(net "M_A_DQ55")
	)
	(segment
		(start 135.495792 -64.375792)
		(end 135.8138 -64.6938)
		(width 0.1524)
		(layer "In4.Cu")
		(net "M_A_DQ55")
	)
	(segment
		(start 121.476262 -64.4398)
		(end 122.2248 -64.4398)
		(width 0.1524)
		(layer "In4.Cu")
		(net "M_A_DQ55")
	)
	(segment
		(start 134.9502 -67.697858)
		(end 134.7978 -67.850258)
		(width 0.1524)
		(layer "In4.Cu")
		(net "M_A_DQ55")
	)
	(segment
		(start 134.6454 -67.850258)
		(end 134.493 -68.002658)
		(width 0.1524)
		(layer "In4.Cu")
		(net "M_A_DQ55")
	)
	(segment
		(start 98.8441 -59.511438)
		(end 98.379026 -59.976512)
		(width 0.1524)
		(layer "In4.Cu")
		(net "M_A_DQ55")
	)
	(segment
		(start 134.62 -67.240658)
		(end 134.7978 -67.240658)
		(width 0.1524)
		(layer "In4.Cu")
		(net "M_A_DQ55")
	)
	(segment
		(start 127.889 -64.4398)
		(end 129.0574 -63.2714)
		(width 0.1524)
		(layer "In4.Cu")
		(net "M_A_DQ55")
	)
	(segment
		(start 134.62 -66.631058)
		(end 134.4676 -66.783458)
		(width 0.1524)
		(layer "In4.Cu")
		(net "M_A_DQ55")
	)
	(segment
		(start 134.7978 -66.631058)
		(end 134.62 -66.631058)
		(width 0.1524)
		(layer "In4.Cu")
		(net "M_A_DQ55")
	)
	(segment
		(start 135.8138 -65.2526)
		(end 134.9502 -66.1162)
		(width 0.1524)
		(layer "In4.Cu")
		(net "M_A_DQ55")
	)
	(segment
		(start 98.8441 -58.4962)
		(end 98.8441 -59.511438)
		(width 0.1016)
		(layer "In4.Cu")
		(net "M_A_DQ55")
	)
	(segment
		(start 134.9502 -66.478658)
		(end 134.7978 -66.631058)
		(width 0.1524)
		(layer "In4.Cu")
		(net "M_A_DQ55")
	)
	(segment
		(start 122.5804 -64.7954)
		(end 123.6726 -64.7954)
		(width 0.1524)
		(layer "In4.Cu")
		(net "M_A_DQ55")
	)
	(segment
		(start 134.493 -68.307458)
		(end 134.6454 -68.459858)
		(width 0.1524)
		(layer "In4.Cu")
		(net "M_A_DQ55")
	)
	(segment
		(start 134.493 -68.002658)
		(end 134.493 -68.307458)
		(width 0.1524)
		(layer "In4.Cu")
		(net "M_A_DQ55")
	)
	(segment
		(start 134.7978 -67.240658)
		(end 134.9502 -67.393058)
		(width 0.1524)
		(layer "In4.Cu")
		(net "M_A_DQ55")
	)
	(segment
		(start 135.001 -63.2714)
		(end 135.495792 -63.766192)
		(width 0.1524)
		(layer "In4.Cu")
		(net "M_A_DQ55")
	)
	(segment
		(start 134.8486 -69.297804)
		(end 134.8486 -69.342)
		(width 0.1524)
		(layer "In4.Cu")
		(net "M_A_DQ55")
	)
	(segment
		(start 108.805726 -67.43065)
		(end 118.485412 -67.43065)
		(width 0.1524)
		(layer "In4.Cu")
		(net "M_A_DQ55")
	)
	(segment
		(start 134.4676 -67.088258)
		(end 134.62 -67.240658)
		(width 0.1524)
		(layer "In4.Cu")
		(net "M_A_DQ55")
	)
	(segment
		(start 134.6454 -68.459858)
		(end 134.7978 -68.459858)
		(width 0.1524)
		(layer "In4.Cu")
		(net "M_A_DQ55")
	)
	(segment
		(start 118.485412 -67.43065)
		(end 121.476262 -64.4398)
		(width 0.1524)
		(layer "In4.Cu")
		(net "M_A_DQ55")
	)
	(segment
		(start 98.379026 -61.125862)
		(end 103.964486 -66.711322)
		(width 0.1524)
		(layer "In4.Cu")
		(net "M_A_DQ55")
	)
	(segment
		(start 135.8138 -64.6938)
		(end 135.8138 -65.2526)
		(width 0.1524)
		(layer "In4.Cu")
		(net "M_A_DQ55")
	)
	(segment
		(start 134.7978 -67.850258)
		(end 134.6454 -67.850258)
		(width 0.1524)
		(layer "In4.Cu")
		(net "M_A_DQ55")
	)
	(segment
		(start 134.9502 -69.196204)
		(end 134.8486 -69.297804)
		(width 0.1524)
		(layer "In4.Cu")
		(net "M_A_DQ55")
	)
	(segment
		(start 134.9502 -66.1162)
		(end 134.9502 -66.478658)
		(width 0.1524)
		(layer "In4.Cu")
		(net "M_A_DQ55")
	)
	(segment
		(start 134.9502 -67.393058)
		(end 134.9502 -67.697858)
		(width 0.1524)
		(layer "In4.Cu")
		(net "M_A_DQ55")
	)
	(segment
		(start 134.7978 -68.459858)
		(end 134.9502 -68.612258)
		(width 0.1524)
		(layer "In4.Cu")
		(net "M_A_DQ55")
	)
	(segment
		(start 122.2248 -64.4398)
		(end 122.5804 -64.7954)
		(width 0.1524)
		(layer "In4.Cu")
		(net "M_A_DQ55")
	)
	(segment
		(start 108.086398 -66.711322)
		(end 108.805726 -67.43065)
		(width 0.1524)
		(layer "In4.Cu")
		(net "M_A_DQ55")
	)
	(segment
		(start 98.379026 -59.976512)
		(end 98.379026 -61.125862)
		(width 0.1524)
		(layer "In4.Cu")
		(net "M_A_DQ55")
	)
	(segment
		(start 134.4676 -66.783458)
		(end 134.4676 -67.088258)
		(width 0.1524)
		(layer "In4.Cu")
		(net "M_A_DQ55")
	)
	(segment
		(start 124.0282 -64.4398)
		(end 127.889 -64.4398)
		(width 0.1524)
		(layer "In4.Cu")
		(net "M_A_DQ55")
	)
	(segment
		(start 123.6726 -64.7954)
		(end 124.0282 -64.4398)
		(width 0.1524)
		(layer "In4.Cu")
		(net "M_A_DQ55")
	)
	(segment
		(start 129.0574 -63.2714)
		(end 135.001 -63.2714)
		(width 0.1524)
		(layer "In4.Cu")
		(net "M_A_DQ55")
	)
	(segment
		(start 134.9502 -68.612258)
		(end 134.9502 -69.196204)
		(width 0.1524)
		(layer "In4.Cu")
		(net "M_A_DQ55")
	)
	(segment
		(start 135.495792 -63.766192)
		(end 135.495792 -64.375792)
		(width 0.1524)
		(layer "In4.Cu")
		(net "M_A_DQ55")
	)
	(segment
		(start 163.646104 -4.491482)
		(end 163.646104 -6.08076)
		(width 0.2413)
		(layer "F.Cu")
		(net "M_B_MA0")
	)
	(segment
		(start 104.720898 -29.391102)
		(end 104.765348 -29.391102)
		(width 0.1016)
		(layer "F.Cu")
		(net "M_B_MA0")
	)
	(segment
		(start 162.52698 -3.372358)
		(end 163.646104 -4.491482)
		(width 0.2413)
		(layer "F.Cu")
		(net "M_B_MA0")
	)
	(segment
		(start 163.232084 -6.453378)
		(end 163.130484 -6.554978)
		(width 0.2413)
		(layer "F.Cu")
		(net "M_B_MA0")
	)
	(segment
		(start 162.52698 -2.94386)
		(end 162.52698 -3.372358)
		(width 0.2413)
		(layer "F.Cu")
		(net "M_B_MA0")
	)
	(segment
		(start 163.646104 -6.08076)
		(end 163.273486 -6.453378)
		(width 0.2413)
		(layer "F.Cu")
		(net "M_B_MA0")
	)
	(segment
		(start 163.273486 -6.453378)
		(end 163.232084 -6.453378)
		(width 0.2413)
		(layer "F.Cu")
		(net "M_B_MA0")
	)
	(segment
		(start 162.54984 -1.68402)
		(end 162.54984 -2.921)
		(width 0.2413)
		(layer "F.Cu")
		(net "M_B_MA0")
	)
	(segment
		(start 104.264968 -29.616654)
		(end 104.495346 -29.616654)
		(width 0.1016)
		(layer "F.Cu")
		(net "M_B_MA0")
	)
	(segment
		(start 162.54984 -2.921)
		(end 162.52698 -2.94386)
		(width 0.2413)
		(layer "F.Cu")
		(net "M_B_MA0")
	)
	(segment
		(start 104.495346 -29.616654)
		(end 104.720898 -29.391102)
		(width 0.1016)
		(layer "F.Cu")
		(net "M_B_MA0")
	)
	(via
		(at 104.765348 -29.391102)
		(size 0.4318)
		(drill 0.2032)
		(layers "F.Cu" "B.Cu")
		(net "M_B_MA0")
	)
	(via
		(at 163.130484 -6.554978)
		(size 0.4318)
		(drill 0.2032)
		(layers "F.Cu" "B.Cu")
		(net "M_B_MA0")
	)
	(segment
		(start 162.54984 -7.606538)
		(end 163.130484 -7.025894)
		(width 0.2413)
		(layer "B.Cu")
		(net "M_B_MA0")
	)
	(segment
		(start 162.54984 -9.89076)
		(end 162.54984 -7.606538)
		(width 0.2413)
		(layer "B.Cu")
		(net "M_B_MA0")
	)
	(segment
		(start 163.130484 -7.025894)
		(end 163.130484 -6.554978)
		(width 0.2413)
		(layer "B.Cu")
		(net "M_B_MA0")
	)
	(segment
		(start 117.286024 -25.2603)
		(end 115.114324 -27.432)
		(width 0.1905)
		(layer "In7.Cu")
		(net "M_B_MA0")
	)
	(segment
		(start 164.4142 -6.504178)
		(end 165.608 -7.697978)
		(width 0.1905)
		(layer "In7.Cu")
		(net "M_B_MA0")
	)
	(segment
		(start 163.7792 -9.120378)
		(end 163.50615 -9.393428)
		(width 0.1905)
		(layer "In7.Cu")
		(net "M_B_MA0")
	)
	(segment
		(start 163.181284 -6.504178)
		(end 164.4142 -6.504178)
		(width 0.1905)
		(layer "In7.Cu")
		(net "M_B_MA0")
	)
	(segment
		(start 163.50615 -9.393428)
		(end 163.50615 -15.036546)
		(width 0.1905)
		(layer "In7.Cu")
		(net "M_B_MA0")
	)
	(segment
		(start 165.608 -8.673338)
		(end 165.16096 -9.120378)
		(width 0.1905)
		(layer "In7.Cu")
		(net "M_B_MA0")
	)
	(segment
		(start 165.16096 -9.120378)
		(end 163.7792 -9.120378)
		(width 0.1905)
		(layer "In7.Cu")
		(net "M_B_MA0")
	)
	(segment
		(start 109.5248 -27.8638)
		(end 107.0102 -27.8638)
		(width 0.1016)
		(layer "In7.Cu")
		(net "M_B_MA0")
	)
	(segment
		(start 107.0102 -27.8638)
		(end 105.482898 -29.391102)
		(width 0.1016)
		(layer "In7.Cu")
		(net "M_B_MA0")
	)
	(segment
		(start 153.282396 -25.2603)
		(end 117.286024 -25.2603)
		(width 0.1905)
		(layer "In7.Cu")
		(net "M_B_MA0")
	)
	(segment
		(start 115.114324 -27.432)
		(end 112.0648 -27.432)
		(width 0.1905)
		(layer "In7.Cu")
		(net "M_B_MA0")
	)
	(segment
		(start 163.130484 -6.554978)
		(end 163.181284 -6.504178)
		(width 0.1905)
		(layer "In7.Cu")
		(net "M_B_MA0")
	)
	(segment
		(start 105.482898 -29.391102)
		(end 104.765348 -29.391102)
		(width 0.1016)
		(layer "In7.Cu")
		(net "M_B_MA0")
	)
	(segment
		(start 109.9566 -27.432)
		(end 109.5248 -27.8638)
		(width 0.1016)
		(layer "In7.Cu")
		(net "M_B_MA0")
	)
	(segment
		(start 165.608 -7.697978)
		(end 165.608 -8.673338)
		(width 0.1905)
		(layer "In7.Cu")
		(net "M_B_MA0")
	)
	(segment
		(start 112.0648 -27.432)
		(end 109.9566 -27.432)
		(width 0.1016)
		(layer "In7.Cu")
		(net "M_B_MA0")
	)
	(segment
		(start 163.50615 -15.036546)
		(end 153.282396 -25.2603)
		(width 0.1905)
		(layer "In7.Cu")
		(net "M_B_MA0")
	)
	(segment
		(start 137.94994 -2.595118)
		(end 138.39444 -3.039618)
		(width 0.1778)
		(layer "F.Cu")
		(net "M_B_DQ15")
	)
	(segment
		(start 98.534728 -25.433528)
		(end 98.534728 -26.196036)
		(width 0.1016)
		(layer "F.Cu")
		(net "M_B_DQ15")
	)
	(segment
		(start 97.8662 -24.765)
		(end 98.534728 -25.433528)
		(width 0.1016)
		(layer "F.Cu")
		(net "M_B_DQ15")
	)
	(segment
		(start 97.8662 -21.6662)
		(end 97.8662 -24.765)
		(width 0.1016)
		(layer "F.Cu")
		(net "M_B_DQ15")
	)
	(segment
		(start 98.669348 -26.330656)
		(end 98.669348 -26.561034)
		(width 0.1016)
		(layer "F.Cu")
		(net "M_B_DQ15")
	)
	(segment
		(start 97.3709 -21.1709)
		(end 97.8662 -21.6662)
		(width 0.1016)
		(layer "F.Cu")
		(net "M_B_DQ15")
	)
	(segment
		(start 138.39444 -3.039618)
		(end 138.39444 -3.151378)
		(width 0.1778)
		(layer "F.Cu")
		(net "M_B_DQ15")
	)
	(segment
		(start 137.94994 -1.68402)
		(end 137.94994 -2.595118)
		(width 0.1778)
		(layer "F.Cu")
		(net "M_B_DQ15")
	)
	(segment
		(start 98.534728 -26.196036)
		(end 98.669348 -26.330656)
		(width 0.1016)
		(layer "F.Cu")
		(net "M_B_DQ15")
	)
	(via
		(at 97.3709 -21.1709)
		(size 0.4318)
		(drill 0.2032)
		(layers "F.Cu" "B.Cu")
		(net "M_B_DQ15")
	)
	(via
		(at 138.39444 -3.151378)
		(size 0.4318)
		(drill 0.2032)
		(layers "F.Cu" "B.Cu")
		(net "M_B_DQ15")
	)
	(segment
		(start 138.849862 -1.690624)
		(end 138.849862 -2.604516)
		(width 0.1778)
		(layer "B.Cu")
		(net "M_B_DQ15")
	)
	(segment
		(start 138.39444 -3.059938)
		(end 138.39444 -3.151378)
		(width 0.1778)
		(layer "B.Cu")
		(net "M_B_DQ15")
	)
	(segment
		(start 138.849862 -2.604516)
		(end 138.39444 -3.059938)
		(width 0.1778)
		(layer "B.Cu")
		(net "M_B_DQ15")
	)
	(segment
		(start 136.3472 -12.0904)
		(end 136.3472 -14.7828)
		(width 0.1524)
		(layer "In2.Cu")
		(net "M_B_DQ15")
	)
	(segment
		(start 136.1694 -11.2522)
		(end 136.1694 -11.9126)
		(width 0.1524)
		(layer "In2.Cu")
		(net "M_B_DQ15")
	)
	(segment
		(start 137.795 -6.300978)
		(end 137.541 -6.554978)
		(width 0.1524)
		(layer "In2.Cu")
		(net "M_B_DQ15")
	)
	(segment
		(start 136.3472 -14.7828)
		(end 136.0424 -15.0876)
		(width 0.1524)
		(layer "In2.Cu")
		(net "M_B_DQ15")
	)
	(segment
		(start 137.2362 -7.6708)
		(end 137.2362 -10.8204)
		(width 0.1524)
		(layer "In2.Cu")
		(net "M_B_DQ15")
	)
	(segment
		(start 119.1514 -15.0876)
		(end 118.999 -15.24)
		(width 0.1524)
		(layer "In2.Cu")
		(net "M_B_DQ15")
	)
	(segment
		(start 137.541 -6.554978)
		(end 137.541 -7.366)
		(width 0.1524)
		(layer "In2.Cu")
		(net "M_B_DQ15")
	)
	(segment
		(start 97.972626 -20.569174)
		(end 97.3709 -21.1709)
		(width 0.1524)
		(layer "In2.Cu")
		(net "M_B_DQ15")
	)
	(segment
		(start 102.14864 -18.644108)
		(end 100.223574 -20.569174)
		(width 0.1524)
		(layer "In2.Cu")
		(net "M_B_DQ15")
	)
	(segment
		(start 118.999 -15.24)
		(end 118.999 -16.1798)
		(width 0.1524)
		(layer "In2.Cu")
		(net "M_B_DQ15")
	)
	(segment
		(start 138.39444 -3.151378)
		(end 138.39444 -6.148578)
		(width 0.1524)
		(layer "In2.Cu")
		(net "M_B_DQ15")
	)
	(segment
		(start 109.455712 -16.484346)
		(end 107.29595 -18.644108)
		(width 0.1524)
		(layer "In2.Cu")
		(net "M_B_DQ15")
	)
	(segment
		(start 138.24204 -6.300978)
		(end 137.795 -6.300978)
		(width 0.1524)
		(layer "In2.Cu")
		(net "M_B_DQ15")
	)
	(segment
		(start 136.0424 -15.0876)
		(end 119.1514 -15.0876)
		(width 0.1524)
		(layer "In2.Cu")
		(net "M_B_DQ15")
	)
	(segment
		(start 136.3218 -11.0998)
		(end 136.1694 -11.2522)
		(width 0.1524)
		(layer "In2.Cu")
		(net "M_B_DQ15")
	)
	(segment
		(start 136.9568 -11.0998)
		(end 136.3218 -11.0998)
		(width 0.1524)
		(layer "In2.Cu")
		(net "M_B_DQ15")
	)
	(segment
		(start 118.694454 -16.484346)
		(end 109.455712 -16.484346)
		(width 0.1524)
		(layer "In2.Cu")
		(net "M_B_DQ15")
	)
	(segment
		(start 137.541 -7.366)
		(end 137.2362 -7.6708)
		(width 0.1524)
		(layer "In2.Cu")
		(net "M_B_DQ15")
	)
	(segment
		(start 118.999 -16.1798)
		(end 118.694454 -16.484346)
		(width 0.1524)
		(layer "In2.Cu")
		(net "M_B_DQ15")
	)
	(segment
		(start 136.1694 -11.9126)
		(end 136.3472 -12.0904)
		(width 0.1524)
		(layer "In2.Cu")
		(net "M_B_DQ15")
	)
	(segment
		(start 137.2362 -10.8204)
		(end 136.9568 -11.0998)
		(width 0.1524)
		(layer "In2.Cu")
		(net "M_B_DQ15")
	)
	(segment
		(start 107.29595 -18.644108)
		(end 102.14864 -18.644108)
		(width 0.1524)
		(layer "In2.Cu")
		(net "M_B_DQ15")
	)
	(segment
		(start 100.223574 -20.569174)
		(end 97.972626 -20.569174)
		(width 0.1524)
		(layer "In2.Cu")
		(net "M_B_DQ15")
	)
	(segment
		(start 138.39444 -6.148578)
		(end 138.24204 -6.300978)
		(width 0.1524)
		(layer "In2.Cu")
		(net "M_B_DQ15")
	)
	(segment
		(start 31.4452 -37.465)
		(end 31.4452 -36.6776)
		(width 0.3048)
		(layer "F.Cu")
		(net "P1V0_STBY")
	)
	(segment
		(start 92.248228 -36.799774)
		(end 92.248228 -36.799266)
		(width 0.3048)
		(layer "F.Cu")
		(net "P1V0_STBY")
	)
	(segment
		(start 93.950028 -33.697926)
		(end 93.80347 -33.697926)
		(width 0.3048)
		(layer "F.Cu")
		(net "P1V0_STBY")
	)
	(segment
		(start 93.848428 -36.797996)
		(end 93.478604 -36.428172)
		(width 0.3048)
		(layer "F.Cu")
		(net "P1V0_STBY")
	)
	(segment
		(start 93.848428 -36.799774)
		(end 93.848428 -36.797996)
		(width 0.3048)
		(layer "F.Cu")
		(net "P1V0_STBY")
	)
	(segment
		(start 92.30995 -36.799266)
		(end 92.613734 -36.495482)
		(width 0.3048)
		(layer "F.Cu")
		(net "P1V0_STBY")
	)
	(segment
		(start 93.050868 -36.797996)
		(end 92.658184 -36.405312)
		(width 0.3048)
		(layer "F.Cu")
		(net "P1V0_STBY")
	)
	(segment
		(start 93.848428 -35.258248)
		(end 93.478604 -35.628072)
		(width 0.3048)
		(layer "F.Cu")
		(net "P1V0_STBY")
	)
	(segment
		(start 92.613734 -36.495482)
		(end 92.613734 -36.405312)
		(width 0.3048)
		(layer "F.Cu")
		(net "P1V0_STBY")
	)
	(segment
		(start 92.658184 -36.405312)
		(end 92.613734 -36.405312)
		(width 0.3048)
		(layer "F.Cu")
		(net "P1V0_STBY")
	)
	(segment
		(start 93.050868 -34.400236)
		(end 93.478604 -34.827972)
		(width 0.3048)
		(layer "F.Cu")
		(net "P1V0_STBY")
	)
	(segment
		(start 30.6324 -36.6522)
		(end 30.3784 -36.3982)
		(width 0.3048)
		(layer "F.Cu")
		(net "P1V0_STBY")
	)
	(segment
		(start 92.248228 -36.799266)
		(end 92.30995 -36.799266)
		(width 0.3048)
		(layer "F.Cu")
		(net "P1V0_STBY")
	)
	(segment
		(start 93.80347 -33.697926)
		(end 93.469968 -34.031428)
		(width 0.3048)
		(layer "F.Cu")
		(net "P1V0_STBY")
	)
	(segment
		(start 93.950028 -33.698434)
		(end 93.950028 -33.697926)
		(width 0.3048)
		(layer "F.Cu")
		(net "P1V0_STBY")
	)
	(segment
		(start 31.4452 -34.2392)
		(end 30.9118 -34.2392)
		(width 0.3048)
		(layer "F.Cu")
		(net "P1V0_STBY")
	)
	(segment
		(start 92.248228 -43.200574)
		(end 92.222574 -43.200574)
		(width 0.254)
		(layer "F.Cu")
		(net "P1V0_STBY")
	)
	(segment
		(start 31.4198 -38.3286)
		(end 31.4452 -38.3032)
		(width 0.3048)
		(layer "F.Cu")
		(net "P1V0_STBY")
	)
	(segment
		(start 93.050868 -34.399474)
		(end 93.050868 -34.400236)
		(width 0.3048)
		(layer "F.Cu")
		(net "P1V0_STBY")
	)
	(segment
		(start 93.848428 -35.999674)
		(end 93.848428 -36.058348)
		(width 0.3048)
		(layer "F.Cu")
		(net "P1V0_STBY")
	)
	(segment
		(start 31.4452 -38.3032)
		(end 31.4452 -37.465)
		(width 0.3048)
		(layer "F.Cu")
		(net "P1V0_STBY")
	)
	(segment
		(start 31.4198 -36.6522)
		(end 30.6324 -36.6522)
		(width 0.3048)
		(layer "F.Cu")
		(net "P1V0_STBY")
	)
	(segment
		(start 93.848428 -36.058348)
		(end 93.478604 -36.428172)
		(width 0.3048)
		(layer "F.Cu")
		(net "P1V0_STBY")
	)
	(segment
		(start 92.248228 -35.999166)
		(end 92.30995 -35.999166)
		(width 0.3048)
		(layer "F.Cu")
		(net "P1V0_STBY")
	)
	(segment
		(start 92.252038 -35.199066)
		(end 92.681044 -35.628072)
		(width 0.3048)
		(layer "F.Cu")
		(net "P1V0_STBY")
	)
	(segment
		(start 93.848428 -35.199574)
		(end 93.848428 -35.258248)
		(width 0.3048)
		(layer "F.Cu")
		(net "P1V0_STBY")
	)
	(segment
		(start 93.848428 -34.399474)
		(end 93.848428 -34.458148)
		(width 0.3048)
		(layer "F.Cu")
		(net "P1V0_STBY")
	)
	(segment
		(start 30.9118 -34.2392)
		(end 30.734 -34.417)
		(width 0.3048)
		(layer "F.Cu")
		(net "P1V0_STBY")
	)
	(segment
		(start 93.10751 -35.999166)
		(end 93.478604 -35.628072)
		(width 0.3048)
		(layer "F.Cu")
		(net "P1V0_STBY")
	)
	(segment
		(start 93.848428 -34.458148)
		(end 93.478604 -34.827972)
		(width 0.3048)
		(layer "F.Cu")
		(net "P1V0_STBY")
	)
	(segment
		(start 30.734 -34.417)
		(end 30.6578 -34.417)
		(width 0.3048)
		(layer "F.Cu")
		(net "P1V0_STBY")
	)
	(segment
		(start 92.248228 -35.199066)
		(end 92.252038 -35.199066)
		(width 0.3048)
		(layer "F.Cu")
		(net "P1V0_STBY")
	)
	(segment
		(start 92.248228 -35.999674)
		(end 92.248228 -35.999166)
		(width 0.3048)
		(layer "F.Cu")
		(net "P1V0_STBY")
	)
	(segment
		(start 31.4452 -36.6776)
		(end 31.4198 -36.6522)
		(width 0.3048)
		(layer "F.Cu")
		(net "P1V0_STBY")
	)
	(segment
		(start 92.222574 -43.200574)
		(end 91.821 -42.799)
		(width 0.254)
		(layer "F.Cu")
		(net "P1V0_STBY")
	)
	(segment
		(start 93.050868 -35.999674)
		(end 93.050868 -35.999166)
		(width 0.3048)
		(layer "F.Cu")
		(net "P1V0_STBY")
	)
	(segment
		(start 93.050868 -35.999166)
		(end 93.10751 -35.999166)
		(width 0.3048)
		(layer "F.Cu")
		(net "P1V0_STBY")
	)
	(segment
		(start 93.050868 -36.799774)
		(end 93.050868 -36.797996)
		(width 0.3048)
		(layer "F.Cu")
		(net "P1V0_STBY")
	)
	(segment
		(start 92.30995 -35.999166)
		(end 92.681044 -35.628072)
		(width 0.3048)
		(layer "F.Cu")
		(net "P1V0_STBY")
	)
	(segment
		(start 92.248228 -35.199574)
		(end 92.248228 -35.199066)
		(width 0.3048)
		(layer "F.Cu")
		(net "P1V0_STBY")
	)
	(via
		(at 32.512 -51.6382)
		(size 0.508)
		(drill 0.254)
		(layers "F.Cu" "B.Cu")
		(net "P1V0_STBY")
	)
	(via
		(at 92.681044 -35.628072)
		(size 0.4318)
		(drill 0.2032)
		(layers "F.Cu" "B.Cu")
		(net "P1V0_STBY")
	)
	(via
		(at 65.278 -51.2064)
		(size 0.7112)
		(drill 0.3556)
		(layers "F.Cu" "B.Cu")
		(net "P1V0_STBY")
	)
	(via
		(at 64.0969 -51.3969)
		(size 0.7112)
		(drill 0.4064)
		(layers "F.Cu" "B.Cu")
		(net "P1V0_STBY")
	)
	(via
		(at 91.8718 -36.3982)
		(size 0.4318)
		(drill 0.2032)
		(layers "F.Cu" "B.Cu")
		(net "P1V0_STBY")
	)
	(via
		(at 63.3349 -50.6476)
		(size 0.7112)
		(drill 0.4064)
		(layers "F.Cu" "B.Cu")
		(net "P1V0_STBY")
	)
	(via
		(at 30.6578 -34.417)
		(size 0.508)
		(drill 0.254)
		(layers "F.Cu" "B.Cu")
		(net "P1V0_STBY")
	)
	(via
		(at 93.478604 -34.827972)
		(size 0.4318)
		(drill 0.2032)
		(layers "F.Cu" "B.Cu")
		(net "P1V0_STBY")
	)
	(via
		(at 30.3784 -36.3982)
		(size 0.508)
		(drill 0.254)
		(layers "F.Cu" "B.Cu")
		(net "P1V0_STBY")
	)
	(via
		(at 93.478604 -36.428172)
		(size 0.4318)
		(drill 0.2032)
		(layers "F.Cu" "B.Cu")
		(net "P1V0_STBY")
	)
	(via
		(at 93.469968 -34.031428)
		(size 0.4318)
		(drill 0.2032)
		(layers "F.Cu" "B.Cu")
		(net "P1V0_STBY")
	)
	(via
		(at 93.478604 -35.628072)
		(size 0.4318)
		(drill 0.2032)
		(layers "F.Cu" "B.Cu")
		(net "P1V0_STBY")
	)
	(via
		(at 91.821 -42.799)
		(size 0.4318)
		(drill 0.2032)
		(layers "F.Cu" "B.Cu")
		(net "P1V0_STBY")
	)
	(via
		(at 92.6338 -34.036)
		(size 0.4318)
		(drill 0.2032)
		(layers "F.Cu" "B.Cu")
		(net "P1V0_STBY")
	)
	(via
		(at 92.613734 -36.405312)
		(size 0.4318)
		(drill 0.2032)
		(layers "F.Cu" "B.Cu")
		(net "P1V0_STBY")
	)
	(segment
		(start 30.6832 -34.3916)
		(end 30.6578 -34.417)
		(width 0.508)
		(layer "B.Cu")
		(net "P1V0_STBY")
	)
	(segment
		(start 91.567 -42.5958)
		(end 91.7702 -42.799)
		(width 0.3048)
		(layer "B.Cu")
		(net "P1V0_STBY")
	)
	(segment
		(start 30.6832 -33.6042)
		(end 30.6832 -34.3916)
		(width 0.508)
		(layer "B.Cu")
		(net "P1V0_STBY")
	)
	(segment
		(start 91.7702 -42.799)
		(end 91.821 -42.799)
		(width 0.3048)
		(layer "B.Cu")
		(net "P1V0_STBY")
	)
	(segment
		(start 91.186 -42.5958)
		(end 91.567 -42.5958)
		(width 0.3048)
		(layer "B.Cu")
		(net "P1V0_STBY")
	)
	(segment
		(start 28.4734 -48.481234)
		(end 29.191966 -49.1998)
		(width 0.3048)
		(layer "In2.Cu")
		(net "P1V0_STBY")
	)
	(segment
		(start 92.4052 -40.7797)
		(end 92.4052 -39.6875)
		(width 0.3048)
		(layer "In2.Cu")
		(net "P1V0_STBY")
	)
	(segment
		(start 92.4052 -39.6875)
		(end 92.1639 -39.4462)
		(width 0.3048)
		(layer "In2.Cu")
		(net "P1V0_STBY")
	)
	(segment
		(start 32.512 -51.590194)
		(end 32.512 -51.6382)
		(width 0.3048)
		(layer "In2.Cu")
		(net "P1V0_STBY")
	)
	(segment
		(start 28.4734 -39.9034)
		(end 28.4734 -48.481234)
		(width 0.3048)
		(layer "In2.Cu")
		(net "P1V0_STBY")
	)
	(segment
		(start 91.5543 -42.5323)
		(end 91.5543 -41.6306)
		(width 0.3048)
		(layer "In2.Cu")
		(net "P1V0_STBY")
	)
	(segment
		(start 30.5054 -37.8714)
		(end 28.4734 -39.9034)
		(width 0.3048)
		(layer "In2.Cu")
		(net "P1V0_STBY")
	)
	(segment
		(start 30.3784 -36.3982)
		(end 30.5054 -36.5252)
		(width 0.3048)
		(layer "In2.Cu")
		(net "P1V0_STBY")
	)
	(segment
		(start 29.191966 -49.1998)
		(end 30.121606 -49.1998)
		(width 0.3048)
		(layer "In2.Cu")
		(net "P1V0_STBY")
	)
	(segment
		(start 91.5543 -41.6306)
		(end 92.4052 -40.7797)
		(width 0.3048)
		(layer "In2.Cu")
		(net "P1V0_STBY")
	)
	(segment
		(start 30.5054 -36.5252)
		(end 30.5054 -37.8714)
		(width 0.3048)
		(layer "In2.Cu")
		(net "P1V0_STBY")
	)
	(segment
		(start 91.821 -42.799)
		(end 91.5543 -42.5323)
		(width 0.3048)
		(layer "In2.Cu")
		(net "P1V0_STBY")
	)
	(segment
		(start 30.121606 -49.1998)
		(end 32.512 -51.590194)
		(width 0.3048)
		(layer "In2.Cu")
		(net "P1V0_STBY")
	)
	(segment
		(start 92.538804 -38.194996)
		(end 92.538804 -37.065204)
		(width 0.3048)
		(layer "In2.Cu")
		(net "P1V0_STBY")
	)
	(segment
		(start 92.1639 -38.5699)
		(end 92.538804 -38.194996)
		(width 0.3048)
		(layer "In2.Cu")
		(net "P1V0_STBY")
	)
	(segment
		(start 92.538804 -37.065204)
		(end 91.8718 -36.3982)
		(width 0.3048)
		(layer "In2.Cu")
		(net "P1V0_STBY")
	)
	(segment
		(start 92.1639 -39.4462)
		(end 92.1639 -38.5699)
		(width 0.3048)
		(layer "In2.Cu")
		(net "P1V0_STBY")
	)
	(segment
		(start 48.326802 -55.1688)
		(end 48.060102 -55.4355)
		(width 0.3048)
		(layer "In4.Cu")
		(net "P1V0_STBY")
	)
	(segment
		(start 61.64834 -51.54295)
		(end 61.17844 -51.54295)
		(width 0.3048)
		(layer "In4.Cu")
		(net "P1V0_STBY")
	)
	(segment
		(start 54.121812 -55.1688)
		(end 48.326802 -55.1688)
		(width 0.3048)
		(layer "In4.Cu")
		(net "P1V0_STBY")
	)
	(segment
		(start 59.331606 -51.31435)
		(end 58.844942 -51.31435)
		(width 0.3048)
		(layer "In4.Cu")
		(net "P1V0_STBY")
	)
	(segment
		(start 54.621684 -55.1688)
		(end 54.62143 -55.169054)
		(width 0.3048)
		(layer "In4.Cu")
		(net "P1V0_STBY")
	)
	(segment
		(start 59.56046 -51.543204)
		(end 59.331606 -51.31435)
		(width 0.3048)
		(layer "In4.Cu")
		(net "P1V0_STBY")
	)
	(segment
		(start 35.1155 -55.4355)
		(end 32.512 -52.832)
		(width 0.3048)
		(layer "In4.Cu")
		(net "P1V0_STBY")
	)
	(segment
		(start 58.844942 -51.31435)
		(end 54.990492 -55.1688)
		(width 0.3048)
		(layer "In4.Cu")
		(net "P1V0_STBY")
	)
	(segment
		(start 61.177932 -51.543458)
		(end 60.699396 -51.543458)
		(width 0.3048)
		(layer "In4.Cu")
		(net "P1V0_STBY")
	)
	(segment
		(start 32.512 -52.832)
		(end 32.512 -51.6382)
		(width 0.3048)
		(layer "In4.Cu")
		(net "P1V0_STBY")
	)
	(segment
		(start 60.699142 -51.543204)
		(end 59.56046 -51.543204)
		(width 0.3048)
		(layer "In4.Cu")
		(net "P1V0_STBY")
	)
	(segment
		(start 54.990492 -55.1688)
		(end 54.621684 -55.1688)
		(width 0.3048)
		(layer "In4.Cu")
		(net "P1V0_STBY")
	)
	(segment
		(start 54.122066 -55.169054)
		(end 54.121812 -55.1688)
		(width 0.3048)
		(layer "In4.Cu")
		(net "P1V0_STBY")
	)
	(segment
		(start 54.62143 -55.169054)
		(end 54.122066 -55.169054)
		(width 0.3048)
		(layer "In4.Cu")
		(net "P1V0_STBY")
	)
	(segment
		(start 61.17844 -51.54295)
		(end 61.177932 -51.543458)
		(width 0.3048)
		(layer "In4.Cu")
		(net "P1V0_STBY")
	)
	(segment
		(start 62.3443 -51.3207)
		(end 61.87059 -51.3207)
		(width 0.3048)
		(layer "In4.Cu")
		(net "P1V0_STBY")
	)
	(segment
		(start 61.87059 -51.3207)
		(end 61.64834 -51.54295)
		(width 0.3048)
		(layer "In4.Cu")
		(net "P1V0_STBY")
	)
	(segment
		(start 60.699396 -51.543458)
		(end 60.699142 -51.543204)
		(width 0.3048)
		(layer "In4.Cu")
		(net "P1V0_STBY")
	)
	(segment
		(start 48.060102 -55.4355)
		(end 35.1155 -55.4355)
		(width 0.3048)
		(layer "In4.Cu")
		(net "P1V0_STBY")
	)
	(segment
		(start 31.1658 -34.925)
		(end 30.6578 -34.417)
		(width 0.3048)
		(layer "In9.Cu")
		(net "P1V0_STBY")
	)
	(segment
		(start 31.1658 -35.6108)
		(end 31.1658 -34.925)
		(width 0.3048)
		(layer "In9.Cu")
		(net "P1V0_STBY")
	)
	(segment
		(start 30.3784 -36.3982)
		(end 31.1658 -35.6108)
		(width 0.3048)
		(layer "In9.Cu")
		(net "P1V0_STBY")
	)
	(segment
		(start 141.85011 -62.59322)
		(end 141.85011 -63.337694)
		(width 0.1778)
		(layer "F.Cu")
		(net "M_A_DQS_DN5")
	)
	(segment
		(start 141.702536 -66.407538)
		(end 141.967204 -66.672206)
		(width 0.1778)
		(layer "F.Cu")
		(net "M_A_DQS_DN5")
	)
	(segment
		(start 103.859584 -52.140358)
		(end 103.993188 -52.006754)
		(width 0.1016)
		(layer "F.Cu")
		(net "M_A_DQS_DN5")
	)
	(segment
		(start 104.4702 -53.839872)
		(end 103.859584 -53.229256)
		(width 0.1016)
		(layer "F.Cu")
		(net "M_A_DQS_DN5")
	)
	(segment
		(start 141.702536 -63.485268)
		(end 141.702536 -66.407538)
		(width 0.1778)
		(layer "F.Cu")
		(net "M_A_DQS_DN5")
	)
	(segment
		(start 104.6734 -55.4736)
		(end 104.4702 -55.2704)
		(width 0.1016)
		(layer "F.Cu")
		(net "M_A_DQS_DN5")
	)
	(segment
		(start 141.85011 -63.337694)
		(end 141.702536 -63.485268)
		(width 0.1778)
		(layer "F.Cu")
		(net "M_A_DQS_DN5")
	)
	(segment
		(start 104.4702 -55.2704)
		(end 104.4702 -53.839872)
		(width 0.1016)
		(layer "F.Cu")
		(net "M_A_DQS_DN5")
	)
	(segment
		(start 103.859584 -53.229256)
		(end 103.859584 -52.140358)
		(width 0.1016)
		(layer "F.Cu")
		(net "M_A_DQS_DN5")
	)
	(via
		(at 104.6734 -55.4736)
		(size 0.4318)
		(drill 0.2032)
		(layers "F.Cu" "B.Cu")
		(net "M_A_DQS_DN5")
	)
	(via
		(at 141.967204 -66.672206)
		(size 0.4318)
		(drill 0.2032)
		(layers "F.Cu" "B.Cu")
		(net "M_A_DQS_DN5")
	)
	(segment
		(start 141.85011 -70.02018)
		(end 141.702536 -69.872606)
		(width 0.1778)
		(layer "B.Cu")
		(net "M_A_DQS_DN5")
	)
	(segment
		(start 141.702536 -66.936874)
		(end 141.967204 -66.672206)
		(width 0.1778)
		(layer "B.Cu")
		(net "M_A_DQS_DN5")
	)
	(segment
		(start 141.85011 -70.79996)
		(end 141.85011 -70.02018)
		(width 0.1778)
		(layer "B.Cu")
		(net "M_A_DQS_DN5")
	)
	(segment
		(start 141.702536 -69.872606)
		(end 141.702536 -66.936874)
		(width 0.1778)
		(layer "B.Cu")
		(net "M_A_DQS_DN5")
	)
	(segment
		(start 132.86486 -59.05754)
		(end 132.7404 -59.182)
		(width 0.1524)
		(layer "In2.Cu")
		(net "M_A_DQS_DN5")
	)
	(segment
		(start 141.96187 -62.065154)
		(end 140.82522 -60.928504)
		(width 0.1524)
		(layer "In2.Cu")
		(net "M_A_DQS_DN5")
	)
	(segment
		(start 140.32611 -60.429394)
		(end 140.002768 -60.106052)
		(width 0.1524)
		(layer "In2.Cu")
		(net "M_A_DQS_DN5")
	)
	(segment
		(start 126.469902 -58.436002)
		(end 126.153926 -58.751978)
		(width 0.1524)
		(layer "In2.Cu")
		(net "M_A_DQS_DN5")
	)
	(segment
		(start 141.967204 -66.672206)
		(end 141.689836 -66.394838)
		(width 0.1524)
		(layer "In2.Cu")
		(net "M_A_DQS_DN5")
	)
	(segment
		(start 123.45035 -58.436002)
		(end 105.922826 -58.436002)
		(width 0.1524)
		(layer "In2.Cu")
		(net "M_A_DQS_DN5")
	)
	(segment
		(start 141.689836 -66.1162)
		(end 141.96187 -65.844166)
		(width 0.1524)
		(layer "In2.Cu")
		(net "M_A_DQS_DN5")
	)
	(segment
		(start 123.766326 -59.5884)
		(end 123.766326 -58.751978)
		(width 0.1524)
		(layer "In2.Cu")
		(net "M_A_DQS_DN5")
	)
	(segment
		(start 127.754126 -59.309)
		(end 127.601726 -59.1566)
		(width 0.1524)
		(layer "In2.Cu")
		(net "M_A_DQS_DN5")
	)
	(segment
		(start 127.601726 -59.1566)
		(end 127.601726 -58.751978)
		(width 0.1524)
		(layer "In2.Cu")
		(net "M_A_DQS_DN5")
	)
	(segment
		(start 124.223526 -59.7408)
		(end 123.918726 -59.7408)
		(width 0.1524)
		(layer "In2.Cu")
		(net "M_A_DQS_DN5")
	)
	(segment
		(start 105.922826 -58.436002)
		(end 105.1433 -57.656476)
		(width 0.1524)
		(layer "In2.Cu")
		(net "M_A_DQS_DN5")
	)
	(segment
		(start 132.2832 -59.182)
		(end 131.537202 -58.436002)
		(width 0.1524)
		(layer "In2.Cu")
		(net "M_A_DQS_DN5")
	)
	(segment
		(start 125.696726 -59.7408)
		(end 125.544326 -59.5884)
		(width 0.1524)
		(layer "In2.Cu")
		(net "M_A_DQS_DN5")
	)
	(segment
		(start 128.211326 -59.1566)
		(end 128.058926 -59.309)
		(width 0.1524)
		(layer "In2.Cu")
		(net "M_A_DQS_DN5")
	)
	(segment
		(start 140.82522 -60.928504)
		(end 140.82522 -60.752482)
		(width 0.1524)
		(layer "In2.Cu")
		(net "M_A_DQS_DN5")
	)
	(segment
		(start 138.697716 -58.801)
		(end 135.854186 -58.801)
		(width 0.1524)
		(layer "In2.Cu")
		(net "M_A_DQS_DN5")
	)
	(segment
		(start 134.60984 -59.182)
		(end 134.48538 -59.05754)
		(width 0.1524)
		(layer "In2.Cu")
		(net "M_A_DQS_DN5")
	)
	(segment
		(start 133.32206 -59.05754)
		(end 132.86486 -59.05754)
		(width 0.1524)
		(layer "In2.Cu")
		(net "M_A_DQS_DN5")
	)
	(segment
		(start 131.537202 -58.436002)
		(end 128.527302 -58.436002)
		(width 0.1524)
		(layer "In2.Cu")
		(net "M_A_DQS_DN5")
	)
	(segment
		(start 141.96187 -65.844166)
		(end 141.96187 -62.065154)
		(width 0.1524)
		(layer "In2.Cu")
		(net "M_A_DQS_DN5")
	)
	(segment
		(start 126.153926 -59.5884)
		(end 126.001526 -59.7408)
		(width 0.1524)
		(layer "In2.Cu")
		(net "M_A_DQS_DN5")
	)
	(segment
		(start 105.1433 -57.656476)
		(end 105.1433 -55.9435)
		(width 0.1016)
		(layer "In2.Cu")
		(net "M_A_DQS_DN5")
	)
	(segment
		(start 133.90372 -59.182)
		(end 133.44652 -59.182)
		(width 0.1524)
		(layer "In2.Cu")
		(net "M_A_DQS_DN5")
	)
	(segment
		(start 123.766326 -58.751978)
		(end 123.45035 -58.436002)
		(width 0.1524)
		(layer "In2.Cu")
		(net "M_A_DQS_DN5")
	)
	(segment
		(start 135.473186 -59.182)
		(end 134.60984 -59.182)
		(width 0.1524)
		(layer "In2.Cu")
		(net "M_A_DQS_DN5")
	)
	(segment
		(start 140.502132 -60.429394)
		(end 140.32611 -60.429394)
		(width 0.1524)
		(layer "In2.Cu")
		(net "M_A_DQS_DN5")
	)
	(segment
		(start 134.02818 -59.05754)
		(end 133.90372 -59.182)
		(width 0.1524)
		(layer "In2.Cu")
		(net "M_A_DQS_DN5")
	)
	(segment
		(start 128.527302 -58.436002)
		(end 128.211326 -58.751978)
		(width 0.1524)
		(layer "In2.Cu")
		(net "M_A_DQS_DN5")
	)
	(segment
		(start 127.601726 -58.751978)
		(end 127.28575 -58.436002)
		(width 0.1524)
		(layer "In2.Cu")
		(net "M_A_DQS_DN5")
	)
	(segment
		(start 128.058926 -59.309)
		(end 127.754126 -59.309)
		(width 0.1524)
		(layer "In2.Cu")
		(net "M_A_DQS_DN5")
	)
	(segment
		(start 140.82522 -60.752482)
		(end 140.502132 -60.429394)
		(width 0.1524)
		(layer "In2.Cu")
		(net "M_A_DQS_DN5")
	)
	(segment
		(start 133.44652 -59.182)
		(end 133.32206 -59.05754)
		(width 0.1524)
		(layer "In2.Cu")
		(net "M_A_DQS_DN5")
	)
	(segment
		(start 141.689836 -66.394838)
		(end 141.689836 -66.1162)
		(width 0.1524)
		(layer "In2.Cu")
		(net "M_A_DQS_DN5")
	)
	(segment
		(start 140.002768 -60.106052)
		(end 140.002768 -59.93003)
		(width 0.1524)
		(layer "In2.Cu")
		(net "M_A_DQS_DN5")
	)
	(segment
		(start 140.002768 -59.93003)
		(end 139.679426 -59.606688)
		(width 0.1524)
		(layer "In2.Cu")
		(net "M_A_DQS_DN5")
	)
	(segment
		(start 125.22835 -58.436002)
		(end 124.691902 -58.436002)
		(width 0.1524)
		(layer "In2.Cu")
		(net "M_A_DQS_DN5")
	)
	(segment
		(start 132.7404 -59.182)
		(end 132.2832 -59.182)
		(width 0.1524)
		(layer "In2.Cu")
		(net "M_A_DQS_DN5")
	)
	(segment
		(start 124.375926 -58.751978)
		(end 124.375926 -59.5884)
		(width 0.1524)
		(layer "In2.Cu")
		(net "M_A_DQS_DN5")
	)
	(segment
		(start 126.001526 -59.7408)
		(end 125.696726 -59.7408)
		(width 0.1524)
		(layer "In2.Cu")
		(net "M_A_DQS_DN5")
	)
	(segment
		(start 135.854186 -58.801)
		(end 135.473186 -59.182)
		(width 0.1524)
		(layer "In2.Cu")
		(net "M_A_DQS_DN5")
	)
	(segment
		(start 125.544326 -58.751978)
		(end 125.22835 -58.436002)
		(width 0.1524)
		(layer "In2.Cu")
		(net "M_A_DQS_DN5")
	)
	(segment
		(start 127.28575 -58.436002)
		(end 126.469902 -58.436002)
		(width 0.1524)
		(layer "In2.Cu")
		(net "M_A_DQS_DN5")
	)
	(segment
		(start 124.375926 -59.5884)
		(end 124.223526 -59.7408)
		(width 0.1524)
		(layer "In2.Cu")
		(net "M_A_DQS_DN5")
	)
	(segment
		(start 128.211326 -58.751978)
		(end 128.211326 -59.1566)
		(width 0.1524)
		(layer "In2.Cu")
		(net "M_A_DQS_DN5")
	)
	(segment
		(start 105.1433 -55.9435)
		(end 104.6734 -55.4736)
		(width 0.1016)
		(layer "In2.Cu")
		(net "M_A_DQS_DN5")
	)
	(segment
		(start 139.503404 -59.606688)
		(end 138.697716 -58.801)
		(width 0.1524)
		(layer "In2.Cu")
		(net "M_A_DQS_DN5")
	)
	(segment
		(start 123.918726 -59.7408)
		(end 123.766326 -59.5884)
		(width 0.1524)
		(layer "In2.Cu")
		(net "M_A_DQS_DN5")
	)
	(segment
		(start 134.48538 -59.05754)
		(end 134.02818 -59.05754)
		(width 0.1524)
		(layer "In2.Cu")
		(net "M_A_DQS_DN5")
	)
	(segment
		(start 124.691902 -58.436002)
		(end 124.375926 -58.751978)
		(width 0.1524)
		(layer "In2.Cu")
		(net "M_A_DQS_DN5")
	)
	(segment
		(start 126.153926 -58.751978)
		(end 126.153926 -59.5884)
		(width 0.1524)
		(layer "In2.Cu")
		(net "M_A_DQS_DN5")
	)
	(segment
		(start 139.679426 -59.606688)
		(end 139.503404 -59.606688)
		(width 0.1524)
		(layer "In2.Cu")
		(net "M_A_DQS_DN5")
	)
	(segment
		(start 125.544326 -59.5884)
		(end 125.544326 -58.751978)
		(width 0.1524)
		(layer "In2.Cu")
		(net "M_A_DQS_DN5")
	)
	(segment
		(start 97.922842 -31.138368)
		(end 97.922842 -31.123128)
		(width 0.1016)
		(layer "F.Cu")
		(net "M_B_DQS_DP3")
	)
	(segment
		(start 146.502374 -9.00684)
		(end 146.502374 -6.0833)
		(width 0.1778)
		(layer "F.Cu")
		(net "M_B_DQS_DP3")
	)
	(segment
		(start 146.502374 -6.0833)
		(end 146.767296 -5.818378)
		(width 0.1778)
		(layer "F.Cu")
		(net "M_B_DQS_DP3")
	)
	(segment
		(start 146.649948 -9.897364)
		(end 146.649948 -9.154414)
		(width 0.1778)
		(layer "F.Cu")
		(net "M_B_DQS_DP3")
	)
	(segment
		(start 98.306128 -31.521654)
		(end 97.922842 -31.138368)
		(width 0.1016)
		(layer "F.Cu")
		(net "M_B_DQS_DP3")
	)
	(segment
		(start 146.649948 -9.154414)
		(end 146.502374 -9.00684)
		(width 0.1778)
		(layer "F.Cu")
		(net "M_B_DQS_DP3")
	)
	(via
		(at 97.922842 -31.123128)
		(size 0.4318)
		(drill 0.2032)
		(layers "F.Cu" "B.Cu")
		(net "M_B_DQS_DP3")
	)
	(via
		(at 146.767296 -5.818378)
		(size 0.4318)
		(drill 0.2032)
		(layers "F.Cu" "B.Cu")
		(net "M_B_DQS_DP3")
	)
	(segment
		(start 146.649948 -1.690624)
		(end 146.649948 -2.42443)
		(width 0.1778)
		(layer "B.Cu")
		(net "M_B_DQS_DP3")
	)
	(segment
		(start 146.502374 -2.572004)
		(end 146.502374 -5.553456)
		(width 0.1778)
		(layer "B.Cu")
		(net "M_B_DQS_DP3")
	)
	(segment
		(start 146.649948 -2.42443)
		(end 146.502374 -2.572004)
		(width 0.1778)
		(layer "B.Cu")
		(net "M_B_DQS_DP3")
	)
	(segment
		(start 146.502374 -5.553456)
		(end 146.767296 -5.818378)
		(width 0.1778)
		(layer "B.Cu")
		(net "M_B_DQS_DP3")
	)
	(segment
		(start 135.9916 -20.447)
		(end 135.9916 -19.7104)
		(width 0.1524)
		(layer "In4.Cu")
		(net "M_B_DQS_DP3")
	)
	(segment
		(start 146.304 -8.678672)
		(end 146.177254 -8.805418)
		(width 0.1524)
		(layer "In4.Cu")
		(net "M_B_DQS_DP3")
	)
	(segment
		(start 108.0008 -25.07234)
		(end 107.249214 -25.823926)
		(width 0.1524)
		(layer "In4.Cu")
		(net "M_B_DQS_DP3")
	)
	(segment
		(start 107.249214 -25.823926)
		(end 107.231434 -25.841706)
		(width 0.1016)
		(layer "In4.Cu")
		(net "M_B_DQS_DP3")
	)
	(segment
		(start 112.4458 -23.2664)
		(end 108.446824 -23.2664)
		(width 0.1524)
		(layer "In4.Cu")
		(net "M_B_DQS_DP3")
	)
	(segment
		(start 97.922842 -30.997144)
		(end 97.922842 -31.123128)
		(width 0.1016)
		(layer "In4.Cu")
		(net "M_B_DQS_DP3")
	)
	(segment
		(start 135.3566 -20.5486)
		(end 135.0772 -20.828)
		(width 0.1524)
		(layer "In4.Cu")
		(net "M_B_DQS_DP3")
	)
	(segment
		(start 146.177254 -20.18157)
		(end 145.530824 -20.828)
		(width 0.1524)
		(layer "In4.Cu")
		(net "M_B_DQS_DP3")
	)
	(segment
		(start 135.509 -19.558)
		(end 135.3566 -19.7104)
		(width 0.1524)
		(layer "In4.Cu")
		(net "M_B_DQS_DP3")
	)
	(segment
		(start 135.3566 -19.7104)
		(end 135.3566 -20.5486)
		(width 0.1524)
		(layer "In4.Cu")
		(net "M_B_DQS_DP3")
	)
	(segment
		(start 106.9086 -26.1112)
		(end 105.95737 -26.1112)
		(width 0.1016)
		(layer "In4.Cu")
		(net "M_B_DQS_DP3")
	)
	(segment
		(start 146.177254 -8.805418)
		(end 146.177254 -20.18157)
		(width 0.1524)
		(layer "In4.Cu")
		(net "M_B_DQS_DP3")
	)
	(segment
		(start 146.5072 -6.518402)
		(end 146.304 -6.721602)
		(width 0.1524)
		(layer "In4.Cu")
		(net "M_B_DQS_DP3")
	)
	(segment
		(start 99.009962 -29.329888)
		(end 99.009962 -29.910024)
		(width 0.1016)
		(layer "In4.Cu")
		(net "M_B_DQS_DP3")
	)
	(segment
		(start 101.220778 -27.119072)
		(end 99.009962 -29.329888)
		(width 0.1016)
		(layer "In4.Cu")
		(net "M_B_DQS_DP3")
	)
	(segment
		(start 107.178094 -25.841706)
		(end 106.9086 -26.1112)
		(width 0.1016)
		(layer "In4.Cu")
		(net "M_B_DQS_DP3")
	)
	(segment
		(start 146.767296 -5.818378)
		(end 146.5072 -6.078474)
		(width 0.1524)
		(layer "In4.Cu")
		(net "M_B_DQS_DP3")
	)
	(segment
		(start 99.009962 -29.910024)
		(end 97.922842 -30.997144)
		(width 0.1016)
		(layer "In4.Cu")
		(net "M_B_DQS_DP3")
	)
	(segment
		(start 135.8392 -19.558)
		(end 135.509 -19.558)
		(width 0.1524)
		(layer "In4.Cu")
		(net "M_B_DQS_DP3")
	)
	(segment
		(start 135.9916 -19.7104)
		(end 135.8392 -19.558)
		(width 0.1524)
		(layer "In4.Cu")
		(net "M_B_DQS_DP3")
	)
	(segment
		(start 108.0008 -23.712424)
		(end 108.0008 -25.07234)
		(width 0.1524)
		(layer "In4.Cu")
		(net "M_B_DQS_DP3")
	)
	(segment
		(start 146.5072 -6.078474)
		(end 146.5072 -6.518402)
		(width 0.1524)
		(layer "In4.Cu")
		(net "M_B_DQS_DP3")
	)
	(segment
		(start 104.948736 -27.119072)
		(end 101.220778 -27.119072)
		(width 0.1016)
		(layer "In4.Cu")
		(net "M_B_DQS_DP3")
	)
	(segment
		(start 108.446824 -23.2664)
		(end 108.0008 -23.712424)
		(width 0.1524)
		(layer "In4.Cu")
		(net "M_B_DQS_DP3")
	)
	(segment
		(start 136.3726 -20.828)
		(end 135.9916 -20.447)
		(width 0.1524)
		(layer "In4.Cu")
		(net "M_B_DQS_DP3")
	)
	(segment
		(start 107.231434 -25.841706)
		(end 107.178094 -25.841706)
		(width 0.1016)
		(layer "In4.Cu")
		(net "M_B_DQS_DP3")
	)
	(segment
		(start 114.8842 -20.828)
		(end 112.4458 -23.2664)
		(width 0.1524)
		(layer "In4.Cu")
		(net "M_B_DQS_DP3")
	)
	(segment
		(start 145.530824 -20.828)
		(end 136.3726 -20.828)
		(width 0.1524)
		(layer "In4.Cu")
		(net "M_B_DQS_DP3")
	)
	(segment
		(start 146.304 -6.721602)
		(end 146.304 -8.678672)
		(width 0.1524)
		(layer "In4.Cu")
		(net "M_B_DQS_DP3")
	)
	(segment
		(start 135.0772 -20.828)
		(end 114.8842 -20.828)
		(width 0.1524)
		(layer "In4.Cu")
		(net "M_B_DQS_DP3")
	)
	(segment
		(start 105.95737 -26.1112)
		(end 104.948736 -27.119072)
		(width 0.1016)
		(layer "In4.Cu")
		(net "M_B_DQS_DP3")
	)
	(segment
		(start 161.58337 -66.956686)
		(end 161.145728 -67.394328)
		(width 0.2413)
		(layer "F.Cu")
		(net "M_A_MA9")
	)
	(segment
		(start 160.9344 -65.5574)
		(end 161.2646 -65.5574)
		(width 0.2413)
		(layer "F.Cu")
		(net "M_A_MA9")
	)
	(segment
		(start 161.145728 -67.394328)
		(end 161.10712 -67.394328)
		(width 0.2413)
		(layer "F.Cu")
		(net "M_A_MA9")
	)
	(segment
		(start 105.604056 -47.29607)
		(end 105.661968 -47.29607)
		(width 0.1016)
		(layer "F.Cu")
		(net "M_A_MA9")
	)
	(segment
		(start 105.311448 -47.588678)
		(end 105.604056 -47.29607)
		(width 0.1016)
		(layer "F.Cu")
		(net "M_A_MA9")
	)
	(segment
		(start 105.311448 -47.640494)
		(end 105.311448 -47.588678)
		(width 0.1016)
		(layer "F.Cu")
		(net "M_A_MA9")
	)
	(segment
		(start 161.58337 -65.87617)
		(end 161.58337 -66.956686)
		(width 0.2413)
		(layer "F.Cu")
		(net "M_A_MA9")
	)
	(segment
		(start 160.450022 -65.073022)
		(end 160.9344 -65.5574)
		(width 0.2413)
		(layer "F.Cu")
		(net "M_A_MA9")
	)
	(segment
		(start 160.450022 -62.59322)
		(end 160.450022 -65.073022)
		(width 0.2413)
		(layer "F.Cu")
		(net "M_A_MA9")
	)
	(segment
		(start 161.2646 -65.5574)
		(end 161.58337 -65.87617)
		(width 0.2413)
		(layer "F.Cu")
		(net "M_A_MA9")
	)
	(via
		(at 105.661968 -47.29607)
		(size 0.4318)
		(drill 0.2032)
		(layers "F.Cu" "B.Cu")
		(net "M_A_MA9")
	)
	(via
		(at 161.10712 -67.394328)
		(size 0.4318)
		(drill 0.2032)
		(layers "F.Cu" "B.Cu")
		(net "M_A_MA9")
	)
	(segment
		(start 160.505648 -69.547486)
		(end 160.505648 -67.9958)
		(width 0.2413)
		(layer "B.Cu")
		(net "M_A_MA9")
	)
	(segment
		(start 160.450022 -69.603112)
		(end 160.505648 -69.547486)
		(width 0.2413)
		(layer "B.Cu")
		(net "M_A_MA9")
	)
	(segment
		(start 160.450022 -70.79996)
		(end 160.450022 -69.603112)
		(width 0.2413)
		(layer "B.Cu")
		(net "M_A_MA9")
	)
	(segment
		(start 160.505648 -67.9958)
		(end 161.10712 -67.394328)
		(width 0.2413)
		(layer "B.Cu")
		(net "M_A_MA9")
	)
	(segment
		(start 160.02 -65.024)
		(end 160.637728 -65.641728)
		(width 0.1905)
		(layer "In9.Cu")
		(net "M_A_MA9")
	)
	(segment
		(start 107.302046 -47.752)
		(end 107.304586 -47.74946)
		(width 0.1016)
		(layer "In9.Cu")
		(net "M_A_MA9")
	)
	(segment
		(start 160.637728 -65.641728)
		(end 160.637728 -66.92773)
		(width 0.1905)
		(layer "In9.Cu")
		(net "M_A_MA9")
	)
	(segment
		(start 108.283502 -47.74946)
		(end 108.324142 -47.7901)
		(width 0.1016)
		(layer "In9.Cu")
		(net "M_A_MA9")
	)
	(segment
		(start 160.637728 -66.92773)
		(end 161.104326 -67.394328)
		(width 0.1905)
		(layer "In9.Cu")
		(net "M_A_MA9")
	)
	(segment
		(start 149.40788 -48.9331)
		(end 149.408134 -48.932846)
		(width 0.1905)
		(layer "In9.Cu")
		(net "M_A_MA9")
	)
	(segment
		(start 160.28035 -62.32525)
		(end 160.02 -62.5856)
		(width 0.1905)
		(layer "In9.Cu")
		(net "M_A_MA9")
	)
	(segment
		(start 106.96194 -47.752)
		(end 107.302046 -47.752)
		(width 0.1016)
		(layer "In9.Cu")
		(net "M_A_MA9")
	)
	(segment
		(start 119.61495 -48.40605)
		(end 145.09115 -48.40605)
		(width 0.1905)
		(layer "In9.Cu")
		(net "M_A_MA9")
	)
	(segment
		(start 105.661968 -47.29607)
		(end 106.50601 -47.29607)
		(width 0.1016)
		(layer "In9.Cu")
		(net "M_A_MA9")
	)
	(segment
		(start 151.196548 -48.932846)
		(end 160.28035 -58.016648)
		(width 0.1905)
		(layer "In9.Cu")
		(net "M_A_MA9")
	)
	(segment
		(start 108.324142 -47.7901)
		(end 113.4491 -47.7901)
		(width 0.1016)
		(layer "In9.Cu")
		(net "M_A_MA9")
	)
	(segment
		(start 145.6182 -48.9331)
		(end 149.40788 -48.9331)
		(width 0.1905)
		(layer "In9.Cu")
		(net "M_A_MA9")
	)
	(segment
		(start 145.09115 -48.40605)
		(end 145.6182 -48.9331)
		(width 0.1905)
		(layer "In9.Cu")
		(net "M_A_MA9")
	)
	(segment
		(start 161.104326 -67.394328)
		(end 161.10712 -67.394328)
		(width 0.1905)
		(layer "In9.Cu")
		(net "M_A_MA9")
	)
	(segment
		(start 106.50601 -47.29607)
		(end 106.96194 -47.752)
		(width 0.1016)
		(layer "In9.Cu")
		(net "M_A_MA9")
	)
	(segment
		(start 149.408134 -48.932846)
		(end 151.196548 -48.932846)
		(width 0.1905)
		(layer "In9.Cu")
		(net "M_A_MA9")
	)
	(segment
		(start 160.28035 -58.016648)
		(end 160.28035 -62.32525)
		(width 0.1905)
		(layer "In9.Cu")
		(net "M_A_MA9")
	)
	(segment
		(start 119.5578 -48.4632)
		(end 119.61495 -48.40605)
		(width 0.1905)
		(layer "In9.Cu")
		(net "M_A_MA9")
	)
	(segment
		(start 160.02 -62.5856)
		(end 160.02 -65.024)
		(width 0.1905)
		(layer "In9.Cu")
		(net "M_A_MA9")
	)
	(segment
		(start 113.4491 -47.7901)
		(end 114.1222 -48.4632)
		(width 0.1016)
		(layer "In9.Cu")
		(net "M_A_MA9")
	)
	(segment
		(start 107.304586 -47.74946)
		(end 108.283502 -47.74946)
		(width 0.1016)
		(layer "In9.Cu")
		(net "M_A_MA9")
	)
	(segment
		(start 116.586 -48.4632)
		(end 119.5578 -48.4632)
		(width 0.1905)
		(layer "In9.Cu")
		(net "M_A_MA9")
	)
	(segment
		(start 114.1222 -48.4632)
		(end 116.586 -48.4632)
		(width 0.1016)
		(layer "In9.Cu")
		(net "M_A_MA9")
	)
	(segment
		(start 179.949856 -1.68402)
		(end 179.949856 -3.015234)
		(width 0.1778)
		(layer "F.Cu")
		(net "M_B_DQ52")
	)
	(segment
		(start 105.0036 -36.07816)
		(end 105.0036 -36.2458)
		(width 0.1016)
		(layer "F.Cu")
		(net "M_B_DQ52")
	)
	(segment
		(start 104.623108 -35.697414)
		(end 105.0036 -36.07816)
		(width 0.1016)
		(layer "F.Cu")
		(net "M_B_DQ52")
	)
	(segment
		(start 179.949856 -3.015234)
		(end 180.086 -3.151378)
		(width 0.1778)
		(layer "F.Cu")
		(net "M_B_DQ52")
	)
	(via
		(at 105.0036 -36.2458)
		(size 0.4318)
		(drill 0.2032)
		(layers "F.Cu" "B.Cu")
		(net "M_B_DQ52")
	)
	(via
		(at 180.086 -3.151378)
		(size 0.4318)
		(drill 0.2032)
		(layers "F.Cu" "B.Cu")
		(net "M_B_DQ52")
	)
	(segment
		(start 180.24983 -2.987548)
		(end 180.086 -3.151378)
		(width 0.1778)
		(layer "B.Cu")
		(net "M_B_DQ52")
	)
	(segment
		(start 180.24983 -1.690624)
		(end 180.24983 -2.987548)
		(width 0.1778)
		(layer "B.Cu")
		(net "M_B_DQ52")
	)
	(segment
		(start 123.358656 -32.8168)
		(end 123.358656 -32.512)
		(width 0.1524)
		(layer "In9.Cu")
		(net "M_B_DQ52")
	)
	(segment
		(start 138.6205 -31.1277)
		(end 152.1079 -31.1277)
		(width 0.1524)
		(layer "In9.Cu")
		(net "M_B_DQ52")
	)
	(segment
		(start 152.5778 -31.5976)
		(end 156.1338 -31.5976)
		(width 0.1524)
		(layer "In9.Cu")
		(net "M_B_DQ52")
	)
	(segment
		(start 136.779 -32.9692)
		(end 138.6205 -31.1277)
		(width 0.1524)
		(layer "In9.Cu")
		(net "M_B_DQ52")
	)
	(segment
		(start 110.9726 -33.4518)
		(end 119.4562 -33.4518)
		(width 0.1524)
		(layer "In9.Cu")
		(net "M_B_DQ52")
	)
	(segment
		(start 123.358656 -32.512)
		(end 123.511056 -32.3596)
		(width 0.1524)
		(layer "In9.Cu")
		(net "M_B_DQ52")
	)
	(segment
		(start 123.815856 -32.3596)
		(end 123.968256 -32.512)
		(width 0.1524)
		(layer "In9.Cu")
		(net "M_B_DQ52")
	)
	(segment
		(start 159.155384 -31.1912)
		(end 175.687228 -14.659356)
		(width 0.1524)
		(layer "In9.Cu")
		(net "M_B_DQ52")
	)
	(segment
		(start 104.2416 -34.2646)
		(end 104.2416 -35.4584)
		(width 0.1016)
		(layer "In9.Cu")
		(net "M_B_DQ52")
	)
	(segment
		(start 124.577856 -32.4866)
		(end 124.730256 -32.3342)
		(width 0.1524)
		(layer "In9.Cu")
		(net "M_B_DQ52")
	)
	(segment
		(start 156.1338 -31.5976)
		(end 156.5402 -31.1912)
		(width 0.1524)
		(layer "In9.Cu")
		(net "M_B_DQ52")
	)
	(segment
		(start 124.730256 -32.3342)
		(end 125.035056 -32.3342)
		(width 0.1524)
		(layer "In9.Cu")
		(net "M_B_DQ52")
	)
	(segment
		(start 104.2416 -35.4584)
		(end 105.0036 -36.2204)
		(width 0.1016)
		(layer "In9.Cu")
		(net "M_B_DQ52")
	)
	(segment
		(start 125.187456 -32.8168)
		(end 125.339856 -32.9692)
		(width 0.1524)
		(layer "In9.Cu")
		(net "M_B_DQ52")
	)
	(segment
		(start 180.0606 -3.176778)
		(end 180.086 -3.151378)
		(width 0.1524)
		(layer "In9.Cu")
		(net "M_B_DQ52")
	)
	(segment
		(start 124.577856 -32.8168)
		(end 124.577856 -32.4866)
		(width 0.1524)
		(layer "In9.Cu")
		(net "M_B_DQ52")
	)
	(segment
		(start 123.511056 -32.3596)
		(end 123.815856 -32.3596)
		(width 0.1524)
		(layer "In9.Cu")
		(net "M_B_DQ52")
	)
	(segment
		(start 110.9726 -33.4518)
		(end 110.6297 -33.1089)
		(width 0.1016)
		(layer "In9.Cu")
		(net "M_B_DQ52")
	)
	(segment
		(start 119.4562 -33.4518)
		(end 119.9388 -32.9692)
		(width 0.1524)
		(layer "In9.Cu")
		(net "M_B_DQ52")
	)
	(segment
		(start 124.425456 -32.9692)
		(end 124.577856 -32.8168)
		(width 0.1524)
		(layer "In9.Cu")
		(net "M_B_DQ52")
	)
	(segment
		(start 156.5402 -31.1912)
		(end 159.155384 -31.1912)
		(width 0.1524)
		(layer "In9.Cu")
		(net "M_B_DQ52")
	)
	(segment
		(start 180.0606 -4.0894)
		(end 180.0606 -3.176778)
		(width 0.1524)
		(layer "In9.Cu")
		(net "M_B_DQ52")
	)
	(segment
		(start 123.968256 -32.8168)
		(end 124.120656 -32.9692)
		(width 0.1524)
		(layer "In9.Cu")
		(net "M_B_DQ52")
	)
	(segment
		(start 105.0036 -36.2204)
		(end 105.0036 -36.2458)
		(width 0.1016)
		(layer "In9.Cu")
		(net "M_B_DQ52")
	)
	(segment
		(start 124.120656 -32.9692)
		(end 124.425456 -32.9692)
		(width 0.1524)
		(layer "In9.Cu")
		(net "M_B_DQ52")
	)
	(segment
		(start 152.1079 -31.1277)
		(end 152.5778 -31.5976)
		(width 0.1524)
		(layer "In9.Cu")
		(net "M_B_DQ52")
	)
	(segment
		(start 175.687228 -10.037572)
		(end 176.911 -8.8138)
		(width 0.1524)
		(layer "In9.Cu")
		(net "M_B_DQ52")
	)
	(segment
		(start 110.0709 -33.1089)
		(end 109.3978 -33.782)
		(width 0.1016)
		(layer "In9.Cu")
		(net "M_B_DQ52")
	)
	(segment
		(start 110.6297 -33.1089)
		(end 110.0709 -33.1089)
		(width 0.1016)
		(layer "In9.Cu")
		(net "M_B_DQ52")
	)
	(segment
		(start 176.911 -8.8138)
		(end 176.911 -7.239)
		(width 0.1524)
		(layer "In9.Cu")
		(net "M_B_DQ52")
	)
	(segment
		(start 125.187456 -32.4866)
		(end 125.187456 -32.8168)
		(width 0.1524)
		(layer "In9.Cu")
		(net "M_B_DQ52")
	)
	(segment
		(start 104.7242 -33.782)
		(end 104.2416 -34.2646)
		(width 0.1016)
		(layer "In9.Cu")
		(net "M_B_DQ52")
	)
	(segment
		(start 123.206256 -32.9692)
		(end 123.358656 -32.8168)
		(width 0.1524)
		(layer "In9.Cu")
		(net "M_B_DQ52")
	)
	(segment
		(start 176.911 -7.239)
		(end 180.0606 -4.0894)
		(width 0.1524)
		(layer "In9.Cu")
		(net "M_B_DQ52")
	)
	(segment
		(start 119.9388 -32.9692)
		(end 123.206256 -32.9692)
		(width 0.1524)
		(layer "In9.Cu")
		(net "M_B_DQ52")
	)
	(segment
		(start 123.968256 -32.512)
		(end 123.968256 -32.8168)
		(width 0.1524)
		(layer "In9.Cu")
		(net "M_B_DQ52")
	)
	(segment
		(start 175.687228 -14.659356)
		(end 175.687228 -10.037572)
		(width 0.1524)
		(layer "In9.Cu")
		(net "M_B_DQ52")
	)
	(segment
		(start 125.339856 -32.9692)
		(end 136.779 -32.9692)
		(width 0.1524)
		(layer "In9.Cu")
		(net "M_B_DQ52")
	)
	(segment
		(start 109.3978 -33.782)
		(end 104.7242 -33.782)
		(width 0.1016)
		(layer "In9.Cu")
		(net "M_B_DQ52")
	)
	(segment
		(start 125.035056 -32.3342)
		(end 125.187456 -32.4866)
		(width 0.1524)
		(layer "In9.Cu")
		(net "M_B_DQ52")
	)
	(segment
		(start 183.850026 -62.59322)
		(end 183.850026 -63.266066)
		(width 0.1778)
		(layer "F.Cu")
		(net "M_A_DQ8")
	)
	(segment
		(start 183.94553 -64.601344)
		(end 183.990996 -64.64681)
		(width 0.1778)
		(layer "F.Cu")
		(net "M_A_DQ8")
	)
	(segment
		(start 183.850026 -63.266066)
		(end 184.08396 -63.5)
		(width 0.1778)
		(layer "F.Cu")
		(net "M_A_DQ8")
	)
	(segment
		(start 184.08396 -63.5)
		(end 184.08396 -63.850012)
		(width 0.1778)
		(layer "F.Cu")
		(net "M_A_DQ8")
	)
	(segment
		(start 106.283506 -42.447972)
		(end 105.87863 -42.447972)
		(width 0.1016)
		(layer "F.Cu")
		(net "M_A_DQ8")
	)
	(segment
		(start 105.87863 -42.447972)
		(end 105.385108 -42.941494)
		(width 0.1016)
		(layer "F.Cu")
		(net "M_A_DQ8")
	)
	(segment
		(start 183.94553 -63.988442)
		(end 183.94553 -64.601344)
		(width 0.1778)
		(layer "F.Cu")
		(net "M_A_DQ8")
	)
	(segment
		(start 184.08396 -63.850012)
		(end 183.94553 -63.988442)
		(width 0.1778)
		(layer "F.Cu")
		(net "M_A_DQ8")
	)
	(via
		(at 106.283506 -42.447972)
		(size 0.4318)
		(drill 0.2032)
		(layers "F.Cu" "B.Cu")
		(net "M_A_DQ8")
	)
	(via
		(at 183.990996 -64.64681)
		(size 0.4318)
		(drill 0.2032)
		(layers "F.Cu" "B.Cu")
		(net "M_A_DQ8")
	)
	(segment
		(start 184.749948 -62.599824)
		(end 184.749948 -63.286132)
		(width 0.1778)
		(layer "B.Cu")
		(net "M_A_DQ8")
	)
	(segment
		(start 183.9595 -63.974472)
		(end 183.9595 -64.615314)
		(width 0.1778)
		(layer "B.Cu")
		(net "M_A_DQ8")
	)
	(segment
		(start 184.749948 -63.286132)
		(end 184.314338 -63.721742)
		(width 0.1778)
		(layer "B.Cu")
		(net "M_A_DQ8")
	)
	(segment
		(start 184.314338 -63.721742)
		(end 184.21223 -63.721742)
		(width 0.1778)
		(layer "B.Cu")
		(net "M_A_DQ8")
	)
	(segment
		(start 184.21223 -63.721742)
		(end 183.9595 -63.974472)
		(width 0.1778)
		(layer "B.Cu")
		(net "M_A_DQ8")
	)
	(segment
		(start 183.9595 -64.615314)
		(end 183.990996 -64.64681)
		(width 0.1778)
		(layer "B.Cu")
		(net "M_A_DQ8")
	)
	(segment
		(start 119.0244 -41.8084)
		(end 118.5164 -41.3004)
		(width 0.1524)
		(layer "In4.Cu")
		(net "M_A_DQ8")
	)
	(segment
		(start 110.828582 -41.977818)
		(end 110.176818 -41.977818)
		(width 0.1016)
		(layer "In4.Cu")
		(net "M_A_DQ8")
	)
	(segment
		(start 111.506 -41.3004)
		(end 110.8964 -41.91)
		(width 0.1524)
		(layer "In4.Cu")
		(net "M_A_DQ8")
	)
	(segment
		(start 183.990996 -64.64681)
		(end 183.990996 -64.560196)
		(width 0.1524)
		(layer "In4.Cu")
		(net "M_A_DQ8")
	)
	(segment
		(start 171.372784 -49.274984)
		(end 171.157392 -49.274984)
		(width 0.1524)
		(layer "In4.Cu")
		(net "M_A_DQ8")
	)
	(segment
		(start 172.926502 -52.03444)
		(end 172.926502 -51.819048)
		(width 0.1524)
		(layer "In4.Cu")
		(net "M_A_DQ8")
	)
	(segment
		(start 183.9468 -64.516)
		(end 183.9468 -61.198252)
		(width 0.1524)
		(layer "In4.Cu")
		(net "M_A_DQ8")
	)
	(segment
		(start 170.3451 -48.577754)
		(end 170.129708 -48.577754)
		(width 0.1524)
		(layer "In4.Cu")
		(net "M_A_DQ8")
	)
	(segment
		(start 170.33875 -49.231296)
		(end 170.561 -49.009046)
		(width 0.1524)
		(layer "In4.Cu")
		(net "M_A_DQ8")
	)
	(segment
		(start 110.8964 -41.91)
		(end 110.828582 -41.977818)
		(width 0.1016)
		(layer "In4.Cu")
		(net "M_A_DQ8")
	)
	(segment
		(start 172.336968 -50.68316)
		(end 172.336968 -50.467768)
		(width 0.1524)
		(layer "In4.Cu")
		(net "M_A_DQ8")
	)
	(segment
		(start 172.79366 -51.089052)
		(end 172.49521 -51.387756)
		(width 0.1524)
		(layer "In4.Cu")
		(net "M_A_DQ8")
	)
	(segment
		(start 156.747972 -42.453306)
		(end 156.32049 -42.336974)
		(width 0.1524)
		(layer "In4.Cu")
		(net "M_A_DQ8")
	)
	(segment
		(start 176.707038 -52.533042)
		(end 173.425104 -52.533042)
		(width 0.1524)
		(layer "In4.Cu")
		(net "M_A_DQ8")
	)
	(segment
		(start 168.835832 -47.283878)
		(end 168.835832 -47.068486)
		(width 0.1524)
		(layer "In4.Cu")
		(net "M_A_DQ8")
	)
	(segment
		(start 171.201334 -50.09388)
		(end 171.588684 -49.706276)
		(width 0.1524)
		(layer "In4.Cu")
		(net "M_A_DQ8")
	)
	(segment
		(start 169.368724 -47.613316)
		(end 169.044874 -47.93742)
		(width 0.1524)
		(layer "In4.Cu")
		(net "M_A_DQ8")
	)
	(segment
		(start 171.417234 -50.525172)
		(end 171.201334 -50.309272)
		(width 0.1524)
		(layer "In4.Cu")
		(net "M_A_DQ8")
	)
	(segment
		(start 106.283506 -42.430954)
		(end 106.283506 -42.447972)
		(width 0.1016)
		(layer "In4.Cu")
		(net "M_A_DQ8")
	)
	(segment
		(start 181.5338 -58.785252)
		(end 181.5338 -57.359804)
		(width 0.1524)
		(layer "In4.Cu")
		(net "M_A_DQ8")
	)
	(segment
		(start 173.224952 -51.520344)
		(end 173.224952 -51.304952)
		(width 0.1524)
		(layer "In4.Cu")
		(net "M_A_DQ8")
	)
	(segment
		(start 167.966898 -47.074836)
		(end 165.809676 -44.917614)
		(width 0.1524)
		(layer "In4.Cu")
		(net "M_A_DQ8")
	)
	(segment
		(start 172.063918 -50.956464)
		(end 172.336968 -50.68316)
		(width 0.1524)
		(layer "In4.Cu")
		(net "M_A_DQ8")
	)
	(segment
		(start 173.425104 -52.533042)
		(end 172.926502 -52.03444)
		(width 0.1524)
		(layer "In4.Cu")
		(net "M_A_DQ8")
	)
	(segment
		(start 106.60253 -42.11193)
		(end 106.283506 -42.430954)
		(width 0.1016)
		(layer "In4.Cu")
		(net "M_A_DQ8")
	)
	(segment
		(start 168.829482 -47.93742)
		(end 168.613582 -47.72152)
		(width 0.1524)
		(layer "In4.Cu")
		(net "M_A_DQ8")
	)
	(segment
		(start 170.561 -49.009046)
		(end 170.561 -48.793654)
		(width 0.1524)
		(layer "In4.Cu")
		(net "M_A_DQ8")
	)
	(segment
		(start 170.561 -48.793654)
		(end 170.3451 -48.577754)
		(width 0.1524)
		(layer "In4.Cu")
		(net "M_A_DQ8")
	)
	(segment
		(start 165.809676 -44.917614)
		(end 156.747972 -42.453306)
		(width 0.1524)
		(layer "In4.Cu")
		(net "M_A_DQ8")
	)
	(segment
		(start 169.476166 -48.368712)
		(end 169.80027 -48.044862)
		(width 0.1524)
		(layer "In4.Cu")
		(net "M_A_DQ8")
	)
	(segment
		(start 110.176818 -41.977818)
		(end 109.617002 -41.418002)
		(width 0.1016)
		(layer "In4.Cu")
		(net "M_A_DQ8")
	)
	(segment
		(start 170.770042 -49.662588)
		(end 170.55465 -49.662588)
		(width 0.1524)
		(layer "In4.Cu")
		(net "M_A_DQ8")
	)
	(segment
		(start 169.907458 -48.800004)
		(end 169.692066 -48.800004)
		(width 0.1524)
		(layer "In4.Cu")
		(net "M_A_DQ8")
	)
	(segment
		(start 168.613582 -47.72152)
		(end 168.613582 -47.506128)
		(width 0.1524)
		(layer "In4.Cu")
		(net "M_A_DQ8")
	)
	(segment
		(start 169.044874 -47.93742)
		(end 168.829482 -47.93742)
		(width 0.1524)
		(layer "In4.Cu")
		(net "M_A_DQ8")
	)
	(segment
		(start 171.201334 -50.309272)
		(end 171.201334 -50.09388)
		(width 0.1524)
		(layer "In4.Cu")
		(net "M_A_DQ8")
	)
	(segment
		(start 171.632626 -50.525172)
		(end 171.417234 -50.525172)
		(width 0.1524)
		(layer "In4.Cu")
		(net "M_A_DQ8")
	)
	(segment
		(start 171.588684 -49.490884)
		(end 171.372784 -49.274984)
		(width 0.1524)
		(layer "In4.Cu")
		(net "M_A_DQ8")
	)
	(segment
		(start 169.692066 -48.800004)
		(end 169.476166 -48.584104)
		(width 0.1524)
		(layer "In4.Cu")
		(net "M_A_DQ8")
	)
	(segment
		(start 109.617002 -41.418002)
		(end 107.63123 -41.418002)
		(width 0.1016)
		(layer "In4.Cu")
		(net "M_A_DQ8")
	)
	(segment
		(start 172.063918 -51.171856)
		(end 172.063918 -50.956464)
		(width 0.1524)
		(layer "In4.Cu")
		(net "M_A_DQ8")
	)
	(segment
		(start 107.037632 -42.0116)
		(end 106.844846 -42.0116)
		(width 0.1016)
		(layer "In4.Cu")
		(net "M_A_DQ8")
	)
	(segment
		(start 183.9468 -61.198252)
		(end 181.5338 -58.785252)
		(width 0.1524)
		(layer "In4.Cu")
		(net "M_A_DQ8")
	)
	(segment
		(start 171.157392 -49.274984)
		(end 170.770042 -49.662588)
		(width 0.1524)
		(layer "In4.Cu")
		(net "M_A_DQ8")
	)
	(segment
		(start 181.5338 -57.359804)
		(end 176.707038 -52.533042)
		(width 0.1524)
		(layer "In4.Cu")
		(net "M_A_DQ8")
	)
	(segment
		(start 169.584116 -47.613316)
		(end 169.368724 -47.613316)
		(width 0.1524)
		(layer "In4.Cu")
		(net "M_A_DQ8")
	)
	(segment
		(start 118.5164 -41.3004)
		(end 111.506 -41.3004)
		(width 0.1524)
		(layer "In4.Cu")
		(net "M_A_DQ8")
	)
	(segment
		(start 170.33875 -49.446688)
		(end 170.33875 -49.231296)
		(width 0.1524)
		(layer "In4.Cu")
		(net "M_A_DQ8")
	)
	(segment
		(start 168.835832 -47.068486)
		(end 168.619932 -46.852586)
		(width 0.1524)
		(layer "In4.Cu")
		(net "M_A_DQ8")
	)
	(segment
		(start 156.32049 -42.336974)
		(end 154.23261 -41.8084)
		(width 0.1524)
		(layer "In4.Cu")
		(net "M_A_DQ8")
	)
	(segment
		(start 172.926502 -51.819048)
		(end 173.224952 -51.520344)
		(width 0.1524)
		(layer "In4.Cu")
		(net "M_A_DQ8")
	)
	(segment
		(start 168.40454 -46.852586)
		(end 168.18229 -47.074836)
		(width 0.1524)
		(layer "In4.Cu")
		(net "M_A_DQ8")
	)
	(segment
		(start 168.18229 -47.074836)
		(end 167.966898 -47.074836)
		(width 0.1524)
		(layer "In4.Cu")
		(net "M_A_DQ8")
	)
	(segment
		(start 107.63123 -41.418002)
		(end 107.037632 -42.0116)
		(width 0.1016)
		(layer "In4.Cu")
		(net "M_A_DQ8")
	)
	(segment
		(start 171.588684 -49.706276)
		(end 171.588684 -49.490884)
		(width 0.1524)
		(layer "In4.Cu")
		(net "M_A_DQ8")
	)
	(segment
		(start 170.55465 -49.662588)
		(end 170.33875 -49.446688)
		(width 0.1524)
		(layer "In4.Cu")
		(net "M_A_DQ8")
	)
	(segment
		(start 168.613582 -47.506128)
		(end 168.835832 -47.283878)
		(width 0.1524)
		(layer "In4.Cu")
		(net "M_A_DQ8")
	)
	(segment
		(start 173.009052 -51.089052)
		(end 172.79366 -51.089052)
		(width 0.1524)
		(layer "In4.Cu")
		(net "M_A_DQ8")
	)
	(segment
		(start 172.121068 -50.251868)
		(end 171.905676 -50.251868)
		(width 0.1524)
		(layer "In4.Cu")
		(net "M_A_DQ8")
	)
	(segment
		(start 173.224952 -51.304952)
		(end 173.009052 -51.089052)
		(width 0.1524)
		(layer "In4.Cu")
		(net "M_A_DQ8")
	)
	(segment
		(start 183.990996 -64.560196)
		(end 183.9468 -64.516)
		(width 0.1524)
		(layer "In4.Cu")
		(net "M_A_DQ8")
	)
	(segment
		(start 172.336968 -50.467768)
		(end 172.121068 -50.251868)
		(width 0.1524)
		(layer "In4.Cu")
		(net "M_A_DQ8")
	)
	(segment
		(start 168.619932 -46.852586)
		(end 168.40454 -46.852586)
		(width 0.1524)
		(layer "In4.Cu")
		(net "M_A_DQ8")
	)
	(segment
		(start 169.80027 -47.82947)
		(end 169.584116 -47.613316)
		(width 0.1524)
		(layer "In4.Cu")
		(net "M_A_DQ8")
	)
	(segment
		(start 172.279818 -51.387756)
		(end 172.063918 -51.171856)
		(width 0.1524)
		(layer "In4.Cu")
		(net "M_A_DQ8")
	)
	(segment
		(start 172.49521 -51.387756)
		(end 172.279818 -51.387756)
		(width 0.1524)
		(layer "In4.Cu")
		(net "M_A_DQ8")
	)
	(segment
		(start 169.80027 -48.044862)
		(end 169.80027 -47.82947)
		(width 0.1524)
		(layer "In4.Cu")
		(net "M_A_DQ8")
	)
	(segment
		(start 169.476166 -48.584104)
		(end 169.476166 -48.368712)
		(width 0.1524)
		(layer "In4.Cu")
		(net "M_A_DQ8")
	)
	(segment
		(start 170.129708 -48.577754)
		(end 169.907458 -48.800004)
		(width 0.1524)
		(layer "In4.Cu")
		(net "M_A_DQ8")
	)
	(segment
		(start 154.23261 -41.8084)
		(end 119.0244 -41.8084)
		(width 0.1524)
		(layer "In4.Cu")
		(net "M_A_DQ8")
	)
	(segment
		(start 171.905676 -50.251868)
		(end 171.632626 -50.525172)
		(width 0.1524)
		(layer "In4.Cu")
		(net "M_A_DQ8")
	)
	(arc
		(start 106.844846 -42.0116)
		(mid 106.713721 -42.037682)
		(end 106.60253 -42.11193)
		(width 0.1016)
		(layer "In4.Cu")
		(net "M_A_DQ8")
	)
	(segment
		(start 107.061 -36.1696)
		(end 107.0864 -36.195)
		(width 0.1016)
		(layer "F.Cu")
		(net "M_B_DQ60")
	)
	(segment
		(start 184.91454 -3.219958)
		(end 184.91454 -3.265678)
		(width 0.1778)
		(layer "F.Cu")
		(net "M_B_DQ60")
	)
	(segment
		(start 107.0864 -36.778946)
		(end 107.290108 -36.982654)
		(width 0.1016)
		(layer "F.Cu")
		(net "M_B_DQ60")
	)
	(segment
		(start 185.349896 -2.472182)
		(end 184.91962 -2.902458)
		(width 0.1778)
		(layer "F.Cu")
		(net "M_B_DQ60")
	)
	(segment
		(start 184.91962 -2.902458)
		(end 184.91962 -3.214878)
		(width 0.1778)
		(layer "F.Cu")
		(net "M_B_DQ60")
	)
	(segment
		(start 185.349896 -1.68402)
		(end 185.349896 -2.472182)
		(width 0.1778)
		(layer "F.Cu")
		(net "M_B_DQ60")
	)
	(segment
		(start 184.91962 -3.214878)
		(end 184.91454 -3.219958)
		(width 0.1778)
		(layer "F.Cu")
		(net "M_B_DQ60")
	)
	(segment
		(start 107.0864 -36.195)
		(end 107.0864 -36.778946)
		(width 0.1016)
		(layer "F.Cu")
		(net "M_B_DQ60")
	)
	(via
		(at 107.061 -36.1696)
		(size 0.4318)
		(drill 0.2032)
		(layers "F.Cu" "B.Cu")
		(net "M_B_DQ60")
	)
	(via
		(at 184.91454 -3.265678)
		(size 0.4318)
		(drill 0.2032)
		(layers "F.Cu" "B.Cu")
		(net "M_B_DQ60")
	)
	(segment
		(start 184.91454 -3.195828)
		(end 184.91454 -3.265678)
		(width 0.1778)
		(layer "B.Cu")
		(net "M_B_DQ60")
	)
	(segment
		(start 184.449974 -1.690624)
		(end 184.449974 -2.731262)
		(width 0.1778)
		(layer "B.Cu")
		(net "M_B_DQ60")
	)
	(segment
		(start 184.449974 -2.731262)
		(end 184.91454 -3.195828)
		(width 0.1778)
		(layer "B.Cu")
		(net "M_B_DQ60")
	)
	(segment
		(start 180.467 -5.361178)
		(end 181.64048 -4.187698)
		(width 0.1524)
		(layer "In2.Cu")
		(net "M_B_DQ60")
	)
	(segment
		(start 146.0246 -32.131)
		(end 146.0246 -32.555434)
		(width 0.1524)
		(layer "In2.Cu")
		(net "M_B_DQ60")
	)
	(segment
		(start 145.8722 -31.9786)
		(end 146.0246 -32.131)
		(width 0.1524)
		(layer "In2.Cu")
		(net "M_B_DQ60")
	)
	(segment
		(start 148.8948 -32.707834)
		(end 157.505146 -32.707834)
		(width 0.1524)
		(layer "In2.Cu")
		(net "M_B_DQ60")
	)
	(segment
		(start 148.7424 -32.555434)
		(end 148.8948 -32.707834)
		(width 0.1524)
		(layer "In2.Cu")
		(net "M_B_DQ60")
	)
	(segment
		(start 181.64048 -4.187698)
		(end 183.9976 -4.187698)
		(width 0.1524)
		(layer "In2.Cu")
		(net "M_B_DQ60")
	)
	(segment
		(start 108.801408 -34.403792)
		(end 107.1372 -36.068)
		(width 0.1016)
		(layer "In2.Cu")
		(net "M_B_DQ60")
	)
	(segment
		(start 163.647628 -26.17851)
		(end 165.2778 -24.548338)
		(width 0.1524)
		(layer "In2.Cu")
		(net "M_B_DQ60")
	)
	(segment
		(start 180.467 -6.453378)
		(end 180.467 -5.361178)
		(width 0.1524)
		(layer "In2.Cu")
		(net "M_B_DQ60")
	)
	(segment
		(start 131.934712 -32.707834)
		(end 139.9286 -32.707834)
		(width 0.1524)
		(layer "In2.Cu")
		(net "M_B_DQ60")
	)
	(segment
		(start 147.3708 -31.9786)
		(end 147.5232 -32.131)
		(width 0.1524)
		(layer "In2.Cu")
		(net "M_B_DQ60")
	)
	(segment
		(start 148.59 -32.0294)
		(end 148.7424 -32.1818)
		(width 0.1524)
		(layer "In2.Cu")
		(net "M_B_DQ60")
	)
	(segment
		(start 110.9472 -34.4678)
		(end 118.3132 -34.4678)
		(width 0.1524)
		(layer "In2.Cu")
		(net "M_B_DQ60")
	)
	(segment
		(start 107.1372 -36.068)
		(end 107.1372 -36.0934)
		(width 0.1016)
		(layer "In2.Cu")
		(net "M_B_DQ60")
	)
	(segment
		(start 140.250418 -31.9786)
		(end 145.8722 -31.9786)
		(width 0.1524)
		(layer "In2.Cu")
		(net "M_B_DQ60")
	)
	(segment
		(start 147.066 -31.9786)
		(end 147.3708 -31.9786)
		(width 0.1524)
		(layer "In2.Cu")
		(net "M_B_DQ60")
	)
	(segment
		(start 148.1328 -32.1818)
		(end 148.2852 -32.0294)
		(width 0.1524)
		(layer "In2.Cu")
		(net "M_B_DQ60")
	)
	(segment
		(start 147.5232 -32.555434)
		(end 147.6756 -32.707834)
		(width 0.1524)
		(layer "In2.Cu")
		(net "M_B_DQ60")
	)
	(segment
		(start 162.884358 -26.17851)
		(end 163.647628 -26.17851)
		(width 0.1524)
		(layer "In2.Cu")
		(net "M_B_DQ60")
	)
	(segment
		(start 162.60191 -26.460958)
		(end 162.884358 -26.17851)
		(width 0.1524)
		(layer "In2.Cu")
		(net "M_B_DQ60")
	)
	(segment
		(start 110.9472 -34.4678)
		(end 110.883192 -34.403792)
		(width 0.1016)
		(layer "In2.Cu")
		(net "M_B_DQ60")
	)
	(segment
		(start 147.5232 -32.131)
		(end 147.5232 -32.555434)
		(width 0.1524)
		(layer "In2.Cu")
		(net "M_B_DQ60")
	)
	(segment
		(start 180.1114 -10.10158)
		(end 180.1114 -8.367014)
		(width 0.1524)
		(layer "In2.Cu")
		(net "M_B_DQ60")
	)
	(segment
		(start 157.505146 -32.707834)
		(end 162.60191 -27.61107)
		(width 0.1524)
		(layer "In2.Cu")
		(net "M_B_DQ60")
	)
	(segment
		(start 146.9136 -32.131)
		(end 147.066 -31.9786)
		(width 0.1524)
		(layer "In2.Cu")
		(net "M_B_DQ60")
	)
	(segment
		(start 139.9286 -32.707834)
		(end 140.081 -32.555434)
		(width 0.1524)
		(layer "In2.Cu")
		(net "M_B_DQ60")
	)
	(segment
		(start 118.658386 -34.122614)
		(end 130.52044 -34.122614)
		(width 0.1524)
		(layer "In2.Cu")
		(net "M_B_DQ60")
	)
	(segment
		(start 148.1328 -32.555434)
		(end 148.1328 -32.1818)
		(width 0.1524)
		(layer "In2.Cu")
		(net "M_B_DQ60")
	)
	(segment
		(start 146.7612 -32.707834)
		(end 146.9136 -32.555434)
		(width 0.1524)
		(layer "In2.Cu")
		(net "M_B_DQ60")
	)
	(segment
		(start 140.081 -32.148018)
		(end 140.250418 -31.9786)
		(width 0.1524)
		(layer "In2.Cu")
		(net "M_B_DQ60")
	)
	(segment
		(start 140.081 -32.555434)
		(end 140.081 -32.148018)
		(width 0.1524)
		(layer "In2.Cu")
		(net "M_B_DQ60")
	)
	(segment
		(start 146.0246 -32.555434)
		(end 146.177 -32.707834)
		(width 0.1524)
		(layer "In2.Cu")
		(net "M_B_DQ60")
	)
	(segment
		(start 148.2852 -32.0294)
		(end 148.59 -32.0294)
		(width 0.1524)
		(layer "In2.Cu")
		(net "M_B_DQ60")
	)
	(segment
		(start 146.177 -32.707834)
		(end 146.7612 -32.707834)
		(width 0.1524)
		(layer "In2.Cu")
		(net "M_B_DQ60")
	)
	(segment
		(start 184.88152 -3.298698)
		(end 184.91454 -3.265678)
		(width 0.1524)
		(layer "In2.Cu")
		(net "M_B_DQ60")
	)
	(segment
		(start 183.9976 -4.187698)
		(end 184.88152 -3.303778)
		(width 0.1524)
		(layer "In2.Cu")
		(net "M_B_DQ60")
	)
	(segment
		(start 147.6756 -32.707834)
		(end 147.9804 -32.707834)
		(width 0.1524)
		(layer "In2.Cu")
		(net "M_B_DQ60")
	)
	(segment
		(start 165.619938 -23.0378)
		(end 167.17518 -23.0378)
		(width 0.1524)
		(layer "In2.Cu")
		(net "M_B_DQ60")
	)
	(segment
		(start 147.9804 -32.707834)
		(end 148.1328 -32.555434)
		(width 0.1524)
		(layer "In2.Cu")
		(net "M_B_DQ60")
	)
	(segment
		(start 130.52044 -34.122614)
		(end 131.934712 -32.707834)
		(width 0.1524)
		(layer "In2.Cu")
		(net "M_B_DQ60")
	)
	(segment
		(start 146.9136 -32.555434)
		(end 146.9136 -32.131)
		(width 0.1524)
		(layer "In2.Cu")
		(net "M_B_DQ60")
	)
	(segment
		(start 167.17518 -23.0378)
		(end 180.1114 -10.10158)
		(width 0.1524)
		(layer "In2.Cu")
		(net "M_B_DQ60")
	)
	(segment
		(start 165.2778 -23.379938)
		(end 165.619938 -23.0378)
		(width 0.1524)
		(layer "In2.Cu")
		(net "M_B_DQ60")
	)
	(segment
		(start 148.7424 -32.1818)
		(end 148.7424 -32.555434)
		(width 0.1524)
		(layer "In2.Cu")
		(net "M_B_DQ60")
	)
	(segment
		(start 118.3132 -34.4678)
		(end 118.658386 -34.122614)
		(width 0.1524)
		(layer "In2.Cu")
		(net "M_B_DQ60")
	)
	(segment
		(start 179.628292 -7.883906)
		(end 179.628292 -7.291578)
		(width 0.1524)
		(layer "In2.Cu")
		(net "M_B_DQ60")
	)
	(segment
		(start 162.60191 -27.61107)
		(end 162.60191 -26.460958)
		(width 0.1524)
		(layer "In2.Cu")
		(net "M_B_DQ60")
	)
	(segment
		(start 180.466492 -6.453378)
		(end 180.467 -6.453378)
		(width 0.1524)
		(layer "In2.Cu")
		(net "M_B_DQ60")
	)
	(segment
		(start 180.1114 -8.367014)
		(end 179.628292 -7.883906)
		(width 0.1524)
		(layer "In2.Cu")
		(net "M_B_DQ60")
	)
	(segment
		(start 184.88152 -3.303778)
		(end 184.88152 -3.298698)
		(width 0.1524)
		(layer "In2.Cu")
		(net "M_B_DQ60")
	)
	(segment
		(start 107.1372 -36.0934)
		(end 107.061 -36.1696)
		(width 0.1016)
		(layer "In2.Cu")
		(net "M_B_DQ60")
	)
	(segment
		(start 165.2778 -24.548338)
		(end 165.2778 -23.379938)
		(width 0.1524)
		(layer "In2.Cu")
		(net "M_B_DQ60")
	)
	(segment
		(start 179.628292 -7.291578)
		(end 180.466492 -6.453378)
		(width 0.1524)
		(layer "In2.Cu")
		(net "M_B_DQ60")
	)
	(segment
		(start 110.883192 -34.403792)
		(end 108.801408 -34.403792)
		(width 0.1016)
		(layer "In2.Cu")
		(net "M_B_DQ60")
	)
	(segment
		(start 110.645956 -34.132774)
		(end 110.645448 -34.132774)
		(width 0.1016)
		(layer "F.Cu")
		(net "M_B_DQ40")
	)
	(segment
		(start 111.968534 -34.163508)
		(end 111.747808 -34.384234)
		(width 0.1016)
		(layer "F.Cu")
		(net "M_B_DQ40")
	)
	(segment
		(start 175.2854 -8.561578)
		(end 175.2854 -7.838186)
		(width 0.1778)
		(layer "F.Cu")
		(net "M_B_DQ40")
	)
	(segment
		(start 110.897416 -34.384234)
		(end 110.645956 -34.132774)
		(width 0.1016)
		(layer "F.Cu")
		(net "M_B_DQ40")
	)
	(segment
		(start 174.850044 -8.996934)
		(end 175.2854 -8.561578)
		(width 0.1778)
		(layer "F.Cu")
		(net "M_B_DQ40")
	)
	(segment
		(start 111.747808 -34.384234)
		(end 110.897416 -34.384234)
		(width 0.1016)
		(layer "F.Cu")
		(net "M_B_DQ40")
	)
	(segment
		(start 174.850044 -9.897364)
		(end 174.850044 -8.996934)
		(width 0.1778)
		(layer "F.Cu")
		(net "M_B_DQ40")
	)
	(segment
		(start 115.062 -31.3182)
		(end 115.062 -31.496)
		(width 0.1016)
		(layer "F.Cu")
		(net "M_B_DQ40")
	)
	(segment
		(start 112.394492 -34.163508)
		(end 111.968534 -34.163508)
		(width 0.1016)
		(layer "F.Cu")
		(net "M_B_DQ40")
	)
	(segment
		(start 175.2854 -7.838186)
		(end 175.164496 -7.717282)
		(width 0.1778)
		(layer "F.Cu")
		(net "M_B_DQ40")
	)
	(segment
		(start 115.062 -31.496)
		(end 112.394492 -34.163508)
		(width 0.1016)
		(layer "F.Cu")
		(net "M_B_DQ40")
	)
	(via
		(at 175.164496 -7.717282)
		(size 0.4318)
		(drill 0.2032)
		(layers "F.Cu" "B.Cu")
		(net "M_B_DQ40")
	)
	(via
		(at 115.062 -31.3182)
		(size 0.4318)
		(drill 0.2032)
		(layers "F.Cu" "B.Cu")
		(net "M_B_DQ40")
	)
	(segment
		(start 175.2854 -7.838186)
		(end 175.164496 -7.717282)
		(width 0.1778)
		(layer "B.Cu")
		(net "M_B_DQ40")
	)
	(segment
		(start 175.2854 -8.739378)
		(end 175.2854 -7.838186)
		(width 0.1778)
		(layer "B.Cu")
		(net "M_B_DQ40")
	)
	(segment
		(start 175.749966 -9.89076)
		(end 175.749966 -9.203944)
		(width 0.1778)
		(layer "B.Cu")
		(net "M_B_DQ40")
	)
	(segment
		(start 175.749966 -9.203944)
		(end 175.2854 -8.739378)
		(width 0.1778)
		(layer "B.Cu")
		(net "M_B_DQ40")
	)
	(segment
		(start 164.857938 -16.2306)
		(end 164.33038 -16.757904)
		(width 0.1524)
		(layer "In2.Cu")
		(net "M_B_DQ40")
	)
	(segment
		(start 163.683696 -17.188942)
		(end 163.683696 -17.404334)
		(width 0.1524)
		(layer "In2.Cu")
		(net "M_B_DQ40")
	)
	(segment
		(start 117.4242 -30.3784)
		(end 117.1956 -30.607)
		(width 0.1016)
		(layer "In2.Cu")
		(net "M_B_DQ40")
	)
	(segment
		(start 167.444166 -16.2306)
		(end 164.857938 -16.2306)
		(width 0.1524)
		(layer "In2.Cu")
		(net "M_B_DQ40")
	)
	(segment
		(start 157.650942 -22.09292)
		(end 157.650942 -22.308312)
		(width 0.1524)
		(layer "In2.Cu")
		(net "M_B_DQ40")
	)
	(segment
		(start 174.880016 -7.717282)
		(end 173.8122 -8.785098)
		(width 0.1524)
		(layer "In2.Cu")
		(net "M_B_DQ40")
	)
	(segment
		(start 156.788358 -23.170896)
		(end 157.239208 -23.622)
		(width 0.1524)
		(layer "In2.Cu")
		(net "M_B_DQ40")
	)
	(segment
		(start 157.004258 -22.739604)
		(end 156.788358 -22.955504)
		(width 0.1524)
		(layer "In2.Cu")
		(net "M_B_DQ40")
	)
	(segment
		(start 158.089092 -22.962108)
		(end 157.872938 -23.178008)
		(width 0.1524)
		(layer "In2.Cu")
		(net "M_B_DQ40")
	)
	(segment
		(start 123.344432 -29.449014)
		(end 118.353586 -29.449014)
		(width 0.1524)
		(layer "In2.Cu")
		(net "M_B_DQ40")
	)
	(segment
		(start 157.239208 -23.622)
		(end 157.239208 -23.837392)
		(width 0.1524)
		(layer "In2.Cu")
		(net "M_B_DQ40")
	)
	(segment
		(start 156.357066 -23.602188)
		(end 156.141674 -23.602188)
		(width 0.1524)
		(layer "In2.Cu")
		(net "M_B_DQ40")
	)
	(segment
		(start 157.657546 -23.178008)
		(end 157.21965 -22.739604)
		(width 0.1524)
		(layer "In2.Cu")
		(net "M_B_DQ40")
	)
	(segment
		(start 159.149796 -21.686012)
		(end 159.149796 -21.901404)
		(width 0.1524)
		(layer "In2.Cu")
		(net "M_B_DQ40")
	)
	(segment
		(start 163.461446 -16.319754)
		(end 163.2458 -16.5354)
		(width 0.1524)
		(layer "In2.Cu")
		(net "M_B_DQ40")
	)
	(segment
		(start 158.280354 -21.6789)
		(end 158.064962 -21.6789)
		(width 0.1524)
		(layer "In2.Cu")
		(net "M_B_DQ40")
	)
	(segment
		(start 153.507948 -26.235914)
		(end 153.507948 -26.959052)
		(width 0.1524)
		(layer "In2.Cu")
		(net "M_B_DQ40")
	)
	(segment
		(start 158.064962 -21.6789)
		(end 157.650942 -22.09292)
		(width 0.1524)
		(layer "In2.Cu")
		(net "M_B_DQ40")
	)
	(segment
		(start 164.33038 -16.757904)
		(end 164.114988 -16.757904)
		(width 0.1524)
		(layer "In2.Cu")
		(net "M_B_DQ40")
	)
	(segment
		(start 163.683696 -17.404334)
		(end 163.132262 -17.956022)
		(width 0.1524)
		(layer "In2.Cu")
		(net "M_B_DQ40")
	)
	(segment
		(start 117.1956 -30.607)
		(end 115.5446 -30.607)
		(width 0.1016)
		(layer "In2.Cu")
		(net "M_B_DQ40")
	)
	(segment
		(start 156.141674 -23.602188)
		(end 153.507948 -26.235914)
		(width 0.1524)
		(layer "In2.Cu")
		(net "M_B_DQ40")
	)
	(segment
		(start 115.062 -31.0896)
		(end 115.062 -31.3182)
		(width 0.1016)
		(layer "In2.Cu")
		(net "M_B_DQ40")
	)
	(segment
		(start 175.164496 -7.717282)
		(end 174.880016 -7.717282)
		(width 0.1524)
		(layer "In2.Cu")
		(net "M_B_DQ40")
	)
	(segment
		(start 158.711646 -21.032216)
		(end 158.711646 -21.247608)
		(width 0.1524)
		(layer "In2.Cu")
		(net "M_B_DQ40")
	)
	(segment
		(start 153.507948 -26.959052)
		(end 153.27122 -27.19578)
		(width 0.1524)
		(layer "In2.Cu")
		(net "M_B_DQ40")
	)
	(segment
		(start 156.788358 -22.955504)
		(end 156.788358 -23.170896)
		(width 0.1524)
		(layer "In2.Cu")
		(net "M_B_DQ40")
	)
	(segment
		(start 158.711646 -21.247608)
		(end 159.149796 -21.686012)
		(width 0.1524)
		(layer "In2.Cu")
		(net "M_B_DQ40")
	)
	(segment
		(start 163.676838 -16.319754)
		(end 163.461446 -16.319754)
		(width 0.1524)
		(layer "In2.Cu")
		(net "M_B_DQ40")
	)
	(segment
		(start 125.597666 -27.19578)
		(end 123.344432 -29.449014)
		(width 0.1524)
		(layer "In2.Cu")
		(net "M_B_DQ40")
	)
	(segment
		(start 173.8122 -9.271)
		(end 173.536356 -9.546844)
		(width 0.1524)
		(layer "In2.Cu")
		(net "M_B_DQ40")
	)
	(segment
		(start 157.023308 -24.053292)
		(end 156.807916 -24.053292)
		(width 0.1524)
		(layer "In2.Cu")
		(net "M_B_DQ40")
	)
	(segment
		(start 115.5446 -30.607)
		(end 115.062 -31.0896)
		(width 0.1016)
		(layer "In2.Cu")
		(net "M_B_DQ40")
	)
	(segment
		(start 164.114988 -16.757904)
		(end 163.676838 -16.319754)
		(width 0.1524)
		(layer "In2.Cu")
		(net "M_B_DQ40")
	)
	(segment
		(start 156.807916 -24.053292)
		(end 156.357066 -23.602188)
		(width 0.1524)
		(layer "In2.Cu")
		(net "M_B_DQ40")
	)
	(segment
		(start 163.132262 -17.956022)
		(end 161.737802 -19.350482)
		(width 0.1524)
		(layer "In2.Cu")
		(net "M_B_DQ40")
	)
	(segment
		(start 173.536356 -10.13841)
		(end 167.444166 -16.2306)
		(width 0.1524)
		(layer "In2.Cu")
		(net "M_B_DQ40")
	)
	(segment
		(start 157.650942 -22.308312)
		(end 158.089092 -22.746716)
		(width 0.1524)
		(layer "In2.Cu")
		(net "M_B_DQ40")
	)
	(segment
		(start 158.089092 -22.746716)
		(end 158.089092 -22.962108)
		(width 0.1524)
		(layer "In2.Cu")
		(net "M_B_DQ40")
	)
	(segment
		(start 157.239208 -23.837392)
		(end 157.023308 -24.053292)
		(width 0.1524)
		(layer "In2.Cu")
		(net "M_B_DQ40")
	)
	(segment
		(start 158.718504 -22.117304)
		(end 158.280354 -21.6789)
		(width 0.1524)
		(layer "In2.Cu")
		(net "M_B_DQ40")
	)
	(segment
		(start 163.2458 -16.750792)
		(end 163.683696 -17.188942)
		(width 0.1524)
		(layer "In2.Cu")
		(net "M_B_DQ40")
	)
	(segment
		(start 173.536356 -9.546844)
		(end 173.536356 -10.13841)
		(width 0.1524)
		(layer "In2.Cu")
		(net "M_B_DQ40")
	)
	(segment
		(start 159.149796 -21.901404)
		(end 158.933896 -22.117304)
		(width 0.1524)
		(layer "In2.Cu")
		(net "M_B_DQ40")
	)
	(segment
		(start 160.39338 -19.350482)
		(end 158.711646 -21.032216)
		(width 0.1524)
		(layer "In2.Cu")
		(net "M_B_DQ40")
	)
	(segment
		(start 173.8122 -8.785098)
		(end 173.8122 -9.271)
		(width 0.1524)
		(layer "In2.Cu")
		(net "M_B_DQ40")
	)
	(segment
		(start 153.27122 -27.19578)
		(end 125.597666 -27.19578)
		(width 0.1524)
		(layer "In2.Cu")
		(net "M_B_DQ40")
	)
	(segment
		(start 157.21965 -22.739604)
		(end 157.004258 -22.739604)
		(width 0.1524)
		(layer "In2.Cu")
		(net "M_B_DQ40")
	)
	(segment
		(start 118.353586 -29.449014)
		(end 117.4242 -30.3784)
		(width 0.1524)
		(layer "In2.Cu")
		(net "M_B_DQ40")
	)
	(segment
		(start 158.933896 -22.117304)
		(end 158.718504 -22.117304)
		(width 0.1524)
		(layer "In2.Cu")
		(net "M_B_DQ40")
	)
	(segment
		(start 163.2458 -16.5354)
		(end 163.2458 -16.750792)
		(width 0.1524)
		(layer "In2.Cu")
		(net "M_B_DQ40")
	)
	(segment
		(start 157.872938 -23.178008)
		(end 157.657546 -23.178008)
		(width 0.1524)
		(layer "In2.Cu")
		(net "M_B_DQ40")
	)
	(segment
		(start 161.737802 -19.350482)
		(end 160.39338 -19.350482)
		(width 0.1524)
		(layer "In2.Cu")
		(net "M_B_DQ40")
	)
	(segment
		(start 14.454124 -34.948876)
		(end 14.6304 -34.7726)
		(width 0.254)
		(layer "F.Cu")
		(net "P3V3_STBY_PG")
	)
	(segment
		(start 13.371322 -34.948876)
		(end 14.454124 -34.948876)
		(width 0.254)
		(layer "F.Cu")
		(net "P3V3_STBY_PG")
	)
	(via
		(at 71.1454 -22.6314)
		(size 0.508)
		(drill 0.254)
		(layers "F.Cu" "B.Cu")
		(net "P3V3_STBY_PG")
	)
	(via
		(at 5.6642 -32.4358)
		(size 0.7112)
		(drill 0.3556)
		(layers "F.Cu" "B.Cu")
		(net "P3V3_STBY_PG")
	)
	(via
		(at 14.6304 -34.7726)
		(size 0.508)
		(drill 0.254)
		(layers "F.Cu" "B.Cu")
		(net "P3V3_STBY_PG")
	)
	(segment
		(start 9.398 -30.988)
		(end 8.6868 -31.6992)
		(width 0.254)
		(layer "B.Cu")
		(net "P3V3_STBY_PG")
	)
	(segment
		(start 6.4008 -31.6992)
		(end 6.604 -31.6992)
		(width 0.254)
		(layer "B.Cu")
		(net "P3V3_STBY_PG")
	)
	(segment
		(start 71.9074 -23.241)
		(end 71.2978 -22.6314)
		(width 0.254)
		(layer "B.Cu")
		(net "P3V3_STBY_PG")
	)
	(segment
		(start 13.9446 -34.7726)
		(end 11.049 -31.877)
		(width 0.254)
		(layer "B.Cu")
		(net "P3V3_STBY_PG")
	)
	(segment
		(start 8.6868 -31.6992)
		(end 6.604 -31.6992)
		(width 0.254)
		(layer "B.Cu")
		(net "P3V3_STBY_PG")
	)
	(segment
		(start 11.049 -31.242)
		(end 10.795 -30.988)
		(width 0.254)
		(layer "B.Cu")
		(net "P3V3_STBY_PG")
	)
	(segment
		(start 5.6642 -33.401)
		(end 5.6642 -32.4358)
		(width 0.254)
		(layer "B.Cu")
		(net "P3V3_STBY_PG")
	)
	(segment
		(start 15.0368 -34.3662)
		(end 14.6304 -34.7726)
		(width 0.254)
		(layer "B.Cu")
		(net "P3V3_STBY_PG")
	)
	(segment
		(start 71.2978 -22.6314)
		(end 71.1454 -22.6314)
		(width 0.254)
		(layer "B.Cu")
		(net "P3V3_STBY_PG")
	)
	(segment
		(start 5.6642 -32.4358)
		(end 6.4008 -31.6992)
		(width 0.254)
		(layer "B.Cu")
		(net "P3V3_STBY_PG")
	)
	(segment
		(start 10.795 -30.988)
		(end 9.398 -30.988)
		(width 0.254)
		(layer "B.Cu")
		(net "P3V3_STBY_PG")
	)
	(segment
		(start 11.049 -31.877)
		(end 11.049 -31.242)
		(width 0.254)
		(layer "B.Cu")
		(net "P3V3_STBY_PG")
	)
	(segment
		(start 15.494 -34.3662)
		(end 15.0368 -34.3662)
		(width 0.254)
		(layer "B.Cu")
		(net "P3V3_STBY_PG")
	)
	(segment
		(start 14.6304 -34.7726)
		(end 13.9446 -34.7726)
		(width 0.254)
		(layer "B.Cu")
		(net "P3V3_STBY_PG")
	)
	(segment
		(start 67.8815 -22.3901)
		(end 68.4276 -22.9362)
		(width 0.254)
		(layer "In4.Cu")
		(net "P3V3_STBY_PG")
	)
	(segment
		(start 70.8406 -22.9362)
		(end 71.1454 -22.6314)
		(width 0.254)
		(layer "In4.Cu")
		(net "P3V3_STBY_PG")
	)
	(segment
		(start 33.35528 -31.1531)
		(end 36.180522 -31.1531)
		(width 0.254)
		(layer "In4.Cu")
		(net "P3V3_STBY_PG")
	)
	(segment
		(start 55.567326 -23.4569)
		(end 59.698636 -23.4569)
		(width 0.254)
		(layer "In4.Cu")
		(net "P3V3_STBY_PG")
	)
	(segment
		(start 37.2618 -32.234378)
		(end 39.529258 -32.234378)
		(width 0.254)
		(layer "In4.Cu")
		(net "P3V3_STBY_PG")
	)
	(segment
		(start 45.383196 -23.356824)
		(end 46.790356 -23.356824)
		(width 0.254)
		(layer "In4.Cu")
		(net "P3V3_STBY_PG")
	)
	(segment
		(start 44.6786 -24.06142)
		(end 45.383196 -23.356824)
		(width 0.254)
		(layer "In4.Cu")
		(net "P3V3_STBY_PG")
	)
	(segment
		(start 30.409642 -31.1277)
		(end 30.549342 -31.2674)
		(width 0.254)
		(layer "In4.Cu")
		(net "P3V3_STBY_PG")
	)
	(segment
		(start 47.811944 -25.23109)
		(end 49.556924 -25.23109)
		(width 0.254)
		(layer "In4.Cu")
		(net "P3V3_STBY_PG")
	)
	(segment
		(start 39.529258 -32.234378)
		(end 44.6786 -27.085036)
		(width 0.254)
		(layer "In4.Cu")
		(net "P3V3_STBY_PG")
	)
	(segment
		(start 44.6786 -27.085036)
		(end 44.6786 -24.06142)
		(width 0.254)
		(layer "In4.Cu")
		(net "P3V3_STBY_PG")
	)
	(segment
		(start 68.4276 -22.9362)
		(end 70.8406 -22.9362)
		(width 0.254)
		(layer "In4.Cu")
		(net "P3V3_STBY_PG")
	)
	(segment
		(start 47.336456 -24.755602)
		(end 47.811944 -25.23109)
		(width 0.254)
		(layer "In4.Cu")
		(net "P3V3_STBY_PG")
	)
	(segment
		(start 63.2206 -23.368)
		(end 64.1985 -22.3901)
		(width 0.254)
		(layer "In4.Cu")
		(net "P3V3_STBY_PG")
	)
	(segment
		(start 19.953732 -34.7726)
		(end 23.598632 -31.1277)
		(width 0.254)
		(layer "In4.Cu")
		(net "P3V3_STBY_PG")
	)
	(segment
		(start 50.988214 -23.7998)
		(end 55.224426 -23.7998)
		(width 0.254)
		(layer "In4.Cu")
		(net "P3V3_STBY_PG")
	)
	(segment
		(start 55.224426 -23.7998)
		(end 55.567326 -23.4569)
		(width 0.254)
		(layer "In4.Cu")
		(net "P3V3_STBY_PG")
	)
	(segment
		(start 46.790356 -23.356824)
		(end 47.336456 -23.902924)
		(width 0.254)
		(layer "In4.Cu")
		(net "P3V3_STBY_PG")
	)
	(segment
		(start 14.6304 -34.7726)
		(end 19.953732 -34.7726)
		(width 0.254)
		(layer "In4.Cu")
		(net "P3V3_STBY_PG")
	)
	(segment
		(start 60.8584 -23.4696)
		(end 60.96 -23.368)
		(width 0.254)
		(layer "In4.Cu")
		(net "P3V3_STBY_PG")
	)
	(segment
		(start 60.96 -23.368)
		(end 63.2206 -23.368)
		(width 0.254)
		(layer "In4.Cu")
		(net "P3V3_STBY_PG")
	)
	(segment
		(start 33.24098 -31.2674)
		(end 33.35528 -31.1531)
		(width 0.254)
		(layer "In4.Cu")
		(net "P3V3_STBY_PG")
	)
	(segment
		(start 30.549342 -31.2674)
		(end 33.24098 -31.2674)
		(width 0.254)
		(layer "In4.Cu")
		(net "P3V3_STBY_PG")
	)
	(segment
		(start 36.180522 -31.1531)
		(end 37.2618 -32.234378)
		(width 0.254)
		(layer "In4.Cu")
		(net "P3V3_STBY_PG")
	)
	(segment
		(start 64.1985 -22.3901)
		(end 67.8815 -22.3901)
		(width 0.254)
		(layer "In4.Cu")
		(net "P3V3_STBY_PG")
	)
	(segment
		(start 59.711336 -23.4696)
		(end 60.8584 -23.4696)
		(width 0.254)
		(layer "In4.Cu")
		(net "P3V3_STBY_PG")
	)
	(segment
		(start 59.698636 -23.4569)
		(end 59.711336 -23.4696)
		(width 0.254)
		(layer "In4.Cu")
		(net "P3V3_STBY_PG")
	)
	(segment
		(start 47.336456 -23.902924)
		(end 47.336456 -24.755602)
		(width 0.254)
		(layer "In4.Cu")
		(net "P3V3_STBY_PG")
	)
	(segment
		(start 49.556924 -25.23109)
		(end 50.988214 -23.7998)
		(width 0.254)
		(layer "In4.Cu")
		(net "P3V3_STBY_PG")
	)
	(segment
		(start 23.598632 -31.1277)
		(end 30.409642 -31.1277)
		(width 0.254)
		(layer "In4.Cu")
		(net "P3V3_STBY_PG")
	)
	(segment
		(start 104.623108 -42.941494)
		(end 104.969056 -43.287442)
		(width 0.1016)
		(layer "F.Cu")
		(net "M_A_DQ12")
	)
	(segment
		(start 184.749948 -70.806564)
		(end 184.749948 -69.814948)
		(width 0.1778)
		(layer "F.Cu")
		(net "M_A_DQ12")
	)
	(segment
		(start 184.749948 -69.814948)
		(end 184.2262 -69.2912)
		(width 0.1778)
		(layer "F.Cu")
		(net "M_A_DQ12")
	)
	(segment
		(start 104.969056 -43.287442)
		(end 104.96931 -43.287442)
		(width 0.1016)
		(layer "F.Cu")
		(net "M_A_DQ12")
	)
	(via
		(at 184.2262 -69.2912)
		(size 0.4318)
		(drill 0.2032)
		(layers "F.Cu" "B.Cu")
		(net "M_A_DQ12")
	)
	(via
		(at 104.96931 -43.287442)
		(size 0.4318)
		(drill 0.2032)
		(layers "F.Cu" "B.Cu")
		(net "M_A_DQ12")
	)
	(segment
		(start 183.850026 -70.79996)
		(end 183.850026 -69.851778)
		(width 0.1778)
		(layer "B.Cu")
		(net "M_A_DQ12")
	)
	(segment
		(start 184.2008 -69.501004)
		(end 184.2008 -69.3166)
		(width 0.1778)
		(layer "B.Cu")
		(net "M_A_DQ12")
	)
	(segment
		(start 183.850026 -69.851778)
		(end 184.2008 -69.501004)
		(width 0.1778)
		(layer "B.Cu")
		(net "M_A_DQ12")
	)
	(segment
		(start 184.2008 -69.3166)
		(end 184.2262 -69.2912)
		(width 0.1778)
		(layer "B.Cu")
		(net "M_A_DQ12")
	)
	(segment
		(start 177.327306 -51.500786)
		(end 182.7022 -56.87568)
		(width 0.1524)
		(layer "In4.Cu")
		(net "M_A_DQ12")
	)
	(segment
		(start 185.0898 -62.3062)
		(end 185.0898 -64.389)
		(width 0.1524)
		(layer "In4.Cu")
		(net "M_A_DQ12")
	)
	(segment
		(start 105.74909 -41.153334)
		(end 105.74909 -42.1386)
		(width 0.1016)
		(layer "In4.Cu")
		(net "M_A_DQ12")
	)
	(segment
		(start 106.683556 -40.327834)
		(end 105.963212 -40.939212)
		(width 0.1016)
		(layer "In4.Cu")
		(net "M_A_DQ12")
	)
	(segment
		(start 105.65765 -42.279062)
		(end 105.633266 -42.309288)
		(width 0.1016)
		(layer "In4.Cu")
		(net "M_A_DQ12")
	)
	(segment
		(start 107.413552 -40.132)
		(end 106.683556 -40.327834)
		(width 0.1016)
		(layer "In4.Cu")
		(net "M_A_DQ12")
	)
	(segment
		(start 105.74909 -42.1386)
		(end 105.65765 -42.279062)
		(width 0.1016)
		(layer "In4.Cu")
		(net "M_A_DQ12")
	)
	(segment
		(start 185.0898 -64.389)
		(end 184.2262 -69.2912)
		(width 0.1524)
		(layer "In4.Cu")
		(net "M_A_DQ12")
	)
	(segment
		(start 111.887 -40.132)
		(end 113.6142 -40.64)
		(width 0.1524)
		(layer "In4.Cu")
		(net "M_A_DQ12")
	)
	(segment
		(start 184.74944 -60.160662)
		(end 185.0898 -62.3062)
		(width 0.1524)
		(layer "In4.Cu")
		(net "M_A_DQ12")
	)
	(segment
		(start 166.130224 -43.5483)
		(end 177.327306 -51.500786)
		(width 0.1524)
		(layer "In4.Cu")
		(net "M_A_DQ12")
	)
	(segment
		(start 154.528774 -40.64)
		(end 166.130224 -43.5483)
		(width 0.1524)
		(layer "In4.Cu")
		(net "M_A_DQ12")
	)
	(segment
		(start 111.887 -40.132)
		(end 107.413552 -40.132)
		(width 0.1016)
		(layer "In4.Cu")
		(net "M_A_DQ12")
	)
	(segment
		(start 113.6142 -40.64)
		(end 154.528774 -40.64)
		(width 0.1524)
		(layer "In4.Cu")
		(net "M_A_DQ12")
	)
	(segment
		(start 182.7022 -56.87568)
		(end 184.74944 -60.160662)
		(width 0.1524)
		(layer "In4.Cu")
		(net "M_A_DQ12")
	)
	(segment
		(start 105.633266 -42.309288)
		(end 104.96931 -43.287442)
		(width 0.1016)
		(layer "In4.Cu")
		(net "M_A_DQ12")
	)
	(segment
		(start 105.963212 -40.939212)
		(end 105.74909 -41.153334)
		(width 0.1016)
		(layer "In4.Cu")
		(net "M_A_DQ12")
	)
	(segment
		(start 184.8866 -8.657082)
		(end 184.8866 -7.951978)
		(width 0.1778)
		(layer "F.Cu")
		(net "M_B_DQ56")
	)
	(segment
		(start 109.448346 -36.982654)
		(end 108.814108 -36.982654)
		(width 0.1016)
		(layer "F.Cu")
		(net "M_B_DQ56")
	)
	(segment
		(start 109.474 -36.957)
		(end 109.448346 -36.982654)
		(width 0.1016)
		(layer "F.Cu")
		(net "M_B_DQ56")
	)
	(segment
		(start 184.449974 -9.897364)
		(end 184.449974 -9.093708)
		(width 0.1778)
		(layer "F.Cu")
		(net "M_B_DQ56")
	)
	(segment
		(start 109.4994 -36.957)
		(end 109.474 -36.957)
		(width 0.1016)
		(layer "F.Cu")
		(net "M_B_DQ56")
	)
	(segment
		(start 184.8866 -7.951978)
		(end 184.658 -7.723378)
		(width 0.1778)
		(layer "F.Cu")
		(net "M_B_DQ56")
	)
	(segment
		(start 184.449974 -9.093708)
		(end 184.8866 -8.657082)
		(width 0.1778)
		(layer "F.Cu")
		(net "M_B_DQ56")
	)
	(via
		(at 184.658 -7.723378)
		(size 0.4318)
		(drill 0.2032)
		(layers "F.Cu" "B.Cu")
		(net "M_B_DQ56")
	)
	(via
		(at 109.4994 -36.957)
		(size 0.4318)
		(drill 0.2032)
		(layers "F.Cu" "B.Cu")
		(net "M_B_DQ56")
	)
	(segment
		(start 185.349896 -9.89076)
		(end 185.349896 -8.415274)
		(width 0.1778)
		(layer "B.Cu")
		(net "M_B_DQ56")
	)
	(segment
		(start 185.349896 -8.415274)
		(end 184.658 -7.723378)
		(width 0.1778)
		(layer "B.Cu")
		(net "M_B_DQ56")
	)
	(segment
		(start 139.427966 -34.798)
		(end 139.580366 -34.6456)
		(width 0.1524)
		(layer "In2.Cu")
		(net "M_B_DQ56")
	)
	(segment
		(start 153.099262 -34.8234)
		(end 153.251662 -34.671)
		(width 0.1524)
		(layer "In2.Cu")
		(net "M_B_DQ56")
	)
	(segment
		(start 135.922766 -34.6456)
		(end 135.922766 -34.028634)
		(width 0.1524)
		(layer "In2.Cu")
		(net "M_B_DQ56")
	)
	(segment
		(start 152.032462 -34.028634)
		(end 152.184862 -33.876234)
		(width 0.1524)
		(layer "In2.Cu")
		(net "M_B_DQ56")
	)
	(segment
		(start 136.532366 -34.6456)
		(end 136.684766 -34.798)
		(width 0.1524)
		(layer "In2.Cu")
		(net "M_B_DQ56")
	)
	(segment
		(start 157.98927 -33.876234)
		(end 181.9402 -9.925304)
		(width 0.1524)
		(layer "In2.Cu")
		(net "M_B_DQ56")
	)
	(segment
		(start 137.294366 -33.876234)
		(end 137.599166 -33.876234)
		(width 0.1524)
		(layer "In2.Cu")
		(net "M_B_DQ56")
	)
	(segment
		(start 151.270462 -33.876234)
		(end 151.422862 -34.028634)
		(width 0.1524)
		(layer "In2.Cu")
		(net "M_B_DQ56")
	)
	(segment
		(start 157.240478 -33.876234)
		(end 157.98927 -33.876234)
		(width 0.1524)
		(layer "In2.Cu")
		(net "M_B_DQ56")
	)
	(segment
		(start 139.580366 -34.6456)
		(end 139.580366 -34.028634)
		(width 0.1524)
		(layer "In2.Cu")
		(net "M_B_DQ56")
	)
	(segment
		(start 156.630878 -34.5186)
		(end 156.935678 -34.5186)
		(width 0.1524)
		(layer "In2.Cu")
		(net "M_B_DQ56")
	)
	(segment
		(start 118.971314 -35.3822)
		(end 119.0625 -35.291014)
		(width 0.1524)
		(layer "In2.Cu")
		(net "M_B_DQ56")
	)
	(segment
		(start 138.361166 -34.028634)
		(end 138.513566 -33.876234)
		(width 0.1524)
		(layer "In2.Cu")
		(net "M_B_DQ56")
	)
	(segment
		(start 156.478478 -34.3662)
		(end 156.630878 -34.5186)
		(width 0.1524)
		(layer "In2.Cu")
		(net "M_B_DQ56")
	)
	(segment
		(start 110.345474 -35.433)
		(end 109.855 -35.923474)
		(width 0.1016)
		(layer "In2.Cu")
		(net "M_B_DQ56")
	)
	(segment
		(start 183.769 -6.808978)
		(end 184.658 -7.697978)
		(width 0.1524)
		(layer "In2.Cu")
		(net "M_B_DQ56")
	)
	(segment
		(start 138.970766 -34.6456)
		(end 139.123166 -34.798)
		(width 0.1524)
		(layer "In2.Cu")
		(net "M_B_DQ56")
	)
	(segment
		(start 137.141966 -34.028634)
		(end 137.294366 -33.876234)
		(width 0.1524)
		(layer "In2.Cu")
		(net "M_B_DQ56")
	)
	(segment
		(start 131.256786 -35.291014)
		(end 131.7244 -34.8234)
		(width 0.1524)
		(layer "In2.Cu")
		(net "M_B_DQ56")
	)
	(segment
		(start 152.184862 -33.876234)
		(end 152.489662 -33.876234)
		(width 0.1524)
		(layer "In2.Cu")
		(net "M_B_DQ56")
	)
	(segment
		(start 153.404062 -33.876234)
		(end 156.326078 -33.876234)
		(width 0.1524)
		(layer "In2.Cu")
		(net "M_B_DQ56")
	)
	(segment
		(start 138.208766 -34.798)
		(end 138.361166 -34.6456)
		(width 0.1524)
		(layer "In2.Cu")
		(net "M_B_DQ56")
	)
	(segment
		(start 152.642062 -34.028634)
		(end 152.642062 -34.671)
		(width 0.1524)
		(layer "In2.Cu")
		(net "M_B_DQ56")
	)
	(segment
		(start 153.251662 -34.671)
		(end 153.251662 -34.028634)
		(width 0.1524)
		(layer "In2.Cu")
		(net "M_B_DQ56")
	)
	(segment
		(start 152.794462 -34.8234)
		(end 153.099262 -34.8234)
		(width 0.1524)
		(layer "In2.Cu")
		(net "M_B_DQ56")
	)
	(segment
		(start 138.970766 -34.028634)
		(end 138.970766 -34.6456)
		(width 0.1524)
		(layer "In2.Cu")
		(net "M_B_DQ56")
	)
	(segment
		(start 139.123166 -34.798)
		(end 139.427966 -34.798)
		(width 0.1524)
		(layer "In2.Cu")
		(net "M_B_DQ56")
	)
	(segment
		(start 152.642062 -34.671)
		(end 152.794462 -34.8234)
		(width 0.1524)
		(layer "In2.Cu")
		(net "M_B_DQ56")
	)
	(segment
		(start 136.989566 -34.798)
		(end 137.141966 -34.6456)
		(width 0.1524)
		(layer "In2.Cu")
		(net "M_B_DQ56")
	)
	(segment
		(start 135.922766 -34.028634)
		(end 136.075166 -33.876234)
		(width 0.1524)
		(layer "In2.Cu")
		(net "M_B_DQ56")
	)
	(segment
		(start 138.361166 -34.6456)
		(end 138.361166 -34.028634)
		(width 0.1524)
		(layer "In2.Cu")
		(net "M_B_DQ56")
	)
	(segment
		(start 109.855 -36.322)
		(end 109.4994 -36.957)
		(width 0.1016)
		(layer "In2.Cu")
		(net "M_B_DQ56")
	)
	(segment
		(start 131.7244 -34.8234)
		(end 135.744966 -34.8234)
		(width 0.1524)
		(layer "In2.Cu")
		(net "M_B_DQ56")
	)
	(segment
		(start 156.478478 -34.028634)
		(end 156.478478 -34.3662)
		(width 0.1524)
		(layer "In2.Cu")
		(net "M_B_DQ56")
	)
	(segment
		(start 117.7798 -35.3822)
		(end 118.971314 -35.3822)
		(width 0.1524)
		(layer "In2.Cu")
		(net "M_B_DQ56")
	)
	(segment
		(start 151.422862 -34.028634)
		(end 151.422862 -34.671)
		(width 0.1524)
		(layer "In2.Cu")
		(net "M_B_DQ56")
	)
	(segment
		(start 153.251662 -34.028634)
		(end 153.404062 -33.876234)
		(width 0.1524)
		(layer "In2.Cu")
		(net "M_B_DQ56")
	)
	(segment
		(start 157.088078 -34.028634)
		(end 157.240478 -33.876234)
		(width 0.1524)
		(layer "In2.Cu")
		(net "M_B_DQ56")
	)
	(segment
		(start 117.7798 -35.3822)
		(end 117.729 -35.433)
		(width 0.1016)
		(layer "In2.Cu")
		(net "M_B_DQ56")
	)
	(segment
		(start 136.532366 -34.028634)
		(end 136.532366 -34.6456)
		(width 0.1524)
		(layer "In2.Cu")
		(net "M_B_DQ56")
	)
	(segment
		(start 138.818366 -33.876234)
		(end 138.970766 -34.028634)
		(width 0.1524)
		(layer "In2.Cu")
		(net "M_B_DQ56")
	)
	(segment
		(start 139.732766 -33.876234)
		(end 151.270462 -33.876234)
		(width 0.1524)
		(layer "In2.Cu")
		(net "M_B_DQ56")
	)
	(segment
		(start 156.935678 -34.5186)
		(end 157.088078 -34.3662)
		(width 0.1524)
		(layer "In2.Cu")
		(net "M_B_DQ56")
	)
	(segment
		(start 136.379966 -33.876234)
		(end 136.532366 -34.028634)
		(width 0.1524)
		(layer "In2.Cu")
		(net "M_B_DQ56")
	)
	(segment
		(start 181.9402 -7.756398)
		(end 182.88762 -6.808978)
		(width 0.1524)
		(layer "In2.Cu")
		(net "M_B_DQ56")
	)
	(segment
		(start 136.075166 -33.876234)
		(end 136.379966 -33.876234)
		(width 0.1524)
		(layer "In2.Cu")
		(net "M_B_DQ56")
	)
	(segment
		(start 137.751566 -34.6456)
		(end 137.903966 -34.798)
		(width 0.1524)
		(layer "In2.Cu")
		(net "M_B_DQ56")
	)
	(segment
		(start 137.903966 -34.798)
		(end 138.208766 -34.798)
		(width 0.1524)
		(layer "In2.Cu")
		(net "M_B_DQ56")
	)
	(segment
		(start 136.684766 -34.798)
		(end 136.989566 -34.798)
		(width 0.1524)
		(layer "In2.Cu")
		(net "M_B_DQ56")
	)
	(segment
		(start 151.880062 -34.8234)
		(end 152.032462 -34.671)
		(width 0.1524)
		(layer "In2.Cu")
		(net "M_B_DQ56")
	)
	(segment
		(start 117.729 -35.433)
		(end 110.345474 -35.433)
		(width 0.1016)
		(layer "In2.Cu")
		(net "M_B_DQ56")
	)
	(segment
		(start 151.575262 -34.8234)
		(end 151.880062 -34.8234)
		(width 0.1524)
		(layer "In2.Cu")
		(net "M_B_DQ56")
	)
	(segment
		(start 184.658 -7.697978)
		(end 184.658 -7.723378)
		(width 0.1524)
		(layer "In2.Cu")
		(net "M_B_DQ56")
	)
	(segment
		(start 152.032462 -34.671)
		(end 152.032462 -34.028634)
		(width 0.1524)
		(layer "In2.Cu")
		(net "M_B_DQ56")
	)
	(segment
		(start 135.744966 -34.8234)
		(end 135.922766 -34.6456)
		(width 0.1524)
		(layer "In2.Cu")
		(net "M_B_DQ56")
	)
	(segment
		(start 139.580366 -34.028634)
		(end 139.732766 -33.876234)
		(width 0.1524)
		(layer "In2.Cu")
		(net "M_B_DQ56")
	)
	(segment
		(start 182.88762 -6.808978)
		(end 183.769 -6.808978)
		(width 0.1524)
		(layer "In2.Cu")
		(net "M_B_DQ56")
	)
	(segment
		(start 109.855 -35.923474)
		(end 109.855 -36.322)
		(width 0.1016)
		(layer "In2.Cu")
		(net "M_B_DQ56")
	)
	(segment
		(start 181.9402 -9.925304)
		(end 181.9402 -7.756398)
		(width 0.1524)
		(layer "In2.Cu")
		(net "M_B_DQ56")
	)
	(segment
		(start 152.489662 -33.876234)
		(end 152.642062 -34.028634)
		(width 0.1524)
		(layer "In2.Cu")
		(net "M_B_DQ56")
	)
	(segment
		(start 137.599166 -33.876234)
		(end 137.751566 -34.028634)
		(width 0.1524)
		(layer "In2.Cu")
		(net "M_B_DQ56")
	)
	(segment
		(start 138.513566 -33.876234)
		(end 138.818366 -33.876234)
		(width 0.1524)
		(layer "In2.Cu")
		(net "M_B_DQ56")
	)
	(segment
		(start 157.088078 -34.3662)
		(end 157.088078 -34.028634)
		(width 0.1524)
		(layer "In2.Cu")
		(net "M_B_DQ56")
	)
	(segment
		(start 151.422862 -34.671)
		(end 151.575262 -34.8234)
		(width 0.1524)
		(layer "In2.Cu")
		(net "M_B_DQ56")
	)
	(segment
		(start 119.0625 -35.291014)
		(end 131.256786 -35.291014)
		(width 0.1524)
		(layer "In2.Cu")
		(net "M_B_DQ56")
	)
	(segment
		(start 156.326078 -33.876234)
		(end 156.478478 -34.028634)
		(width 0.1524)
		(layer "In2.Cu")
		(net "M_B_DQ56")
	)
	(segment
		(start 137.751566 -34.028634)
		(end 137.751566 -34.6456)
		(width 0.1524)
		(layer "In2.Cu")
		(net "M_B_DQ56")
	)
	(segment
		(start 137.141966 -34.6456)
		(end 137.141966 -34.028634)
		(width 0.1524)
		(layer "In2.Cu")
		(net "M_B_DQ56")
	)
	(segment
		(start 90.122248 -46.902116)
		(end 89.748868 -47.275496)
		(width 0.1397)
		(layer "F.Cu")
		(net "USB_P1_DN")
	)
	(segment
		(start 90.122248 -46.878494)
		(end 90.122248 -46.902116)
		(width 0.1397)
		(layer "F.Cu")
		(net "USB_P1_DN")
	)
	(via
		(at 82.296 -13.9446)
		(size 0.508)
		(drill 0.254)
		(layers "F.Cu" "B.Cu")
		(net "USB_P1_DN")
	)
	(via
		(at 89.748868 -47.275496)
		(size 0.4318)
		(drill 0.2032)
		(layers "F.Cu" "B.Cu")
		(net "USB_P1_DN")
	)
	(segment
		(start 87.9221 -12.7889)
		(end 83.0199 -12.7889)
		(width 0.1397)
		(layer "B.Cu")
		(net "USB_P1_DN")
	)
	(segment
		(start 89.67851 -8.7757)
		(end 89.67851 -11.03249)
		(width 0.1397)
		(layer "B.Cu")
		(net "USB_P1_DN")
	)
	(segment
		(start 82.5754 -13.2334)
		(end 82.5754 -13.6652)
		(width 0.1397)
		(layer "B.Cu")
		(net "USB_P1_DN")
	)
	(segment
		(start 89.67851 -11.03249)
		(end 87.9221 -12.7889)
		(width 0.1397)
		(layer "B.Cu")
		(net "USB_P1_DN")
	)
	(segment
		(start 89.350088 -5.814568)
		(end 89.350088 -8.447278)
		(width 0.1397)
		(layer "B.Cu")
		(net "USB_P1_DN")
	)
	(segment
		(start 82.5754 -13.6652)
		(end 82.296 -13.9446)
		(width 0.1397)
		(layer "B.Cu")
		(net "USB_P1_DN")
	)
	(segment
		(start 83.0199 -12.7889)
		(end 82.5754 -13.2334)
		(width 0.1397)
		(layer "B.Cu")
		(net "USB_P1_DN")
	)
	(segment
		(start 89.350088 -8.447278)
		(end 89.67851 -8.7757)
		(width 0.1397)
		(layer "B.Cu")
		(net "USB_P1_DN")
	)
	(segment
		(start 81.8896 -45.3009)
		(end 81.8642 -45.3009)
		(width 0.1016)
		(layer "In9.Cu")
		(net "USB_P1_DN")
	)
	(segment
		(start 86.6648 -46.1772)
		(end 86.232492 -46.609508)
		(width 0.1016)
		(layer "In9.Cu")
		(net "USB_P1_DN")
	)
	(segment
		(start 74.2696 -34.731706)
		(end 74.2696 -27.441906)
		(width 0.1143)
		(layer "In9.Cu")
		(net "USB_P1_DN")
	)
	(segment
		(start 81.9531 -45.2374)
		(end 81.8896 -45.3009)
		(width 0.1016)
		(layer "In9.Cu")
		(net "USB_P1_DN")
	)
	(segment
		(start 82.55 -14.1986)
		(end 82.296 -13.9446)
		(width 0.1143)
		(layer "In9.Cu")
		(net "USB_P1_DN")
	)
	(segment
		(start 89.748868 -47.275496)
		(end 89.452704 -46.979332)
		(width 0.1016)
		(layer "In9.Cu")
		(net "USB_P1_DN")
	)
	(segment
		(start 79.085694 -42.8752)
		(end 77.510894 -42.8752)
		(width 0.1143)
		(layer "In9.Cu")
		(net "USB_P1_DN")
	)
	(segment
		(start 83.73618 -46.609508)
		(end 82.364072 -45.2374)
		(width 0.1016)
		(layer "In9.Cu")
		(net "USB_P1_DN")
	)
	(segment
		(start 73.787 -26.959306)
		(end 73.787 -21.8948)
		(width 0.1143)
		(layer "In9.Cu")
		(net "USB_P1_DN")
	)
	(segment
		(start 78.0415 -19.3675)
		(end 82.55 -14.859)
		(width 0.1143)
		(layer "In9.Cu")
		(net "USB_P1_DN")
	)
	(segment
		(start 74.676 -37.609526)
		(end 74.676 -35.138106)
		(width 0.1143)
		(layer "In9.Cu")
		(net "USB_P1_DN")
	)
	(segment
		(start 87.8332 -46.1772)
		(end 86.6648 -46.1772)
		(width 0.1016)
		(layer "In9.Cu")
		(net "USB_P1_DN")
	)
	(segment
		(start 82.364072 -45.2374)
		(end 81.9531 -45.2374)
		(width 0.1016)
		(layer "In9.Cu")
		(net "USB_P1_DN")
	)
	(segment
		(start 89.452704 -46.979332)
		(end 88.635332 -46.979332)
		(width 0.1016)
		(layer "In9.Cu")
		(net "USB_P1_DN")
	)
	(segment
		(start 73.787 -21.8948)
		(end 76.3143 -19.3675)
		(width 0.1143)
		(layer "In9.Cu")
		(net "USB_P1_DN")
	)
	(segment
		(start 82.55 -14.859)
		(end 82.55 -14.1986)
		(width 0.1143)
		(layer "In9.Cu")
		(net "USB_P1_DN")
	)
	(segment
		(start 76.3143 -19.3675)
		(end 78.0415 -19.3675)
		(width 0.1143)
		(layer "In9.Cu")
		(net "USB_P1_DN")
	)
	(segment
		(start 81.8642 -45.3009)
		(end 81.511394 -45.3009)
		(width 0.1143)
		(layer "In9.Cu")
		(net "USB_P1_DN")
	)
	(segment
		(start 75.95616 -41.320466)
		(end 75.95616 -38.889686)
		(width 0.1143)
		(layer "In9.Cu")
		(net "USB_P1_DN")
	)
	(segment
		(start 88.635332 -46.979332)
		(end 87.8332 -46.1772)
		(width 0.1016)
		(layer "In9.Cu")
		(net "USB_P1_DN")
	)
	(segment
		(start 75.95616 -38.889686)
		(end 74.676 -37.609526)
		(width 0.1143)
		(layer "In9.Cu")
		(net "USB_P1_DN")
	)
	(segment
		(start 74.2696 -27.441906)
		(end 73.787 -26.959306)
		(width 0.1143)
		(layer "In9.Cu")
		(net "USB_P1_DN")
	)
	(segment
		(start 81.511394 -45.3009)
		(end 79.085694 -42.8752)
		(width 0.1143)
		(layer "In9.Cu")
		(net "USB_P1_DN")
	)
	(segment
		(start 74.676 -35.138106)
		(end 74.2696 -34.731706)
		(width 0.1143)
		(layer "In9.Cu")
		(net "USB_P1_DN")
	)
	(segment
		(start 86.232492 -46.609508)
		(end 83.73618 -46.609508)
		(width 0.1016)
		(layer "In9.Cu")
		(net "USB_P1_DN")
	)
	(segment
		(start 77.510894 -42.8752)
		(end 75.95616 -41.320466)
		(width 0.1143)
		(layer "In9.Cu")
		(net "USB_P1_DN")
	)
	(segment
		(start 127.109474 -72.231504)
		(end 116.503704 -72.231504)
		(width 0.1143)
		(layer "F.Cu")
		(net "CHA_1_SA1")
	)
	(segment
		(start 116.503704 -72.231504)
		(end 115.824 -71.5518)
		(width 0.1143)
		(layer "F.Cu")
		(net "CHA_1_SA1")
	)
	(segment
		(start 115.824 -71.5518)
		(end 114.808 -71.5518)
		(width 0.1143)
		(layer "F.Cu")
		(net "CHA_1_SA1")
	)
	(segment
		(start 127.750062 -71.590916)
		(end 127.109474 -72.231504)
		(width 0.1143)
		(layer "F.Cu")
		(net "CHA_1_SA1")
	)
	(segment
		(start 114.808 -71.5518)
		(end 114.046 -71.5518)
		(width 0.1143)
		(layer "F.Cu")
		(net "CHA_1_SA1")
	)
	(segment
		(start 127.750062 -70.806564)
		(end 127.750062 -71.590916)
		(width 0.1143)
		(layer "F.Cu")
		(net "CHA_1_SA1")
	)
	(via
		(at 115.824 -71.5518)
		(size 0.7112)
		(drill 0.3556)
		(layers "F.Cu" "B.Cu")
		(net "CHA_1_SA1")
	)
	(segment
		(start 182.202328 -4.828286)
		(end 182.202328 -5.553456)
		(width 0.1778)
		(layer "F.Cu")
		(net "M_B_DQS_DP6")
	)
	(segment
		(start 182.202328 -5.553456)
		(end 182.46725 -5.818378)
		(width 0.1778)
		(layer "F.Cu")
		(net "M_B_DQS_DP6")
	)
	(segment
		(start 182.349902 -1.68402)
		(end 182.349902 -2.436876)
		(width 0.1778)
		(layer "F.Cu")
		(net "M_B_DQS_DP6")
	)
	(segment
		(start 182.202328 -2.58445)
		(end 182.202328 -4.006342)
		(width 0.1778)
		(layer "F.Cu")
		(net "M_B_DQS_DP6")
	)
	(segment
		(start 182.349902 -2.436876)
		(end 182.202328 -2.58445)
		(width 0.1778)
		(layer "F.Cu")
		(net "M_B_DQS_DP6")
	)
	(segment
		(start 182.202328 -4.006342)
		(end 182.0418 -4.16687)
		(width 0.1778)
		(layer "F.Cu")
		(net "M_B_DQS_DP6")
	)
	(segment
		(start 182.0418 -4.16687)
		(end 182.0418 -4.667758)
		(width 0.1778)
		(layer "F.Cu")
		(net "M_B_DQS_DP6")
	)
	(segment
		(start 182.0418 -4.667758)
		(end 182.202328 -4.828286)
		(width 0.1778)
		(layer "F.Cu")
		(net "M_B_DQS_DP6")
	)
	(segment
		(start 109.396276 -35.898582)
		(end 109.396276 -36.13785)
		(width 0.1016)
		(layer "F.Cu")
		(net "M_B_DQS_DP6")
	)
	(segment
		(start 109.195108 -35.697414)
		(end 109.396276 -35.898582)
		(width 0.1016)
		(layer "F.Cu")
		(net "M_B_DQS_DP6")
	)
	(via
		(at 109.396276 -36.13785)
		(size 0.4318)
		(drill 0.2032)
		(layers "F.Cu" "B.Cu")
		(net "M_B_DQS_DP6")
	)
	(via
		(at 182.46725 -5.818378)
		(size 0.4318)
		(drill 0.2032)
		(layers "F.Cu" "B.Cu")
		(net "M_B_DQS_DP6")
	)
	(segment
		(start 182.003954 -8.752332)
		(end 182.003954 -7.634224)
		(width 0.1778)
		(layer "B.Cu")
		(net "M_B_DQS_DP6")
	)
	(segment
		(start 182.003954 -7.634224)
		(end 182.2704 -7.367778)
		(width 0.1778)
		(layer "B.Cu")
		(net "M_B_DQS_DP6")
	)
	(segment
		(start 182.2704 -7.367778)
		(end 182.2704 -6.015228)
		(width 0.1778)
		(layer "B.Cu")
		(net "M_B_DQS_DP6")
	)
	(segment
		(start 182.349902 -9.89076)
		(end 182.349902 -9.09828)
		(width 0.1778)
		(layer "B.Cu")
		(net "M_B_DQS_DP6")
	)
	(segment
		(start 182.2704 -6.015228)
		(end 182.46725 -5.818378)
		(width 0.1778)
		(layer "B.Cu")
		(net "M_B_DQS_DP6")
	)
	(segment
		(start 182.349902 -9.09828)
		(end 182.003954 -8.752332)
		(width 0.1778)
		(layer "B.Cu")
		(net "M_B_DQS_DP6")
	)
	(segment
		(start 155.814776 -37.101526)
		(end 157.93593 -37.101526)
		(width 0.1524)
		(layer "In9.Cu")
		(net "M_B_DQS_DP6")
	)
	(segment
		(start 179.249324 -12.5349)
		(end 181.6608 -10.123424)
		(width 0.1524)
		(layer "In9.Cu")
		(net "M_B_DQS_DP6")
	)
	(segment
		(start 111.0742 -36.6776)
		(end 110.1852 -36.6776)
		(width 0.1016)
		(layer "In9.Cu")
		(net "M_B_DQS_DP6")
	)
	(segment
		(start 111.461804 -36.289996)
		(end 112.85855 -36.289996)
		(width 0.1524)
		(layer "In9.Cu")
		(net "M_B_DQS_DP6")
	)
	(segment
		(start 142.367 -36.2458)
		(end 143.3068 -36.2458)
		(width 0.1524)
		(layer "In9.Cu")
		(net "M_B_DQS_DP6")
	)
	(segment
		(start 143.4592 -36.844224)
		(end 143.775176 -37.1602)
		(width 0.1524)
		(layer "In9.Cu")
		(net "M_B_DQS_DP6")
	)
	(segment
		(start 142.2146 -36.3982)
		(end 142.367 -36.2458)
		(width 0.1524)
		(layer "In9.Cu")
		(net "M_B_DQS_DP6")
	)
	(segment
		(start 109.8804 -36.3728)
		(end 109.8804 -35.7632)
		(width 0.1016)
		(layer "In9.Cu")
		(net "M_B_DQS_DP6")
	)
	(segment
		(start 109.452664 -35.6362)
		(end 109.347 -35.741864)
		(width 0.1016)
		(layer "In9.Cu")
		(net "M_B_DQS_DP6")
	)
	(segment
		(start 135.1026 -37.1602)
		(end 141.8844 -37.1602)
		(width 0.1524)
		(layer "In9.Cu")
		(net "M_B_DQS_DP6")
	)
	(segment
		(start 149.2504 -36.2458)
		(end 149.3266 -36.1696)
		(width 0.1524)
		(layer "In9.Cu")
		(net "M_B_DQS_DP6")
	)
	(segment
		(start 157.93593 -37.101526)
		(end 179.249324 -15.788132)
		(width 0.1524)
		(layer "In9.Cu")
		(net "M_B_DQS_DP6")
	)
	(segment
		(start 147.066 -36.4998)
		(end 147.32 -36.2458)
		(width 0.1524)
		(layer "In9.Cu")
		(net "M_B_DQS_DP6")
	)
	(segment
		(start 146.685 -37.1602)
		(end 147.066 -36.7792)
		(width 0.1524)
		(layer "In9.Cu")
		(net "M_B_DQS_DP6")
	)
	(segment
		(start 109.347 -35.741864)
		(end 109.347 -36.088574)
		(width 0.1016)
		(layer "In9.Cu")
		(net "M_B_DQS_DP6")
	)
	(segment
		(start 109.8804 -35.7632)
		(end 109.7534 -35.6362)
		(width 0.1016)
		(layer "In9.Cu")
		(net "M_B_DQS_DP6")
	)
	(segment
		(start 110.1852 -36.6776)
		(end 109.8804 -36.3728)
		(width 0.1016)
		(layer "In9.Cu")
		(net "M_B_DQS_DP6")
	)
	(segment
		(start 131.5974 -37.1856)
		(end 132.6134 -36.1696)
		(width 0.1524)
		(layer "In9.Cu")
		(net "M_B_DQS_DP6")
	)
	(segment
		(start 149.3266 -36.1696)
		(end 152.3238 -36.1696)
		(width 0.1524)
		(layer "In9.Cu")
		(net "M_B_DQS_DP6")
	)
	(segment
		(start 152.3238 -36.1696)
		(end 152.7048 -36.5506)
		(width 0.1524)
		(layer "In9.Cu")
		(net "M_B_DQS_DP6")
	)
	(segment
		(start 179.249324 -15.788132)
		(end 179.249324 -12.5349)
		(width 0.1524)
		(layer "In9.Cu")
		(net "M_B_DQS_DP6")
	)
	(segment
		(start 154.88285 -36.1696)
		(end 155.814776 -37.101526)
		(width 0.1524)
		(layer "In9.Cu")
		(net "M_B_DQS_DP6")
	)
	(segment
		(start 134.7978 -36.322)
		(end 134.7978 -36.8554)
		(width 0.1524)
		(layer "In9.Cu")
		(net "M_B_DQS_DP6")
	)
	(segment
		(start 109.347 -36.088574)
		(end 109.396276 -36.13785)
		(width 0.1016)
		(layer "In9.Cu")
		(net "M_B_DQS_DP6")
	)
	(segment
		(start 142.2146 -36.83)
		(end 142.2146 -36.3982)
		(width 0.1524)
		(layer "In9.Cu")
		(net "M_B_DQS_DP6")
	)
	(segment
		(start 112.85855 -36.289996)
		(end 113.754154 -37.1856)
		(width 0.1524)
		(layer "In9.Cu")
		(net "M_B_DQS_DP6")
	)
	(segment
		(start 181.6608 -7.051802)
		(end 182.189628 -6.522974)
		(width 0.1524)
		(layer "In9.Cu")
		(net "M_B_DQS_DP6")
	)
	(segment
		(start 143.4592 -36.3982)
		(end 143.4592 -36.844224)
		(width 0.1524)
		(layer "In9.Cu")
		(net "M_B_DQS_DP6")
	)
	(segment
		(start 111.0742 -36.6776)
		(end 111.461804 -36.289996)
		(width 0.1524)
		(layer "In9.Cu")
		(net "M_B_DQS_DP6")
	)
	(segment
		(start 154.3812 -36.1696)
		(end 154.88285 -36.1696)
		(width 0.1524)
		(layer "In9.Cu")
		(net "M_B_DQS_DP6")
	)
	(segment
		(start 143.775176 -37.1602)
		(end 146.685 -37.1602)
		(width 0.1524)
		(layer "In9.Cu")
		(net "M_B_DQS_DP6")
	)
	(segment
		(start 154.0002 -36.5506)
		(end 154.3812 -36.1696)
		(width 0.1524)
		(layer "In9.Cu")
		(net "M_B_DQS_DP6")
	)
	(segment
		(start 141.8844 -37.1602)
		(end 142.2146 -36.83)
		(width 0.1524)
		(layer "In9.Cu")
		(net "M_B_DQS_DP6")
	)
	(segment
		(start 147.32 -36.2458)
		(end 149.2504 -36.2458)
		(width 0.1524)
		(layer "In9.Cu")
		(net "M_B_DQS_DP6")
	)
	(segment
		(start 152.7048 -36.5506)
		(end 154.0002 -36.5506)
		(width 0.1524)
		(layer "In9.Cu")
		(net "M_B_DQS_DP6")
	)
	(segment
		(start 132.6134 -36.1696)
		(end 134.6454 -36.1696)
		(width 0.1524)
		(layer "In9.Cu")
		(net "M_B_DQS_DP6")
	)
	(segment
		(start 181.6608 -10.123424)
		(end 181.6608 -7.051802)
		(width 0.1524)
		(layer "In9.Cu")
		(net "M_B_DQS_DP6")
	)
	(segment
		(start 134.7978 -36.8554)
		(end 135.1026 -37.1602)
		(width 0.1524)
		(layer "In9.Cu")
		(net "M_B_DQS_DP6")
	)
	(segment
		(start 143.3068 -36.2458)
		(end 143.4592 -36.3982)
		(width 0.1524)
		(layer "In9.Cu")
		(net "M_B_DQS_DP6")
	)
	(segment
		(start 113.754154 -37.1856)
		(end 131.5974 -37.1856)
		(width 0.1524)
		(layer "In9.Cu")
		(net "M_B_DQS_DP6")
	)
	(segment
		(start 182.189628 -6.522974)
		(end 182.189628 -6.096)
		(width 0.1524)
		(layer "In9.Cu")
		(net "M_B_DQS_DP6")
	)
	(segment
		(start 109.7534 -35.6362)
		(end 109.452664 -35.6362)
		(width 0.1016)
		(layer "In9.Cu")
		(net "M_B_DQS_DP6")
	)
	(segment
		(start 182.189628 -6.096)
		(end 182.46725 -5.818378)
		(width 0.1524)
		(layer "In9.Cu")
		(net "M_B_DQS_DP6")
	)
	(segment
		(start 134.6454 -36.1696)
		(end 134.7978 -36.322)
		(width 0.1524)
		(layer "In9.Cu")
		(net "M_B_DQS_DP6")
	)
	(segment
		(start 147.066 -36.7792)
		(end 147.066 -36.4998)
		(width 0.1524)
		(layer "In9.Cu")
		(net "M_B_DQS_DP6")
	)
	(segment
		(start 188.1378 -60.7822)
		(end 189.103 -60.7822)
		(width 0.1778)
		(layer "F.Cu")
		(net "DDR3_M_A_VREF_DQ1")
	)
	(segment
		(start 190.7032 -61.749178)
		(end 189.736222 -60.7822)
		(width 0.1778)
		(layer "F.Cu")
		(net "DDR3_M_A_VREF_DQ1")
	)
	(segment
		(start 189.736222 -60.7822)
		(end 189.103 -60.7822)
		(width 0.1778)
		(layer "F.Cu")
		(net "DDR3_M_A_VREF_DQ1")
	)
	(segment
		(start 184.1246 -56.0578)
		(end 183.388 -56.0578)
		(width 0.1778)
		(layer "F.Cu")
		(net "DDR3_M_A_VREF_DQ1")
	)
	(segment
		(start 190.149988 -69.946012)
		(end 190.7032 -69.3928)
		(width 0.1778)
		(layer "F.Cu")
		(net "DDR3_M_A_VREF_DQ1")
	)
	(segment
		(start 185.42 -56.8706)
		(end 185.42 -58.0644)
		(width 0.1778)
		(layer "F.Cu")
		(net "DDR3_M_A_VREF_DQ1")
	)
	(segment
		(start 187.96 -60.6044)
		(end 188.1378 -60.7822)
		(width 0.1778)
		(layer "F.Cu")
		(net "DDR3_M_A_VREF_DQ1")
	)
	(segment
		(start 184.15 -56.0832)
		(end 184.1246 -56.0578)
		(width 0.1778)
		(layer "F.Cu")
		(net "DDR3_M_A_VREF_DQ1")
	)
	(segment
		(start 185.42 -56.8706)
		(end 184.6326 -56.0832)
		(width 0.1778)
		(layer "F.Cu")
		(net "DDR3_M_A_VREF_DQ1")
	)
	(segment
		(start 190.7032 -69.3928)
		(end 190.7032 -61.749178)
		(width 0.1778)
		(layer "F.Cu")
		(net "DDR3_M_A_VREF_DQ1")
	)
	(segment
		(start 190.149988 -70.806564)
		(end 190.149988 -69.946012)
		(width 0.1778)
		(layer "F.Cu")
		(net "DDR3_M_A_VREF_DQ1")
	)
	(segment
		(start 184.6326 -56.0832)
		(end 184.15 -56.0832)
		(width 0.1778)
		(layer "F.Cu")
		(net "DDR3_M_A_VREF_DQ1")
	)
	(segment
		(start 185.42 -58.0644)
		(end 187.96 -60.6044)
		(width 0.1778)
		(layer "F.Cu")
		(net "DDR3_M_A_VREF_DQ1")
	)
	(via
		(at 185.42 -56.8706)
		(size 0.7112)
		(drill 0.3556)
		(layers "F.Cu" "B.Cu")
		(net "DDR3_M_A_VREF_DQ1")
	)
	(segment
		(start 189.55004 -1.68402)
		(end 189.55004 -2.841752)
		(width 0.1143)
		(layer "F.Cu")
		(net "CHB_1_SA0")
	)
	(segment
		(start 194.710812 -6.675628)
		(end 196.159628 -6.675628)
		(width 0.1143)
		(layer "F.Cu")
		(net "CHB_1_SA0")
	)
	(segment
		(start 189.65545 -2.947162)
		(end 189.65545 -5.127752)
		(width 0.1143)
		(layer "F.Cu")
		(net "CHB_1_SA0")
	)
	(segment
		(start 192.512442 -6.711442)
		(end 194.674998 -6.711442)
		(width 0.1143)
		(layer "F.Cu")
		(net "CHB_1_SA0")
	)
	(segment
		(start 196.596 -7.112)
		(end 197.6882 -7.112)
		(width 0.1143)
		(layer "F.Cu")
		(net "CHB_1_SA0")
	)
	(segment
		(start 194.674998 -6.711442)
		(end 194.710812 -6.675628)
		(width 0.1143)
		(layer "F.Cu")
		(net "CHB_1_SA0")
	)
	(segment
		(start 192.438528 -6.637528)
		(end 192.512442 -6.711442)
		(width 0.1143)
		(layer "F.Cu")
		(net "CHB_1_SA0")
	)
	(segment
		(start 191.165226 -6.637528)
		(end 192.438528 -6.637528)
		(width 0.1143)
		(layer "F.Cu")
		(net "CHB_1_SA0")
	)
	(segment
		(start 189.55004 -2.841752)
		(end 189.65545 -2.947162)
		(width 0.1143)
		(layer "F.Cu")
		(net "CHB_1_SA0")
	)
	(segment
		(start 197.6882 -6.35)
		(end 197.6882 -7.112)
		(width 0.1143)
		(layer "F.Cu")
		(net "CHB_1_SA0")
	)
	(segment
		(start 196.159628 -6.675628)
		(end 196.596 -7.112)
		(width 0.1143)
		(layer "F.Cu")
		(net "CHB_1_SA0")
	)
	(segment
		(start 189.65545 -5.127752)
		(end 191.165226 -6.637528)
		(width 0.1143)
		(layer "F.Cu")
		(net "CHB_1_SA0")
	)
	(segment
		(start 84.409788 -40.716454)
		(end 84.34197 -40.716454)
		(width 0.1143)
		(layer "F.Cu")
		(net "IRQ_NMI_R")
	)
	(segment
		(start 84.34197 -40.716454)
		(end 83.8962 -40.270684)
		(width 0.1143)
		(layer "F.Cu")
		(net "IRQ_NMI_R")
	)
	(via
		(at 71.755 -45.0342)
		(size 0.7112)
		(drill 0.3556)
		(layers "F.Cu" "B.Cu")
		(net "IRQ_NMI_R")
	)
	(via
		(at 83.8962 -40.270684)
		(size 0.4318)
		(drill 0.2032)
		(layers "F.Cu" "B.Cu")
		(net "IRQ_NMI_R")
	)
	(segment
		(start 74.94905 -45.59935)
		(end 75.4126 -45.1358)
		(width 0.1143)
		(layer "B.Cu")
		(net "IRQ_NMI_R")
	)
	(segment
		(start 82.030062 -41.667938)
		(end 83.144106 -41.667938)
		(width 0.1143)
		(layer "B.Cu")
		(net "IRQ_NMI_R")
	)
	(segment
		(start 68.834 -46.6598)
		(end 69.3674 -46.6598)
		(width 0.1143)
		(layer "B.Cu")
		(net "IRQ_NMI_R")
	)
	(segment
		(start 73.28535 -45.59935)
		(end 74.94905 -45.59935)
		(width 0.1143)
		(layer "B.Cu")
		(net "IRQ_NMI_R")
	)
	(segment
		(start 83.144106 -41.667938)
		(end 83.63585 -41.176194)
		(width 0.1143)
		(layer "B.Cu")
		(net "IRQ_NMI_R")
	)
	(segment
		(start 75.4126 -45.1358)
		(end 78.5622 -45.1358)
		(width 0.1143)
		(layer "B.Cu")
		(net "IRQ_NMI_R")
	)
	(segment
		(start 70.4596 -46.0248)
		(end 71.4502 -45.0342)
		(width 0.1143)
		(layer "B.Cu")
		(net "IRQ_NMI_R")
	)
	(segment
		(start 71.755 -45.0342)
		(end 72.7202 -45.0342)
		(width 0.1143)
		(layer "B.Cu")
		(net "IRQ_NMI_R")
	)
	(segment
		(start 69.596 -46.4312)
		(end 70.0532 -46.4312)
		(width 0.1143)
		(layer "B.Cu")
		(net "IRQ_NMI_R")
	)
	(segment
		(start 69.3674 -46.6598)
		(end 69.596 -46.4312)
		(width 0.1143)
		(layer "B.Cu")
		(net "IRQ_NMI_R")
	)
	(segment
		(start 72.7202 -45.0342)
		(end 73.28535 -45.59935)
		(width 0.1143)
		(layer "B.Cu")
		(net "IRQ_NMI_R")
	)
	(segment
		(start 83.63585 -40.531034)
		(end 83.8962 -40.270684)
		(width 0.1143)
		(layer "B.Cu")
		(net "IRQ_NMI_R")
	)
	(segment
		(start 83.63585 -41.176194)
		(end 83.63585 -40.531034)
		(width 0.1143)
		(layer "B.Cu")
		(net "IRQ_NMI_R")
	)
	(segment
		(start 71.4502 -45.0342)
		(end 71.755 -45.0342)
		(width 0.1143)
		(layer "B.Cu")
		(net "IRQ_NMI_R")
	)
	(segment
		(start 78.5622 -45.1358)
		(end 82.030062 -41.667938)
		(width 0.1143)
		(layer "B.Cu")
		(net "IRQ_NMI_R")
	)
	(segment
		(start 70.0532 -46.4312)
		(end 70.4596 -46.0248)
		(width 0.1143)
		(layer "B.Cu")
		(net "IRQ_NMI_R")
	)
	(segment
		(start 53.8734 -52.5526)
		(end 53.2892 -51.9684)
		(width 0.254)
		(layer "F.Cu")
		(net "AGND_P1V0_STBY")
	)
	(segment
		(start 55.57393 -53.033422)
		(end 54.737 -53.870352)
		(width 0.254)
		(layer "F.Cu")
		(net "AGND_P1V0_STBY")
	)
	(segment
		(start 54.3306 -53.9242)
		(end 53.8734 -53.467)
		(width 0.254)
		(layer "F.Cu")
		(net "AGND_P1V0_STBY")
	)
	(segment
		(start 53.8734 -53.467)
		(end 53.8734 -52.5526)
		(width 0.254)
		(layer "F.Cu")
		(net "AGND_P1V0_STBY")
	)
	(segment
		(start 55.57393 -52.557934)
		(end 55.57393 -53.033422)
		(width 0.254)
		(layer "F.Cu")
		(net "AGND_P1V0_STBY")
	)
	(segment
		(start 54.737 -53.9242)
		(end 54.3306 -53.9242)
		(width 0.254)
		(layer "F.Cu")
		(net "AGND_P1V0_STBY")
	)
	(segment
		(start 54.737 -53.870352)
		(end 54.737 -53.9242)
		(width 0.254)
		(layer "F.Cu")
		(net "AGND_P1V0_STBY")
	)
	(segment
		(start 152.841198 -68.824602)
		(end 152.841198 -66.811398)
		(width 0.2413)
		(layer "F.Cu")
		(net "M_A_MA10")
	)
	(segment
		(start 152.841198 -66.811398)
		(end 152.120346 -66.090546)
		(width 0.2413)
		(layer "F.Cu")
		(net "M_A_MA10")
	)
	(segment
		(start 152.120346 -66.090546)
		(end 151.993092 -66.090546)
		(width 0.2413)
		(layer "F.Cu")
		(net "M_A_MA10")
	)
	(segment
		(start 152.5397 -69.1261)
		(end 152.841198 -68.824602)
		(width 0.2413)
		(layer "F.Cu")
		(net "M_A_MA10")
	)
	(segment
		(start 152.5397 -69.498718)
		(end 152.5397 -69.1261)
		(width 0.2413)
		(layer "F.Cu")
		(net "M_A_MA10")
	)
	(segment
		(start 107.315 -53.28285)
		(end 106.92765 -53.6702)
		(width 0.2413)
		(layer "F.Cu")
		(net "M_A_MA10")
	)
	(segment
		(start 152.950164 -70.806564)
		(end 152.950164 -69.909182)
		(width 0.2413)
		(layer "F.Cu")
		(net "M_A_MA10")
	)
	(segment
		(start 107.467908 -51.841654)
		(end 107.315 -51.994562)
		(width 0.2413)
		(layer "F.Cu")
		(net "M_A_MA10")
	)
	(segment
		(start 152.950164 -69.909182)
		(end 152.5397 -69.498718)
		(width 0.2413)
		(layer "F.Cu")
		(net "M_A_MA10")
	)
	(segment
		(start 107.315 -51.994562)
		(end 107.315 -53.28285)
		(width 0.2413)
		(layer "F.Cu")
		(net "M_A_MA10")
	)
	(via
		(at 151.993092 -66.090546)
		(size 0.4318)
		(drill 0.2032)
		(layers "F.Cu" "B.Cu")
		(net "M_A_MA10")
	)
	(via
		(at 106.92765 -53.6702)
		(size 0.4318)
		(drill 0.2032)
		(layers "F.Cu" "B.Cu")
		(net "M_A_MA10")
	)
	(segment
		(start 152.745948 -63.690246)
		(end 152.745948 -65.321688)
		(width 0.2413)
		(layer "B.Cu")
		(net "M_A_MA10")
	)
	(segment
		(start 151.9936 -66.074036)
		(end 151.9936 -66.090038)
		(width 0.2413)
		(layer "B.Cu")
		(net "M_A_MA10")
	)
	(segment
		(start 151.9936 -66.090038)
		(end 151.993092 -66.090546)
		(width 0.2413)
		(layer "B.Cu")
		(net "M_A_MA10")
	)
	(segment
		(start 152.950164 -62.599824)
		(end 152.950164 -63.48603)
		(width 0.2413)
		(layer "B.Cu")
		(net "M_A_MA10")
	)
	(segment
		(start 152.950164 -63.48603)
		(end 152.745948 -63.690246)
		(width 0.2413)
		(layer "B.Cu")
		(net "M_A_MA10")
	)
	(segment
		(start 152.745948 -65.321688)
		(end 151.9936 -66.074036)
		(width 0.2413)
		(layer "B.Cu")
		(net "M_A_MA10")
	)
	(segment
		(start 125.64491 -57.6326)
		(end 125.64491 -57.30875)
		(width 0.1905)
		(layer "In9.Cu")
		(net "M_A_MA10")
	)
	(segment
		(start 126.40691 -57.6326)
		(end 126.24181 -57.7977)
		(width 0.1905)
		(layer "In9.Cu")
		(net "M_A_MA10")
	)
	(segment
		(start 122.40641 -57.11825)
		(end 109.13745 -57.11825)
		(width 0.1905)
		(layer "In9.Cu")
		(net "M_A_MA10")
	)
	(segment
		(start 126.98476 -57.11825)
		(end 126.59106 -57.11825)
		(width 0.1905)
		(layer "In9.Cu")
		(net "M_A_MA10")
	)
	(segment
		(start 124.88291 -57.30875)
		(end 124.88291 -57.6326)
		(width 0.1905)
		(layer "In9.Cu")
		(net "M_A_MA10")
	)
	(segment
		(start 124.12091 -57.6326)
		(end 124.12091 -57.30875)
		(width 0.1905)
		(layer "In9.Cu")
		(net "M_A_MA10")
	)
	(segment
		(start 149.148038 -60.312554)
		(end 148.453602 -59.618118)
		(width 0.1905)
		(layer "In9.Cu")
		(net "M_A_MA10")
	)
	(segment
		(start 109.13745 -57.11825)
		(end 109.0422 -57.023)
		(width 0.1905)
		(layer "In9.Cu")
		(net "M_A_MA10")
	)
	(segment
		(start 128.607058 -57.11825)
		(end 128.12141 -57.11825)
		(width 0.1905)
		(layer "In9.Cu")
		(net "M_A_MA10")
	)
	(segment
		(start 107.569 -54.31155)
		(end 106.92765 -53.6702)
		(width 0.1016)
		(layer "In9.Cu")
		(net "M_A_MA10")
	)
	(segment
		(start 107.634024 -56.054244)
		(end 107.8738 -56.054244)
		(width 0.1016)
		(layer "In9.Cu")
		(net "M_A_MA10")
	)
	(segment
		(start 107.8738 -57.531)
		(end 107.634024 -57.531)
		(width 0.1016)
		(layer "In9.Cu")
		(net "M_A_MA10")
	)
	(segment
		(start 132.846064 -57.11825)
		(end 129.36982 -57.11825)
		(width 0.1905)
		(layer "In9.Cu")
		(net "M_A_MA10")
	)
	(segment
		(start 123.35891 -57.658)
		(end 123.21921 -57.7977)
		(width 0.1905)
		(layer "In9.Cu")
		(net "M_A_MA10")
	)
	(segment
		(start 125.45441 -57.11825)
		(end 125.07341 -57.11825)
		(width 0.1905)
		(layer "In9.Cu")
		(net "M_A_MA10")
	)
	(segment
		(start 124.71781 -57.7977)
		(end 124.28601 -57.7977)
		(width 0.1905)
		(layer "In9.Cu")
		(net "M_A_MA10")
	)
	(segment
		(start 134.488936 -57.49925)
		(end 134.107936 -57.88025)
		(width 0.1905)
		(layer "In9.Cu")
		(net "M_A_MA10")
	)
	(segment
		(start 133.608064 -57.88025)
		(end 133.286754 -57.55894)
		(width 0.1905)
		(layer "In9.Cu")
		(net "M_A_MA10")
	)
	(segment
		(start 107.8738 -56.054244)
		(end 108.0262 -55.901844)
		(width 0.1016)
		(layer "In9.Cu")
		(net "M_A_MA10")
	)
	(segment
		(start 107.569 -55.0418)
		(end 107.569 -54.31155)
		(width 0.1016)
		(layer "In9.Cu")
		(net "M_A_MA10")
	)
	(segment
		(start 124.12091 -57.30875)
		(end 123.93041 -57.11825)
		(width 0.1905)
		(layer "In9.Cu")
		(net "M_A_MA10")
	)
	(segment
		(start 141.772894 -57.68975)
		(end 139.441174 -57.68975)
		(width 0.1905)
		(layer "In9.Cu")
		(net "M_A_MA10")
	)
	(segment
		(start 122.59691 -57.30875)
		(end 122.40641 -57.11825)
		(width 0.1905)
		(layer "In9.Cu")
		(net "M_A_MA10")
	)
	(segment
		(start 134.107936 -57.88025)
		(end 133.608064 -57.88025)
		(width 0.1905)
		(layer "In9.Cu")
		(net "M_A_MA10")
	)
	(segment
		(start 127.93091 -57.30875)
		(end 127.93091 -57.6326)
		(width 0.1905)
		(layer "In9.Cu")
		(net "M_A_MA10")
	)
	(segment
		(start 138.06805 -57.88025)
		(end 137.68705 -57.49925)
		(width 0.1905)
		(layer "In9.Cu")
		(net "M_A_MA10")
	)
	(segment
		(start 122.59691 -57.658)
		(end 122.59691 -57.30875)
		(width 0.1905)
		(layer "In9.Cu")
		(net "M_A_MA10")
	)
	(segment
		(start 127.16891 -57.6326)
		(end 127.16891 -57.3024)
		(width 0.1905)
		(layer "In9.Cu")
		(net "M_A_MA10")
	)
	(segment
		(start 135.14705 -57.49925)
		(end 134.488936 -57.49925)
		(width 0.1905)
		(layer "In9.Cu")
		(net "M_A_MA10")
	)
	(segment
		(start 108.0262 -57.3786)
		(end 107.8738 -57.531)
		(width 0.1016)
		(layer "In9.Cu")
		(net "M_A_MA10")
	)
	(segment
		(start 125.07341 -57.11825)
		(end 124.88291 -57.30875)
		(width 0.1905)
		(layer "In9.Cu")
		(net "M_A_MA10")
	)
	(segment
		(start 127.33401 -57.7977)
		(end 127.16891 -57.6326)
		(width 0.1905)
		(layer "In9.Cu")
		(net "M_A_MA10")
	)
	(segment
		(start 129.36982 -57.11825)
		(end 129.16027 -57.3278)
		(width 0.1905)
		(layer "In9.Cu")
		(net "M_A_MA10")
	)
	(segment
		(start 136.55675 -57.49925)
		(end 136.17575 -57.88025)
		(width 0.1905)
		(layer "In9.Cu")
		(net "M_A_MA10")
	)
	(segment
		(start 148.453602 -59.618118)
		(end 146.782028 -59.618118)
		(width 0.1905)
		(layer "In9.Cu")
		(net "M_A_MA10")
	)
	(segment
		(start 126.24181 -57.7977)
		(end 125.81001 -57.7977)
		(width 0.1905)
		(layer "In9.Cu")
		(net "M_A_MA10")
	)
	(segment
		(start 127.16891 -57.3024)
		(end 126.98476 -57.11825)
		(width 0.1905)
		(layer "In9.Cu")
		(net "M_A_MA10")
	)
	(segment
		(start 137.68705 -57.49925)
		(end 136.55675 -57.49925)
		(width 0.1905)
		(layer "In9.Cu")
		(net "M_A_MA10")
	)
	(segment
		(start 107.8738 -55.1942)
		(end 107.7214 -55.1942)
		(width 0.1016)
		(layer "In9.Cu")
		(net "M_A_MA10")
	)
	(segment
		(start 129.16027 -57.3278)
		(end 128.816608 -57.3278)
		(width 0.1905)
		(layer "In9.Cu")
		(net "M_A_MA10")
	)
	(segment
		(start 152.1206 -62.992)
		(end 149.441154 -60.312554)
		(width 0.1905)
		(layer "In9.Cu")
		(net "M_A_MA10")
	)
	(segment
		(start 126.59106 -57.11825)
		(end 126.40691 -57.3024)
		(width 0.1905)
		(layer "In9.Cu")
		(net "M_A_MA10")
	)
	(segment
		(start 145.416524 -58.252614)
		(end 142.335758 -58.252614)
		(width 0.1905)
		(layer "In9.Cu")
		(net "M_A_MA10")
	)
	(segment
		(start 124.88291 -57.6326)
		(end 124.71781 -57.7977)
		(width 0.1905)
		(layer "In9.Cu")
		(net "M_A_MA10")
	)
	(segment
		(start 138.89355 -57.49925)
		(end 138.51255 -57.88025)
		(width 0.1905)
		(layer "In9.Cu")
		(net "M_A_MA10")
	)
	(segment
		(start 109.0422 -57.023)
		(end 109.0422 -56.896)
		(width 0.1016)
		(layer "In9.Cu")
		(net "M_A_MA10")
	)
	(segment
		(start 139.250674 -57.49925)
		(end 138.89355 -57.49925)
		(width 0.1905)
		(layer "In9.Cu")
		(net "M_A_MA10")
	)
	(segment
		(start 146.782028 -59.618118)
		(end 145.416524 -58.252614)
		(width 0.1905)
		(layer "In9.Cu")
		(net "M_A_MA10")
	)
	(segment
		(start 123.93041 -57.11825)
		(end 123.54941 -57.11825)
		(width 0.1905)
		(layer "In9.Cu")
		(net "M_A_MA10")
	)
	(segment
		(start 136.17575 -57.88025)
		(end 135.52805 -57.88025)
		(width 0.1905)
		(layer "In9.Cu")
		(net "M_A_MA10")
	)
	(segment
		(start 107.481624 -56.206644)
		(end 107.634024 -56.054244)
		(width 0.1016)
		(layer "In9.Cu")
		(net "M_A_MA10")
	)
	(segment
		(start 108.1786 -56.7436)
		(end 108.0262 -56.896)
		(width 0.1016)
		(layer "In9.Cu")
		(net "M_A_MA10")
	)
	(segment
		(start 142.335758 -58.252614)
		(end 141.772894 -57.68975)
		(width 0.1905)
		(layer "In9.Cu")
		(net "M_A_MA10")
	)
	(segment
		(start 108.0262 -55.901844)
		(end 108.0262 -55.3466)
		(width 0.1016)
		(layer "In9.Cu")
		(net "M_A_MA10")
	)
	(segment
		(start 128.816608 -57.3278)
		(end 128.607058 -57.11825)
		(width 0.1905)
		(layer "In9.Cu")
		(net "M_A_MA10")
	)
	(segment
		(start 107.7214 -55.1942)
		(end 107.569 -55.0418)
		(width 0.1016)
		(layer "In9.Cu")
		(net "M_A_MA10")
	)
	(segment
		(start 149.441154 -60.312554)
		(end 149.148038 -60.312554)
		(width 0.1905)
		(layer "In9.Cu")
		(net "M_A_MA10")
	)
	(segment
		(start 108.8898 -56.7436)
		(end 108.1786 -56.7436)
		(width 0.1016)
		(layer "In9.Cu")
		(net "M_A_MA10")
	)
	(segment
		(start 126.40691 -57.3024)
		(end 126.40691 -57.6326)
		(width 0.1905)
		(layer "In9.Cu")
		(net "M_A_MA10")
	)
	(segment
		(start 152.1206 -65.963038)
		(end 152.1206 -62.992)
		(width 0.1905)
		(layer "In9.Cu")
		(net "M_A_MA10")
	)
	(segment
		(start 139.441174 -57.68975)
		(end 139.250674 -57.49925)
		(width 0.1905)
		(layer "In9.Cu")
		(net "M_A_MA10")
	)
	(segment
		(start 138.51255 -57.88025)
		(end 138.06805 -57.88025)
		(width 0.1905)
		(layer "In9.Cu")
		(net "M_A_MA10")
	)
	(segment
		(start 133.286754 -57.558686)
		(end 132.922518 -57.19445)
		(width 0.1905)
		(layer "In9.Cu")
		(net "M_A_MA10")
	)
	(segment
		(start 123.35891 -57.30875)
		(end 123.35891 -57.658)
		(width 0.1905)
		(layer "In9.Cu")
		(net "M_A_MA10")
	)
	(segment
		(start 132.922518 -57.19445)
		(end 132.922264 -57.19445)
		(width 0.1905)
		(layer "In9.Cu")
		(net "M_A_MA10")
	)
	(segment
		(start 128.12141 -57.11825)
		(end 127.93091 -57.30875)
		(width 0.1905)
		(layer "In9.Cu")
		(net "M_A_MA10")
	)
	(segment
		(start 123.54941 -57.11825)
		(end 123.35891 -57.30875)
		(width 0.1905)
		(layer "In9.Cu")
		(net "M_A_MA10")
	)
	(segment
		(start 132.922264 -57.19445)
		(end 132.846064 -57.11825)
		(width 0.1905)
		(layer "In9.Cu")
		(net "M_A_MA10")
	)
	(segment
		(start 135.52805 -57.88025)
		(end 135.14705 -57.49925)
		(width 0.1905)
		(layer "In9.Cu")
		(net "M_A_MA10")
	)
	(segment
		(start 125.81001 -57.7977)
		(end 125.64491 -57.6326)
		(width 0.1905)
		(layer "In9.Cu")
		(net "M_A_MA10")
	)
	(segment
		(start 122.73661 -57.7977)
		(end 122.59691 -57.658)
		(width 0.1905)
		(layer "In9.Cu")
		(net "M_A_MA10")
	)
	(segment
		(start 108.0262 -55.3466)
		(end 107.8738 -55.1942)
		(width 0.1016)
		(layer "In9.Cu")
		(net "M_A_MA10")
	)
	(segment
		(start 151.993092 -66.090546)
		(end 152.1206 -65.963038)
		(width 0.1905)
		(layer "In9.Cu")
		(net "M_A_MA10")
	)
	(segment
		(start 125.64491 -57.30875)
		(end 125.45441 -57.11825)
		(width 0.1905)
		(layer "In9.Cu")
		(net "M_A_MA10")
	)
	(segment
		(start 107.481624 -57.3786)
		(end 107.481624 -56.206644)
		(width 0.1016)
		(layer "In9.Cu")
		(net "M_A_MA10")
	)
	(segment
		(start 127.93091 -57.6326)
		(end 127.76581 -57.7977)
		(width 0.1905)
		(layer "In9.Cu")
		(net "M_A_MA10")
	)
	(segment
		(start 107.634024 -57.531)
		(end 107.481624 -57.3786)
		(width 0.1016)
		(layer "In9.Cu")
		(net "M_A_MA10")
	)
	(segment
		(start 124.28601 -57.7977)
		(end 124.12091 -57.6326)
		(width 0.1905)
		(layer "In9.Cu")
		(net "M_A_MA10")
	)
	(segment
		(start 123.21921 -57.7977)
		(end 122.73661 -57.7977)
		(width 0.1905)
		(layer "In9.Cu")
		(net "M_A_MA10")
	)
	(segment
		(start 109.0422 -56.896)
		(end 108.8898 -56.7436)
		(width 0.1016)
		(layer "In9.Cu")
		(net "M_A_MA10")
	)
	(segment
		(start 127.76581 -57.7977)
		(end 127.33401 -57.7977)
		(width 0.1905)
		(layer "In9.Cu")
		(net "M_A_MA10")
	)
	(segment
		(start 108.0262 -56.896)
		(end 108.0262 -57.3786)
		(width 0.1016)
		(layer "In9.Cu")
		(net "M_A_MA10")
	)
	(segment
		(start 133.286754 -57.55894)
		(end 133.286754 -57.558686)
		(width 0.1905)
		(layer "In9.Cu")
		(net "M_A_MA10")
	)
	(segment
		(start 135.24992 -9.897364)
		(end 135.24992 -9.064498)
		(width 0.1778)
		(layer "F.Cu")
		(net "M_B_DQ9")
	)
	(segment
		(start 134.833868 -8.648446)
		(end 134.833868 -8.205216)
		(width 0.1778)
		(layer "F.Cu")
		(net "M_B_DQ9")
	)
	(segment
		(start 95.9104 -21.6662)
		(end 95.9104 -24.893016)
		(width 0.1016)
		(layer "F.Cu")
		(net "M_B_DQ9")
	)
	(segment
		(start 135.24992 -9.064498)
		(end 134.833868 -8.648446)
		(width 0.1778)
		(layer "F.Cu")
		(net "M_B_DQ9")
	)
	(segment
		(start 95.4532 -21.209)
		(end 95.9104 -21.6662)
		(width 0.1016)
		(layer "F.Cu")
		(net "M_B_DQ9")
	)
	(segment
		(start 135.214106 -7.824978)
		(end 135.2169 -7.824978)
		(width 0.1778)
		(layer "F.Cu")
		(net "M_B_DQ9")
	)
	(segment
		(start 96.639888 -25.622504)
		(end 96.639888 -25.875488)
		(width 0.1016)
		(layer "F.Cu")
		(net "M_B_DQ9")
	)
	(segment
		(start 97.135188 -26.370788)
		(end 97.135188 -26.952194)
		(width 0.1016)
		(layer "F.Cu")
		(net "M_B_DQ9")
	)
	(segment
		(start 134.833868 -8.205216)
		(end 135.214106 -7.824978)
		(width 0.1778)
		(layer "F.Cu")
		(net "M_B_DQ9")
	)
	(segment
		(start 95.9104 -24.893016)
		(end 96.639888 -25.622504)
		(width 0.1016)
		(layer "F.Cu")
		(net "M_B_DQ9")
	)
	(segment
		(start 96.639888 -25.875488)
		(end 97.135188 -26.370788)
		(width 0.1016)
		(layer "F.Cu")
		(net "M_B_DQ9")
	)
	(via
		(at 95.4532 -21.209)
		(size 0.4318)
		(drill 0.2032)
		(layers "F.Cu" "B.Cu")
		(net "M_B_DQ9")
	)
	(via
		(at 135.2169 -7.824978)
		(size 0.4318)
		(drill 0.2032)
		(layers "F.Cu" "B.Cu")
		(net "M_B_DQ9")
	)
	(segment
		(start 134.833868 -8.52551)
		(end 134.833868 -8.205216)
		(width 0.1778)
		(layer "B.Cu")
		(net "M_B_DQ9")
	)
	(segment
		(start 135.214106 -7.824978)
		(end 135.2169 -7.824978)
		(width 0.1778)
		(layer "B.Cu")
		(net "M_B_DQ9")
	)
	(segment
		(start 134.833868 -8.205216)
		(end 135.214106 -7.824978)
		(width 0.1778)
		(layer "B.Cu")
		(net "M_B_DQ9")
	)
	(segment
		(start 134.349998 -9.00938)
		(end 134.833868 -8.52551)
		(width 0.1778)
		(layer "B.Cu")
		(net "M_B_DQ9")
	)
	(segment
		(start 134.349998 -9.89076)
		(end 134.349998 -9.00938)
		(width 0.1778)
		(layer "B.Cu")
		(net "M_B_DQ9")
	)
	(segment
		(start 114.682778 -13.0556)
		(end 114.835178 -12.9032)
		(width 0.1524)
		(layer "In2.Cu")
		(net "M_B_DQ9")
	)
	(segment
		(start 111.202978 -12.9032)
		(end 111.507778 -12.9032)
		(width 0.1524)
		(layer "In2.Cu")
		(net "M_B_DQ9")
	)
	(segment
		(start 113.946178 -12.9032)
		(end 114.098578 -13.0556)
		(width 0.1524)
		(layer "In2.Cu")
		(net "M_B_DQ9")
	)
	(segment
		(start 111.507778 -12.9032)
		(end 111.660178 -13.0556)
		(width 0.1524)
		(layer "In2.Cu")
		(net "M_B_DQ9")
	)
	(segment
		(start 114.098578 -13.9192)
		(end 114.250978 -14.0716)
		(width 0.1524)
		(layer "In2.Cu")
		(net "M_B_DQ9")
	)
	(segment
		(start 111.812578 -14.097)
		(end 112.117378 -14.097)
		(width 0.1524)
		(layer "In2.Cu")
		(net "M_B_DQ9")
	)
	(segment
		(start 113.336578 -14.1224)
		(end 113.488978 -13.97)
		(width 0.1524)
		(layer "In2.Cu")
		(net "M_B_DQ9")
	)
	(segment
		(start 99.473004 -16.612108)
		(end 106.415078 -16.612108)
		(width 0.1524)
		(layer "In2.Cu")
		(net "M_B_DQ9")
	)
	(segment
		(start 135.214106 -7.824978)
		(end 135.2169 -7.824978)
		(width 0.1524)
		(layer "In2.Cu")
		(net "M_B_DQ9")
	)
	(segment
		(start 113.488978 -13.97)
		(end 113.488978 -13.0556)
		(width 0.1524)
		(layer "In2.Cu")
		(net "M_B_DQ9")
	)
	(segment
		(start 134.846568 -9.298432)
		(end 134.846568 -8.192516)
		(width 0.1524)
		(layer "In2.Cu")
		(net "M_B_DQ9")
	)
	(segment
		(start 112.422178 -12.9032)
		(end 112.726978 -12.9032)
		(width 0.1524)
		(layer "In2.Cu")
		(net "M_B_DQ9")
	)
	(segment
		(start 111.660178 -13.9446)
		(end 111.812578 -14.097)
		(width 0.1524)
		(layer "In2.Cu")
		(net "M_B_DQ9")
	)
	(segment
		(start 114.682778 -13.9192)
		(end 114.682778 -13.0556)
		(width 0.1524)
		(layer "In2.Cu")
		(net "M_B_DQ9")
	)
	(segment
		(start 112.269778 -13.0556)
		(end 112.422178 -12.9032)
		(width 0.1524)
		(layer "In2.Cu")
		(net "M_B_DQ9")
	)
	(segment
		(start 113.641378 -12.9032)
		(end 113.946178 -12.9032)
		(width 0.1524)
		(layer "In2.Cu")
		(net "M_B_DQ9")
	)
	(segment
		(start 110.898178 -14.3002)
		(end 111.050578 -14.1478)
		(width 0.1524)
		(layer "In2.Cu")
		(net "M_B_DQ9")
	)
	(segment
		(start 111.050578 -13.0556)
		(end 111.202978 -12.9032)
		(width 0.1524)
		(layer "In2.Cu")
		(net "M_B_DQ9")
	)
	(segment
		(start 114.530378 -14.0716)
		(end 114.682778 -13.9192)
		(width 0.1524)
		(layer "In2.Cu")
		(net "M_B_DQ9")
	)
	(segment
		(start 112.726978 -12.9032)
		(end 112.879378 -13.0556)
		(width 0.1524)
		(layer "In2.Cu")
		(net "M_B_DQ9")
	)
	(segment
		(start 114.250978 -14.0716)
		(end 114.530378 -14.0716)
		(width 0.1524)
		(layer "In2.Cu")
		(net "M_B_DQ9")
	)
	(segment
		(start 112.117378 -14.097)
		(end 112.269778 -13.9446)
		(width 0.1524)
		(layer "In2.Cu")
		(net "M_B_DQ9")
	)
	(segment
		(start 112.269778 -13.9446)
		(end 112.269778 -13.0556)
		(width 0.1524)
		(layer "In2.Cu")
		(net "M_B_DQ9")
	)
	(segment
		(start 108.726986 -14.3002)
		(end 110.898178 -14.3002)
		(width 0.1524)
		(layer "In2.Cu")
		(net "M_B_DQ9")
	)
	(segment
		(start 113.031778 -14.1224)
		(end 113.336578 -14.1224)
		(width 0.1524)
		(layer "In2.Cu")
		(net "M_B_DQ9")
	)
	(segment
		(start 114.098578 -13.0556)
		(end 114.098578 -13.9192)
		(width 0.1524)
		(layer "In2.Cu")
		(net "M_B_DQ9")
	)
	(segment
		(start 106.415078 -16.612108)
		(end 108.726986 -14.3002)
		(width 0.1524)
		(layer "In2.Cu")
		(net "M_B_DQ9")
	)
	(segment
		(start 111.660178 -13.0556)
		(end 111.660178 -13.9446)
		(width 0.1524)
		(layer "In2.Cu")
		(net "M_B_DQ9")
	)
	(segment
		(start 111.050578 -14.1478)
		(end 111.050578 -13.0556)
		(width 0.1524)
		(layer "In2.Cu")
		(net "M_B_DQ9")
	)
	(segment
		(start 95.4532 -20.631912)
		(end 99.473004 -16.612108)
		(width 0.1524)
		(layer "In2.Cu")
		(net "M_B_DQ9")
	)
	(segment
		(start 114.835178 -12.9032)
		(end 133.0706 -12.9032)
		(width 0.1524)
		(layer "In2.Cu")
		(net "M_B_DQ9")
	)
	(segment
		(start 113.488978 -13.0556)
		(end 113.641378 -12.9032)
		(width 0.1524)
		(layer "In2.Cu")
		(net "M_B_DQ9")
	)
	(segment
		(start 133.0706 -12.9032)
		(end 133.6294 -12.3444)
		(width 0.1524)
		(layer "In2.Cu")
		(net "M_B_DQ9")
	)
	(segment
		(start 133.6294 -12.3444)
		(end 133.6294 -10.5156)
		(width 0.1524)
		(layer "In2.Cu")
		(net "M_B_DQ9")
	)
	(segment
		(start 133.6294 -10.5156)
		(end 134.846568 -9.298432)
		(width 0.1524)
		(layer "In2.Cu")
		(net "M_B_DQ9")
	)
	(segment
		(start 112.879378 -13.97)
		(end 113.031778 -14.1224)
		(width 0.1524)
		(layer "In2.Cu")
		(net "M_B_DQ9")
	)
	(segment
		(start 134.846568 -8.192516)
		(end 135.214106 -7.824978)
		(width 0.1524)
		(layer "In2.Cu")
		(net "M_B_DQ9")
	)
	(segment
		(start 112.879378 -13.0556)
		(end 112.879378 -13.97)
		(width 0.1524)
		(layer "In2.Cu")
		(net "M_B_DQ9")
	)
	(segment
		(start 95.4532 -21.209)
		(end 95.4532 -20.631912)
		(width 0.1524)
		(layer "In2.Cu")
		(net "M_B_DQ9")
	)
	(segment
		(start 186.182 -50.17135)
		(end 187.12815 -50.17135)
		(width 0.254)
		(layer "F.Cu")
		(net "PV_VDDR_VREF_RW")
	)
	(segment
		(start 186.182 -50.17135)
		(end 185.09996 -50.17135)
		(width 0.254)
		(layer "F.Cu")
		(net "PV_VDDR_VREF_RW")
	)
	(segment
		(start 186.95924 -48.91024)
		(end 186.26328 -48.91024)
		(width 0.254)
		(layer "F.Cu")
		(net "PV_VDDR_VREF_RW")
	)
	(segment
		(start 188.087 -50.2412)
		(end 187.198 -50.2412)
		(width 0.254)
		(layer "F.Cu")
		(net "PV_VDDR_VREF_RW")
	)
	(segment
		(start 187.198 -49.149)
		(end 186.95924 -48.91024)
		(width 0.254)
		(layer "F.Cu")
		(net "PV_VDDR_VREF_RW")
	)
	(segment
		(start 187.12815 -50.17135)
		(end 187.198 -50.2412)
		(width 0.254)
		(layer "F.Cu")
		(net "PV_VDDR_VREF_RW")
	)
	(segment
		(start 185.99531 -48.91024)
		(end 186.26328 -48.91024)
		(width 0.254)
		(layer "F.Cu")
		(net "PV_VDDR_VREF_RW")
	)
	(segment
		(start 187.198 -50.2412)
		(end 187.198 -49.149)
		(width 0.254)
		(layer "F.Cu")
		(net "PV_VDDR_VREF_RW")
	)
	(segment
		(start 185.09996 -48.26)
		(end 185.34507 -48.26)
		(width 0.254)
		(layer "F.Cu")
		(net "PV_VDDR_VREF_RW")
	)
	(segment
		(start 185.34507 -48.26)
		(end 185.99531 -48.91024)
		(width 0.254)
		(layer "F.Cu")
		(net "PV_VDDR_VREF_RW")
	)
	(via
		(at 186.182 -50.17135)
		(size 0.7112)
		(drill 0.3556)
		(layers "F.Cu" "B.Cu")
		(net "PV_VDDR_VREF_RW")
	)
	(segment
		(start 174.250096 -63.892938)
		(end 174.087028 -64.056006)
		(width 0.1778)
		(layer "F.Cu")
		(net "M_A_DQ24")
	)
	(segment
		(start 111.027718 -41.708324)
		(end 110.749588 -41.986454)
		(width 0.1016)
		(layer "F.Cu")
		(net "M_A_DQ24")
	)
	(segment
		(start 112.294924 -41.708324)
		(end 111.027718 -41.708324)
		(width 0.1016)
		(layer "F.Cu")
		(net "M_A_DQ24")
	)
	(segment
		(start 174.250096 -62.59322)
		(end 174.250096 -63.892938)
		(width 0.1778)
		(layer "F.Cu")
		(net "M_A_DQ24")
	)
	(segment
		(start 114.554 -43.4594)
		(end 114.046 -43.4594)
		(width 0.1016)
		(layer "F.Cu")
		(net "M_A_DQ24")
	)
	(segment
		(start 174.087028 -64.056006)
		(end 174.087028 -64.0588)
		(width 0.1778)
		(layer "F.Cu")
		(net "M_A_DQ24")
	)
	(segment
		(start 114.046 -43.4594)
		(end 112.294924 -41.708324)
		(width 0.1016)
		(layer "F.Cu")
		(net "M_A_DQ24")
	)
	(via
		(at 114.554 -43.4594)
		(size 0.4318)
		(drill 0.2032)
		(layers "F.Cu" "B.Cu")
		(net "M_A_DQ24")
	)
	(via
		(at 174.087028 -64.0588)
		(size 0.4318)
		(drill 0.2032)
		(layers "F.Cu" "B.Cu")
		(net "M_A_DQ24")
	)
	(segment
		(start 174.0154 -63.984632)
		(end 174.0154 -63.987172)
		(width 0.1778)
		(layer "B.Cu")
		(net "M_A_DQ24")
	)
	(segment
		(start 173.950122 -62.599824)
		(end 173.950122 -63.9191)
		(width 0.1778)
		(layer "B.Cu")
		(net "M_A_DQ24")
	)
	(segment
		(start 174.0154 -63.987172)
		(end 174.087028 -64.0588)
		(width 0.1778)
		(layer "B.Cu")
		(net "M_A_DQ24")
	)
	(segment
		(start 173.950122 -63.9191)
		(end 174.0154 -63.984632)
		(width 0.1778)
		(layer "B.Cu")
		(net "M_A_DQ24")
	)
	(segment
		(start 172.384212 -56.275224)
		(end 172.384212 -56.059832)
		(width 0.1524)
		(layer "In2.Cu")
		(net "M_A_DQ24")
	)
	(segment
		(start 170.659044 -54.334664)
		(end 171.101258 -53.892704)
		(width 0.1524)
		(layer "In2.Cu")
		(net "M_A_DQ24")
	)
	(segment
		(start 170.4467 -52.2351)
		(end 170.4467 -51.8033)
		(width 0.1524)
		(layer "In2.Cu")
		(net "M_A_DQ24")
	)
	(segment
		(start 173.246796 -56.922416)
		(end 173.68901 -56.480456)
		(width 0.1524)
		(layer "In2.Cu")
		(net "M_A_DQ24")
	)
	(segment
		(start 172.600112 -56.491124)
		(end 172.384212 -56.275224)
		(width 0.1524)
		(layer "In2.Cu")
		(net "M_A_DQ24")
	)
	(segment
		(start 115.0112 -43.0022)
		(end 114.554 -43.4594)
		(width 0.1016)
		(layer "In2.Cu")
		(net "M_A_DQ24")
	)
	(segment
		(start 172.826426 -55.40248)
		(end 172.610526 -55.18658)
		(width 0.1524)
		(layer "In2.Cu")
		(net "M_A_DQ24")
	)
	(segment
		(start 171.737528 -55.62854)
		(end 171.521628 -55.41264)
		(width 0.1524)
		(layer "In2.Cu")
		(net "M_A_DQ24")
	)
	(segment
		(start 171.95292 -55.62854)
		(end 171.737528 -55.62854)
		(width 0.1524)
		(layer "In2.Cu")
		(net "M_A_DQ24")
	)
	(segment
		(start 171.101258 -53.677312)
		(end 170.885358 -53.461412)
		(width 0.1524)
		(layer "In2.Cu")
		(net "M_A_DQ24")
	)
	(segment
		(start 171.963842 -54.755288)
		(end 171.963842 -54.539896)
		(width 0.1524)
		(layer "In2.Cu")
		(net "M_A_DQ24")
	)
	(segment
		(start 170.874944 -54.765956)
		(end 170.659044 -54.550056)
		(width 0.1524)
		(layer "In2.Cu")
		(net "M_A_DQ24")
	)
	(segment
		(start 170.885358 -53.461412)
		(end 170.669966 -53.461412)
		(width 0.1524)
		(layer "In2.Cu")
		(net "M_A_DQ24")
	)
	(segment
		(start 175.29048 -59.181492)
		(end 173.246796 -57.137808)
		(width 0.1524)
		(layer "In2.Cu")
		(net "M_A_DQ24")
	)
	(segment
		(start 171.53255 -54.323996)
		(end 171.090336 -54.765956)
		(width 0.1524)
		(layer "In2.Cu")
		(net "M_A_DQ24")
	)
	(segment
		(start 173.257718 -56.049164)
		(end 172.815504 -56.491124)
		(width 0.1524)
		(layer "In2.Cu")
		(net "M_A_DQ24")
	)
	(segment
		(start 173.246796 -57.137808)
		(end 173.246796 -56.922416)
		(width 0.1524)
		(layer "In2.Cu")
		(net "M_A_DQ24")
	)
	(segment
		(start 170.669966 -53.461412)
		(end 170.227752 -53.903372)
		(width 0.1524)
		(layer "In2.Cu")
		(net "M_A_DQ24")
	)
	(segment
		(start 175.29048 -62.7634)
		(end 175.29048 -59.181492)
		(width 0.1524)
		(layer "In2.Cu")
		(net "M_A_DQ24")
	)
	(segment
		(start 171.521628 -55.197248)
		(end 171.963842 -54.755288)
		(width 0.1524)
		(layer "In2.Cu")
		(net "M_A_DQ24")
	)
	(segment
		(start 166.066978 -47.423578)
		(end 166.066978 -46.231302)
		(width 0.1524)
		(layer "In2.Cu")
		(net "M_A_DQ24")
	)
	(segment
		(start 171.521628 -55.41264)
		(end 171.521628 -55.197248)
		(width 0.1524)
		(layer "In2.Cu")
		(net "M_A_DQ24")
	)
	(segment
		(start 170.227752 -53.903372)
		(end 170.01236 -53.903372)
		(width 0.1524)
		(layer "In2.Cu")
		(net "M_A_DQ24")
	)
	(segment
		(start 170.659044 -54.550056)
		(end 170.659044 -54.334664)
		(width 0.1524)
		(layer "In2.Cu")
		(net "M_A_DQ24")
	)
	(segment
		(start 170.4467 -51.8033)
		(end 166.066978 -47.423578)
		(width 0.1524)
		(layer "In2.Cu")
		(net "M_A_DQ24")
	)
	(segment
		(start 175.13808 -62.9158)
		(end 175.29048 -62.7634)
		(width 0.1524)
		(layer "In2.Cu")
		(net "M_A_DQ24")
	)
	(segment
		(start 172.395134 -55.18658)
		(end 171.95292 -55.62854)
		(width 0.1524)
		(layer "In2.Cu")
		(net "M_A_DQ24")
	)
	(segment
		(start 172.610526 -55.18658)
		(end 172.395134 -55.18658)
		(width 0.1524)
		(layer "In2.Cu")
		(net "M_A_DQ24")
	)
	(segment
		(start 166.066978 -46.231302)
		(end 162.075876 -42.2402)
		(width 0.1524)
		(layer "In2.Cu")
		(net "M_A_DQ24")
	)
	(segment
		(start 171.963842 -54.539896)
		(end 171.747942 -54.323996)
		(width 0.1524)
		(layer "In2.Cu")
		(net "M_A_DQ24")
	)
	(segment
		(start 171.101258 -53.892704)
		(end 171.101258 -53.677312)
		(width 0.1524)
		(layer "In2.Cu")
		(net "M_A_DQ24")
	)
	(segment
		(start 171.090336 -54.765956)
		(end 170.874944 -54.765956)
		(width 0.1524)
		(layer "In2.Cu")
		(net "M_A_DQ24")
	)
	(segment
		(start 172.384212 -56.059832)
		(end 172.826426 -55.617872)
		(width 0.1524)
		(layer "In2.Cu")
		(net "M_A_DQ24")
	)
	(segment
		(start 169.598594 -53.489606)
		(end 169.598594 -53.083206)
		(width 0.1524)
		(layer "In2.Cu")
		(net "M_A_DQ24")
	)
	(segment
		(start 174.371 -62.9158)
		(end 175.13808 -62.9158)
		(width 0.1524)
		(layer "In2.Cu")
		(net "M_A_DQ24")
	)
	(segment
		(start 118.4148 -42.2402)
		(end 117.6528 -43.0022)
		(width 0.1016)
		(layer "In2.Cu")
		(net "M_A_DQ24")
	)
	(segment
		(start 169.598594 -53.083206)
		(end 170.4467 -52.2351)
		(width 0.1524)
		(layer "In2.Cu")
		(net "M_A_DQ24")
	)
	(segment
		(start 172.815504 -56.491124)
		(end 172.600112 -56.491124)
		(width 0.1524)
		(layer "In2.Cu")
		(net "M_A_DQ24")
	)
	(segment
		(start 173.68901 -56.480456)
		(end 173.68901 -56.265064)
		(width 0.1524)
		(layer "In2.Cu")
		(net "M_A_DQ24")
	)
	(segment
		(start 172.826426 -55.617872)
		(end 172.826426 -55.40248)
		(width 0.1524)
		(layer "In2.Cu")
		(net "M_A_DQ24")
	)
	(segment
		(start 174.2186 -63.0682)
		(end 174.371 -62.9158)
		(width 0.1524)
		(layer "In2.Cu")
		(net "M_A_DQ24")
	)
	(segment
		(start 174.2186 -63.927228)
		(end 174.2186 -63.0682)
		(width 0.1524)
		(layer "In2.Cu")
		(net "M_A_DQ24")
	)
	(segment
		(start 162.075876 -42.2402)
		(end 118.4148 -42.2402)
		(width 0.1524)
		(layer "In2.Cu")
		(net "M_A_DQ24")
	)
	(segment
		(start 174.087028 -64.0588)
		(end 174.2186 -63.927228)
		(width 0.1524)
		(layer "In2.Cu")
		(net "M_A_DQ24")
	)
	(segment
		(start 173.68901 -56.265064)
		(end 173.47311 -56.049164)
		(width 0.1524)
		(layer "In2.Cu")
		(net "M_A_DQ24")
	)
	(segment
		(start 170.01236 -53.903372)
		(end 169.598594 -53.489606)
		(width 0.1524)
		(layer "In2.Cu")
		(net "M_A_DQ24")
	)
	(segment
		(start 171.747942 -54.323996)
		(end 171.53255 -54.323996)
		(width 0.1524)
		(layer "In2.Cu")
		(net "M_A_DQ24")
	)
	(segment
		(start 173.47311 -56.049164)
		(end 173.257718 -56.049164)
		(width 0.1524)
		(layer "In2.Cu")
		(net "M_A_DQ24")
	)
	(segment
		(start 117.6528 -43.0022)
		(end 115.0112 -43.0022)
		(width 0.1016)
		(layer "In2.Cu")
		(net "M_A_DQ24")
	)
	(segment
		(start 158.364428 -3.992372)
		(end 158.364428 -5.069078)
		(width 0.2413)
		(layer "F.Cu")
		(net "M_B_MA12")
	)
	(segment
		(start 158.99765 -3.35915)
		(end 158.364428 -3.992372)
		(width 0.2413)
		(layer "F.Cu")
		(net "M_B_MA12")
	)
	(segment
		(start 101.0031 -29.337)
		(end 100.968302 -29.302202)
		(width 0.1016)
		(layer "F.Cu")
		(net "M_B_MA12")
	)
	(segment
		(start 100.739956 -29.302202)
		(end 100.292408 -28.854654)
		(width 0.1016)
		(layer "F.Cu")
		(net "M_B_MA12")
	)
	(segment
		(start 158.99765 -2.943098)
		(end 158.99765 -3.35915)
		(width 0.2413)
		(layer "F.Cu")
		(net "M_B_MA12")
	)
	(segment
		(start 158.364428 -5.069078)
		(end 158.377128 -5.081778)
		(width 0.2413)
		(layer "F.Cu")
		(net "M_B_MA12")
	)
	(segment
		(start 100.968302 -29.302202)
		(end 100.739956 -29.302202)
		(width 0.1016)
		(layer "F.Cu")
		(net "M_B_MA12")
	)
	(segment
		(start 158.949898 -2.895346)
		(end 158.99765 -2.943098)
		(width 0.2413)
		(layer "F.Cu")
		(net "M_B_MA12")
	)
	(segment
		(start 158.949898 -1.68402)
		(end 158.949898 -2.895346)
		(width 0.2413)
		(layer "F.Cu")
		(net "M_B_MA12")
	)
	(via
		(at 101.0031 -29.337)
		(size 0.4318)
		(drill 0.2032)
		(layers "F.Cu" "B.Cu")
		(net "M_B_MA12")
	)
	(via
		(at 158.377128 -5.081778)
		(size 0.4318)
		(drill 0.2032)
		(layers "F.Cu" "B.Cu")
		(net "M_B_MA12")
	)
	(segment
		(start 157.88767 -5.533898)
		(end 158.33979 -5.081778)
		(width 0.2413)
		(layer "B.Cu")
		(net "M_B_MA12")
	)
	(segment
		(start 157.88767 -6.937248)
		(end 157.88767 -5.533898)
		(width 0.2413)
		(layer "B.Cu")
		(net "M_B_MA12")
	)
	(segment
		(start 158.33979 -5.081778)
		(end 158.377128 -5.081778)
		(width 0.2413)
		(layer "B.Cu")
		(net "M_B_MA12")
	)
	(segment
		(start 158.949898 -9.89076)
		(end 158.949898 -8.711438)
		(width 0.2413)
		(layer "B.Cu")
		(net "M_B_MA12")
	)
	(segment
		(start 158.949898 -8.711438)
		(end 159.02305 -8.638286)
		(width 0.2413)
		(layer "B.Cu")
		(net "M_B_MA12")
	)
	(segment
		(start 159.02305 -8.072628)
		(end 157.88767 -6.937248)
		(width 0.2413)
		(layer "B.Cu")
		(net "M_B_MA12")
	)
	(segment
		(start 159.02305 -8.638286)
		(end 159.02305 -8.072628)
		(width 0.2413)
		(layer "B.Cu")
		(net "M_B_MA12")
	)
	(segment
		(start 156.718 -9.440672)
		(end 152.713436 -13.445236)
		(width 0.1905)
		(layer "In7.Cu")
		(net "M_B_MA12")
	)
	(segment
		(start 144.0688 -17.4498)
		(end 144.0688 -16.1798)
		(width 0.1905)
		(layer "In7.Cu")
		(net "M_B_MA12")
	)
	(segment
		(start 145.53438 -17.195546)
		(end 145.013426 -17.7165)
		(width 0.1905)
		(layer "In7.Cu")
		(net "M_B_MA12")
	)
	(segment
		(start 101.0031 -29.337)
		(end 101.1047 -29.2354)
		(width 0.1016)
		(layer "In7.Cu")
		(net "M_B_MA12")
	)
	(segment
		(start 102.0064 -26.3144)
		(end 103.8606 -26.3144)
		(width 0.1016)
		(layer "In7.Cu")
		(net "M_B_MA12")
	)
	(segment
		(start 158.377128 -5.081778)
		(end 158.375604 -5.081778)
		(width 0.1905)
		(layer "In7.Cu")
		(net "M_B_MA12")
	)
	(segment
		(start 104.4194 -25.273)
		(end 104.8258 -24.8666)
		(width 0.1016)
		(layer "In7.Cu")
		(net "M_B_MA12")
	)
	(segment
		(start 143.8656 -15.9766)
		(end 138.303 -15.9766)
		(width 0.1905)
		(layer "In7.Cu")
		(net "M_B_MA12")
	)
	(segment
		(start 138.303 -15.9766)
		(end 138.0998 -16.1798)
		(width 0.1905)
		(layer "In7.Cu")
		(net "M_B_MA12")
	)
	(segment
		(start 157.91307 -5.544312)
		(end 157.91307 -6.477508)
		(width 0.1905)
		(layer "In7.Cu")
		(net "M_B_MA12")
	)
	(segment
		(start 101.1047 -27.2161)
		(end 102.0064 -26.3144)
		(width 0.1016)
		(layer "In7.Cu")
		(net "M_B_MA12")
	)
	(segment
		(start 152.713436 -13.445236)
		(end 148.96338 -17.195546)
		(width 0.1905)
		(layer "In7.Cu")
		(net "M_B_MA12")
	)
	(segment
		(start 138.0998 -17.005046)
		(end 137.9093 -17.195546)
		(width 0.1905)
		(layer "In7.Cu")
		(net "M_B_MA12")
	)
	(segment
		(start 148.96338 -17.195546)
		(end 145.53438 -17.195546)
		(width 0.1905)
		(layer "In7.Cu")
		(net "M_B_MA12")
	)
	(segment
		(start 115.560094 -17.195546)
		(end 110.98784 -21.7678)
		(width 0.1905)
		(layer "In7.Cu")
		(net "M_B_MA12")
	)
	(segment
		(start 157.91307 -6.477508)
		(end 156.718 -7.672578)
		(width 0.1905)
		(layer "In7.Cu")
		(net "M_B_MA12")
	)
	(segment
		(start 101.1047 -29.2354)
		(end 101.1047 -27.2161)
		(width 0.1016)
		(layer "In7.Cu")
		(net "M_B_MA12")
	)
	(segment
		(start 145.013426 -17.7165)
		(end 144.3355 -17.7165)
		(width 0.1905)
		(layer "In7.Cu")
		(net "M_B_MA12")
	)
	(segment
		(start 110.98784 -21.7678)
		(end 105.8926 -21.7678)
		(width 0.1905)
		(layer "In7.Cu")
		(net "M_B_MA12")
	)
	(segment
		(start 104.8258 -24.8666)
		(end 104.8258 -22.8346)
		(width 0.1016)
		(layer "In7.Cu")
		(net "M_B_MA12")
	)
	(segment
		(start 158.375604 -5.081778)
		(end 157.91307 -5.544312)
		(width 0.1905)
		(layer "In7.Cu")
		(net "M_B_MA12")
	)
	(segment
		(start 104.8258 -22.8346)
		(end 105.8926 -21.7678)
		(width 0.1016)
		(layer "In7.Cu")
		(net "M_B_MA12")
	)
	(segment
		(start 104.4194 -25.7556)
		(end 104.4194 -25.273)
		(width 0.1016)
		(layer "In7.Cu")
		(net "M_B_MA12")
	)
	(segment
		(start 144.3355 -17.7165)
		(end 144.0688 -17.4498)
		(width 0.1905)
		(layer "In7.Cu")
		(net "M_B_MA12")
	)
	(segment
		(start 156.718 -7.672578)
		(end 156.718 -9.440672)
		(width 0.1905)
		(layer "In7.Cu")
		(net "M_B_MA12")
	)
	(segment
		(start 137.9093 -17.195546)
		(end 115.560094 -17.195546)
		(width 0.1905)
		(layer "In7.Cu")
		(net "M_B_MA12")
	)
	(segment
		(start 138.0998 -16.1798)
		(end 138.0998 -17.005046)
		(width 0.1905)
		(layer "In7.Cu")
		(net "M_B_MA12")
	)
	(segment
		(start 103.8606 -26.3144)
		(end 104.4194 -25.7556)
		(width 0.1016)
		(layer "In7.Cu")
		(net "M_B_MA12")
	)
	(segment
		(start 144.0688 -16.1798)
		(end 143.8656 -15.9766)
		(width 0.1905)
		(layer "In7.Cu")
		(net "M_B_MA12")
	)
	(segment
		(start 182.4736 -55.1688)
		(end 182.4736 -54.229)
		(width 0.254)
		(layer "F.Cu")
		(net "PV_VDDR_VREF_A")
	)
	(segment
		(start 183.388 -55.1942)
		(end 182.499 -55.1942)
		(width 0.254)
		(layer "F.Cu")
		(net "PV_VDDR_VREF_A")
	)
	(segment
		(start 182.4736 -54.229)
		(end 182.4736 -53.4162)
		(width 0.254)
		(layer "F.Cu")
		(net "PV_VDDR_VREF_A")
	)
	(segment
		(start 183.388 -54.2798)
		(end 183.388 -55.1942)
		(width 0.254)
		(layer "F.Cu")
		(net "PV_VDDR_VREF_A")
	)
	(segment
		(start 182.4736 -53.4162)
		(end 182.499 -53.3908)
		(width 0.254)
		(layer "F.Cu")
		(net "PV_VDDR_VREF_A")
	)
	(segment
		(start 182.499 -55.1942)
		(end 182.4736 -55.1688)
		(width 0.254)
		(layer "F.Cu")
		(net "PV_VDDR_VREF_A")
	)
	(via
		(at 182.4736 -54.229)
		(size 0.7112)
		(drill 0.3556)
		(layers "F.Cu" "B.Cu")
		(net "PV_VDDR_VREF_A")
	)
	(segment
		(start 181.749954 -1.68402)
		(end 181.749954 -2.402332)
		(width 0.1778)
		(layer "F.Cu")
		(net "M_B_DQS_DN6")
	)
	(segment
		(start 181.749954 -2.402332)
		(end 181.897528 -2.549906)
		(width 0.1778)
		(layer "F.Cu")
		(net "M_B_DQS_DN6")
	)
	(segment
		(start 181.897528 -4.954778)
		(end 181.897528 -5.55371)
		(width 0.1778)
		(layer "F.Cu")
		(net "M_B_DQS_DN6")
	)
	(segment
		(start 181.897528 -2.549906)
		(end 181.897528 -3.87985)
		(width 0.1778)
		(layer "F.Cu")
		(net "M_B_DQS_DN6")
	)
	(segment
		(start 109.195108 -34.996374)
		(end 109.135672 -34.996374)
		(width 0.1016)
		(layer "F.Cu")
		(net "M_B_DQS_DN6")
	)
	(segment
		(start 109.135672 -34.996374)
		(end 108.81106 -35.320986)
		(width 0.1016)
		(layer "F.Cu")
		(net "M_B_DQS_DN6")
	)
	(segment
		(start 181.897528 -5.55371)
		(end 181.63286 -5.818378)
		(width 0.1778)
		(layer "F.Cu")
		(net "M_B_DQS_DN6")
	)
	(segment
		(start 181.737 -4.040378)
		(end 181.737 -4.79425)
		(width 0.1778)
		(layer "F.Cu")
		(net "M_B_DQS_DN6")
	)
	(segment
		(start 181.897528 -3.87985)
		(end 181.737 -4.040378)
		(width 0.1778)
		(layer "F.Cu")
		(net "M_B_DQS_DN6")
	)
	(segment
		(start 181.737 -4.79425)
		(end 181.897528 -4.954778)
		(width 0.1778)
		(layer "F.Cu")
		(net "M_B_DQS_DN6")
	)
	(via
		(at 181.63286 -5.818378)
		(size 0.4318)
		(drill 0.2032)
		(layers "F.Cu" "B.Cu")
		(net "M_B_DQS_DN6")
	)
	(via
		(at 108.81106 -35.320986)
		(size 0.4318)
		(drill 0.2032)
		(layers "F.Cu" "B.Cu")
		(net "M_B_DQS_DN6")
	)
	(segment
		(start 181.9656 -6.151118)
		(end 181.63286 -5.818378)
		(width 0.1778)
		(layer "B.Cu")
		(net "M_B_DQS_DN6")
	)
	(segment
		(start 181.749954 -9.89076)
		(end 181.749954 -8.929624)
		(width 0.1778)
		(layer "B.Cu")
		(net "M_B_DQS_DN6")
	)
	(segment
		(start 181.9656 -7.241286)
		(end 181.9656 -6.151118)
		(width 0.1778)
		(layer "B.Cu")
		(net "M_B_DQS_DN6")
	)
	(segment
		(start 181.699154 -8.878824)
		(end 181.699154 -7.507732)
		(width 0.1778)
		(layer "B.Cu")
		(net "M_B_DQS_DN6")
	)
	(segment
		(start 181.699154 -7.507732)
		(end 181.9656 -7.241286)
		(width 0.1778)
		(layer "B.Cu")
		(net "M_B_DQS_DN6")
	)
	(segment
		(start 181.749954 -8.929624)
		(end 181.699154 -8.878824)
		(width 0.1778)
		(layer "B.Cu")
		(net "M_B_DQS_DN6")
	)
	(segment
		(start 141.9352 -36.714176)
		(end 141.9352 -36.282376)
		(width 0.1524)
		(layer "In9.Cu")
		(net "M_B_DQS_DN6")
	)
	(segment
		(start 109.368336 -35.433)
		(end 109.241336 -35.56)
		(width 0.1016)
		(layer "In9.Cu")
		(net "M_B_DQS_DN6")
	)
	(segment
		(start 136.257284 -36.75634)
		(end 136.381744 -36.8808)
		(width 0.1524)
		(layer "In9.Cu")
		(net "M_B_DQS_DN6")
	)
	(segment
		(start 157.820106 -36.822126)
		(end 178.969924 -15.672308)
		(width 0.1524)
		(layer "In9.Cu")
		(net "M_B_DQS_DN6")
	)
	(segment
		(start 181.3814 -6.935978)
		(end 181.910228 -6.40715)
		(width 0.1524)
		(layer "In9.Cu")
		(net "M_B_DQS_DN6")
	)
	(segment
		(start 135.0772 -36.206176)
		(end 135.0772 -36.739576)
		(width 0.1524)
		(layer "In9.Cu")
		(net "M_B_DQS_DN6")
	)
	(segment
		(start 113.869978 -36.9062)
		(end 131.481576 -36.9062)
		(width 0.1524)
		(layer "In9.Cu")
		(net "M_B_DQS_DN6")
	)
	(segment
		(start 137.420604 -36.75634)
		(end 137.545064 -36.8808)
		(width 0.1524)
		(layer "In9.Cu")
		(net "M_B_DQS_DN6")
	)
	(segment
		(start 149.134576 -35.9664)
		(end 149.210776 -35.8902)
		(width 0.1524)
		(layer "In9.Cu")
		(net "M_B_DQS_DN6")
	)
	(segment
		(start 131.481576 -36.9062)
		(end 132.497576 -35.8902)
		(width 0.1524)
		(layer "In9.Cu")
		(net "M_B_DQS_DN6")
	)
	(segment
		(start 141.9352 -36.282376)
		(end 142.251176 -35.9664)
		(width 0.1524)
		(layer "In9.Cu")
		(net "M_B_DQS_DN6")
	)
	(segment
		(start 154.998674 -35.8902)
		(end 155.9306 -36.822126)
		(width 0.1524)
		(layer "In9.Cu")
		(net "M_B_DQS_DN6")
	)
	(segment
		(start 110.0836 -36.288472)
		(end 110.0836 -35.678872)
		(width 0.1016)
		(layer "In9.Cu")
		(net "M_B_DQS_DN6")
	)
	(segment
		(start 143.7386 -36.7284)
		(end 143.891 -36.8808)
		(width 0.1524)
		(layer "In9.Cu")
		(net "M_B_DQS_DN6")
	)
	(segment
		(start 181.3814 -10.0076)
		(end 181.3814 -6.935978)
		(width 0.1524)
		(layer "In9.Cu")
		(net "M_B_DQS_DN6")
	)
	(segment
		(start 141.768576 -36.8808)
		(end 141.9352 -36.714176)
		(width 0.1524)
		(layer "In9.Cu")
		(net "M_B_DQS_DN6")
	)
	(segment
		(start 178.969924 -12.419076)
		(end 181.3814 -10.0076)
		(width 0.1524)
		(layer "In9.Cu")
		(net "M_B_DQS_DN6")
	)
	(segment
		(start 143.7386 -36.282376)
		(end 143.7386 -36.7284)
		(width 0.1524)
		(layer "In9.Cu")
		(net "M_B_DQS_DN6")
	)
	(segment
		(start 147.204176 -35.9664)
		(end 149.134576 -35.9664)
		(width 0.1524)
		(layer "In9.Cu")
		(net "M_B_DQS_DN6")
	)
	(segment
		(start 155.9306 -36.822126)
		(end 157.820106 -36.822126)
		(width 0.1524)
		(layer "In9.Cu")
		(net "M_B_DQS_DN6")
	)
	(segment
		(start 181.910228 -6.40715)
		(end 181.910228 -6.095746)
		(width 0.1524)
		(layer "In9.Cu")
		(net "M_B_DQS_DN6")
	)
	(segment
		(start 110.269528 -36.4744)
		(end 110.0836 -36.288472)
		(width 0.1016)
		(layer "In9.Cu")
		(net "M_B_DQS_DN6")
	)
	(segment
		(start 136.963404 -36.75634)
		(end 137.420604 -36.75634)
		(width 0.1524)
		(layer "In9.Cu")
		(net "M_B_DQS_DN6")
	)
	(segment
		(start 138.002264 -36.8808)
		(end 138.126724 -36.75634)
		(width 0.1524)
		(layer "In9.Cu")
		(net "M_B_DQS_DN6")
	)
	(segment
		(start 146.7866 -36.663376)
		(end 146.7866 -36.383976)
		(width 0.1524)
		(layer "In9.Cu")
		(net "M_B_DQS_DN6")
	)
	(segment
		(start 149.210776 -35.8902)
		(end 152.439624 -35.8902)
		(width 0.1524)
		(layer "In9.Cu")
		(net "M_B_DQS_DN6")
	)
	(segment
		(start 112.974374 -36.010596)
		(end 113.869978 -36.9062)
		(width 0.1524)
		(layer "In9.Cu")
		(net "M_B_DQS_DN6")
	)
	(segment
		(start 110.907576 -36.449)
		(end 110.882176 -36.4744)
		(width 0.1016)
		(layer "In9.Cu")
		(net "M_B_DQS_DN6")
	)
	(segment
		(start 146.7866 -36.383976)
		(end 147.204176 -35.9664)
		(width 0.1524)
		(layer "In9.Cu")
		(net "M_B_DQS_DN6")
	)
	(segment
		(start 154.265376 -35.8902)
		(end 154.998674 -35.8902)
		(width 0.1524)
		(layer "In9.Cu")
		(net "M_B_DQS_DN6")
	)
	(segment
		(start 135.800084 -36.75634)
		(end 136.257284 -36.75634)
		(width 0.1524)
		(layer "In9.Cu")
		(net "M_B_DQS_DN6")
	)
	(segment
		(start 135.218424 -36.8808)
		(end 135.675624 -36.8808)
		(width 0.1524)
		(layer "In9.Cu")
		(net "M_B_DQS_DN6")
	)
	(segment
		(start 135.675624 -36.8808)
		(end 135.800084 -36.75634)
		(width 0.1524)
		(layer "In9.Cu")
		(net "M_B_DQS_DN6")
	)
	(segment
		(start 143.891 -36.8808)
		(end 146.569176 -36.8808)
		(width 0.1524)
		(layer "In9.Cu")
		(net "M_B_DQS_DN6")
	)
	(segment
		(start 109.241336 -35.56)
		(end 109.050074 -35.56)
		(width 0.1016)
		(layer "In9.Cu")
		(net "M_B_DQS_DN6")
	)
	(segment
		(start 110.882176 -36.4744)
		(end 110.269528 -36.4744)
		(width 0.1016)
		(layer "In9.Cu")
		(net "M_B_DQS_DN6")
	)
	(segment
		(start 137.545064 -36.8808)
		(end 138.002264 -36.8808)
		(width 0.1524)
		(layer "In9.Cu")
		(net "M_B_DQS_DN6")
	)
	(segment
		(start 109.837728 -35.433)
		(end 109.368336 -35.433)
		(width 0.1016)
		(layer "In9.Cu")
		(net "M_B_DQS_DN6")
	)
	(segment
		(start 110.907576 -36.449)
		(end 111.34598 -36.010596)
		(width 0.1524)
		(layer "In9.Cu")
		(net "M_B_DQS_DN6")
	)
	(segment
		(start 146.569176 -36.8808)
		(end 146.7866 -36.663376)
		(width 0.1524)
		(layer "In9.Cu")
		(net "M_B_DQS_DN6")
	)
	(segment
		(start 138.708384 -36.8808)
		(end 141.768576 -36.8808)
		(width 0.1524)
		(layer "In9.Cu")
		(net "M_B_DQS_DN6")
	)
	(segment
		(start 152.439624 -35.8902)
		(end 152.820624 -36.2712)
		(width 0.1524)
		(layer "In9.Cu")
		(net "M_B_DQS_DN6")
	)
	(segment
		(start 110.0836 -35.678872)
		(end 109.837728 -35.433)
		(width 0.1016)
		(layer "In9.Cu")
		(net "M_B_DQS_DN6")
	)
	(segment
		(start 152.820624 -36.2712)
		(end 153.884376 -36.2712)
		(width 0.1524)
		(layer "In9.Cu")
		(net "M_B_DQS_DN6")
	)
	(segment
		(start 143.422624 -35.9664)
		(end 143.7386 -36.282376)
		(width 0.1524)
		(layer "In9.Cu")
		(net "M_B_DQS_DN6")
	)
	(segment
		(start 181.910228 -6.095746)
		(end 181.63286 -5.818378)
		(width 0.1524)
		(layer "In9.Cu")
		(net "M_B_DQS_DN6")
	)
	(segment
		(start 111.34598 -36.010596)
		(end 112.974374 -36.010596)
		(width 0.1524)
		(layer "In9.Cu")
		(net "M_B_DQS_DN6")
	)
	(segment
		(start 142.251176 -35.9664)
		(end 143.422624 -35.9664)
		(width 0.1524)
		(layer "In9.Cu")
		(net "M_B_DQS_DN6")
	)
	(segment
		(start 132.497576 -35.8902)
		(end 134.761224 -35.8902)
		(width 0.1524)
		(layer "In9.Cu")
		(net "M_B_DQS_DN6")
	)
	(segment
		(start 153.884376 -36.2712)
		(end 154.265376 -35.8902)
		(width 0.1524)
		(layer "In9.Cu")
		(net "M_B_DQS_DN6")
	)
	(segment
		(start 136.838944 -36.8808)
		(end 136.963404 -36.75634)
		(width 0.1524)
		(layer "In9.Cu")
		(net "M_B_DQS_DN6")
	)
	(segment
		(start 178.969924 -15.672308)
		(end 178.969924 -12.419076)
		(width 0.1524)
		(layer "In9.Cu")
		(net "M_B_DQS_DN6")
	)
	(segment
		(start 136.381744 -36.8808)
		(end 136.838944 -36.8808)
		(width 0.1524)
		(layer "In9.Cu")
		(net "M_B_DQS_DN6")
	)
	(segment
		(start 138.126724 -36.75634)
		(end 138.583924 -36.75634)
		(width 0.1524)
		(layer "In9.Cu")
		(net "M_B_DQS_DN6")
	)
	(segment
		(start 138.583924 -36.75634)
		(end 138.708384 -36.8808)
		(width 0.1524)
		(layer "In9.Cu")
		(net "M_B_DQS_DN6")
	)
	(segment
		(start 134.761224 -35.8902)
		(end 135.0772 -36.206176)
		(width 0.1524)
		(layer "In9.Cu")
		(net "M_B_DQS_DN6")
	)
	(segment
		(start 109.050074 -35.56)
		(end 108.81106 -35.320986)
		(width 0.1016)
		(layer "In9.Cu")
		(net "M_B_DQS_DN6")
	)
	(segment
		(start 135.0772 -36.739576)
		(end 135.218424 -36.8808)
		(width 0.1524)
		(layer "In9.Cu")
		(net "M_B_DQS_DN6")
	)
	(segment
		(start 92.6084 -46.901862)
		(end 92.6084 -47.279052)
		(width 0.1143)
		(layer "F.Cu")
		(net "PCIE_OBS_N")
	)
	(segment
		(start 93.393768 -46.116494)
		(end 92.6084 -46.901862)
		(width 0.1143)
		(layer "F.Cu")
		(net "PCIE_OBS_N")
	)
	(via
		(at 92.6084 -47.279052)
		(size 0.4318)
		(drill 0.2032)
		(layers "F.Cu" "B.Cu")
		(net "PCIE_OBS_N")
	)
	(via
		(at 90.043 -51.755802)
		(size 0.7112)
		(drill 0.3556)
		(layers "F.Cu" "B.Cu")
		(net "PCIE_OBS_N")
	)
	(segment
		(start 91.794584 -51.146202)
		(end 91.794584 -50.689002)
		(width 0.1143)
		(layer "B.Cu")
		(net "PCIE_OBS_N")
	)
	(segment
		(start 91.384628 -49.73193)
		(end 91.384628 -48.282606)
		(width 0.1143)
		(layer "B.Cu")
		(net "PCIE_OBS_N")
	)
	(segment
		(start 91.794584 -50.141886)
		(end 91.384628 -49.73193)
		(width 0.1143)
		(layer "B.Cu")
		(net "PCIE_OBS_N")
	)
	(segment
		(start 91.794584 -50.689002)
		(end 91.794584 -50.141886)
		(width 0.1143)
		(layer "B.Cu")
		(net "PCIE_OBS_N")
	)
	(segment
		(start 91.384628 -48.282606)
		(end 91.604084 -48.06315)
		(width 0.1143)
		(layer "B.Cu")
		(net "PCIE_OBS_N")
	)
	(segment
		(start 91.184984 -51.755802)
		(end 90.043 -51.755802)
		(width 0.1143)
		(layer "B.Cu")
		(net "PCIE_OBS_N")
	)
	(segment
		(start 92.6084 -47.448216)
		(end 92.6084 -47.279052)
		(width 0.1143)
		(layer "B.Cu")
		(net "PCIE_OBS_N")
	)
	(segment
		(start 91.604084 -48.06315)
		(end 91.993466 -48.06315)
		(width 0.1143)
		(layer "B.Cu")
		(net "PCIE_OBS_N")
	)
	(segment
		(start 91.184984 -51.755802)
		(end 91.794584 -51.146202)
		(width 0.1143)
		(layer "B.Cu")
		(net "PCIE_OBS_N")
	)
	(segment
		(start 91.993466 -48.06315)
		(end 92.6084 -47.448216)
		(width 0.1143)
		(layer "B.Cu")
		(net "PCIE_OBS_N")
	)
	(segment
		(start 184.912 -53.4162)
		(end 185.09996 -53.22824)
		(width 0.254)
		(layer "F.Cu")
		(net "PV_VDDR_VREF_A_FB")
	)
	(segment
		(start 183.388 -53.4162)
		(end 183.23052 -53.25872)
		(width 0.254)
		(layer "F.Cu")
		(net "PV_VDDR_VREF_A_FB")
	)
	(segment
		(start 185.09996 -53.22824)
		(end 185.09996 -52.451)
		(width 0.254)
		(layer "F.Cu")
		(net "PV_VDDR_VREF_A_FB")
	)
	(segment
		(start 185.09996 -51.47183)
		(end 185.09996 -52.451)
		(width 0.254)
		(layer "F.Cu")
		(net "PV_VDDR_VREF_A_FB")
	)
	(segment
		(start 184.15 -53.4162)
		(end 183.388 -53.4162)
		(width 0.254)
		(layer "F.Cu")
		(net "PV_VDDR_VREF_A_FB")
	)
	(segment
		(start 183.23052 -53.25872)
		(end 183.23052 -51.47183)
		(width 0.254)
		(layer "F.Cu")
		(net "PV_VDDR_VREF_A_FB")
	)
	(segment
		(start 184.15 -53.4162)
		(end 184.912 -53.4162)
		(width 0.254)
		(layer "F.Cu")
		(net "PV_VDDR_VREF_A_FB")
	)
	(via
		(at 185.09996 -52.451)
		(size 0.7112)
		(drill 0.3556)
		(layers "F.Cu" "B.Cu")
		(net "PV_VDDR_VREF_A_FB")
	)
	(segment
		(start 115.3668 -42.5196)
		(end 115.3414 -42.5196)
		(width 0.1016)
		(layer "F.Cu")
		(net "M_A_DQ28")
	)
	(segment
		(start 173.950122 -69.432678)
		(end 174.0154 -69.3674)
		(width 0.1778)
		(layer "F.Cu")
		(net "M_A_DQ28")
	)
	(segment
		(start 173.950122 -70.806564)
		(end 173.950122 -69.432678)
		(width 0.1778)
		(layer "F.Cu")
		(net "M_A_DQ28")
	)
	(segment
		(start 115.316 -42.545)
		(end 114.046 -42.545)
		(width 0.1016)
		(layer "F.Cu")
		(net "M_A_DQ28")
	)
	(segment
		(start 114.046 -42.545)
		(end 112.593374 -41.092374)
		(width 0.1016)
		(layer "F.Cu")
		(net "M_A_DQ28")
	)
	(segment
		(start 115.3414 -42.5196)
		(end 115.316 -42.545)
		(width 0.1016)
		(layer "F.Cu")
		(net "M_A_DQ28")
	)
	(segment
		(start 112.593374 -41.092374)
		(end 111.491268 -41.092374)
		(width 0.1016)
		(layer "F.Cu")
		(net "M_A_DQ28")
	)
	(via
		(at 174.0154 -69.3674)
		(size 0.4318)
		(drill 0.2032)
		(layers "F.Cu" "B.Cu")
		(net "M_A_DQ28")
	)
	(via
		(at 115.3668 -42.5196)
		(size 0.4318)
		(drill 0.2032)
		(layers "F.Cu" "B.Cu")
		(net "M_A_DQ28")
	)
	(segment
		(start 174.250096 -69.602096)
		(end 174.0154 -69.3674)
		(width 0.1778)
		(layer "B.Cu")
		(net "M_A_DQ28")
	)
	(segment
		(start 174.250096 -70.79996)
		(end 174.250096 -69.602096)
		(width 0.1778)
		(layer "B.Cu")
		(net "M_A_DQ28")
	)
	(segment
		(start 174.0154 -69.3674)
		(end 174.0154 -68.878704)
		(width 0.1524)
		(layer "In2.Cu")
		(net "M_A_DQ28")
	)
	(segment
		(start 176.911 -56.615076)
		(end 167.235378 -46.939454)
		(width 0.1524)
		(layer "In2.Cu")
		(net "M_A_DQ28")
	)
	(segment
		(start 162.56 -41.0718)
		(end 116.8146 -41.0718)
		(width 0.1524)
		(layer "In2.Cu")
		(net "M_A_DQ28")
	)
	(segment
		(start 174.0154 -68.878704)
		(end 176.911 -65.983104)
		(width 0.1524)
		(layer "In2.Cu")
		(net "M_A_DQ28")
	)
	(segment
		(start 167.235378 -45.747178)
		(end 162.56 -41.0718)
		(width 0.1524)
		(layer "In2.Cu")
		(net "M_A_DQ28")
	)
	(segment
		(start 176.911 -65.983104)
		(end 176.911 -56.615076)
		(width 0.1524)
		(layer "In2.Cu")
		(net "M_A_DQ28")
	)
	(segment
		(start 167.235378 -46.939454)
		(end 167.235378 -45.747178)
		(width 0.1524)
		(layer "In2.Cu")
		(net "M_A_DQ28")
	)
	(segment
		(start 116.8146 -41.0718)
		(end 115.3668 -42.5196)
		(width 0.1524)
		(layer "In2.Cu")
		(net "M_A_DQ28")
	)
	(segment
		(start 163.74999 -3.15341)
		(end 163.625022 -3.278378)
		(width 0.2159)
		(layer "F.Cu")
		(net "M_B_CK_DP2")
	)
	(segment
		(start 107.536488 -29.616654)
		(end 107.536488 -29.604716)
		(width 0.1016)
		(layer "F.Cu")
		(net "M_B_CK_DP2")
	)
	(segment
		(start 163.74999 -1.68402)
		(end 163.74999 -3.15341)
		(width 0.2159)
		(layer "F.Cu")
		(net "M_B_CK_DP2")
	)
	(segment
		(start 107.536488 -29.604716)
		(end 107.198668 -29.266896)
		(width 0.1016)
		(layer "F.Cu")
		(net "M_B_CK_DP2")
	)
	(via
		(at 107.198668 -29.266896)
		(size 0.4318)
		(drill 0.2032)
		(layers "F.Cu" "B.Cu")
		(net "M_B_CK_DP2")
	)
	(via
		(at 163.625022 -3.278378)
		(size 0.4318)
		(drill 0.2032)
		(layers "F.Cu" "B.Cu")
		(net "M_B_CK_DP2")
	)
	(segment
		(start 152.7175 -21.2979)
		(end 124.707142 -21.2979)
		(width 0.1905)
		(layer "In9.Cu")
		(net "M_B_CK_DP2")
	)
	(segment
		(start 124.707142 -21.2979)
		(end 124.271278 -21.733764)
		(width 0.1905)
		(layer "In9.Cu")
		(net "M_B_CK_DP2")
	)
	(segment
		(start 121.718578 -22.3266)
		(end 121.337578 -22.3266)
		(width 0.1905)
		(layer "In9.Cu")
		(net "M_B_CK_DP2")
	)
	(segment
		(start 107.391454 -28.566618)
		(end 107.391454 -29.059378)
		(width 0.1016)
		(layer "In9.Cu")
		(net "M_B_CK_DP2")
	)
	(segment
		(start 164.7444 -11.684)
		(end 164.7444 -12.723368)
		(width 0.1905)
		(layer "In9.Cu")
		(net "M_B_CK_DP2")
	)
	(segment
		(start 111.006636 -25.541986)
		(end 111.006636 -25.637236)
		(width 0.1016)
		(layer "In9.Cu")
		(net "M_B_CK_DP2")
	)
	(segment
		(start 117.6909 -21.2979)
		(end 117.0813 -21.9075)
		(width 0.1905)
		(layer "In9.Cu")
		(net "M_B_CK_DP2")
	)
	(segment
		(start 121.909078 -22.1361)
		(end 121.718578 -22.3266)
		(width 0.1905)
		(layer "In9.Cu")
		(net "M_B_CK_DP2")
	)
	(segment
		(start 109.440472 -27.8892)
		(end 108.068872 -27.8892)
		(width 0.1016)
		(layer "In9.Cu")
		(net "M_B_CK_DP2")
	)
	(segment
		(start 163.6395 -5.081778)
		(end 163.6395 -5.788914)
		(width 0.1905)
		(layer "In9.Cu")
		(net "M_B_CK_DP2")
	)
	(segment
		(start 123.509278 -22.2504)
		(end 123.509278 -21.733764)
		(width 0.1905)
		(layer "In9.Cu")
		(net "M_B_CK_DP2")
	)
	(segment
		(start 108.068872 -27.8892)
		(end 107.391454 -28.566618)
		(width 0.1016)
		(layer "In9.Cu")
		(net "M_B_CK_DP2")
	)
	(segment
		(start 153.7716 -20.2438)
		(end 152.7175 -21.2979)
		(width 0.1905)
		(layer "In9.Cu")
		(net "M_B_CK_DP2")
	)
	(segment
		(start 110.89005 -25.09901)
		(end 110.89005 -25.4254)
		(width 0.1905)
		(layer "In9.Cu")
		(net "M_B_CK_DP2")
	)
	(segment
		(start 110.006384 -27.323288)
		(end 109.440472 -27.8892)
		(width 0.1016)
		(layer "In9.Cu")
		(net "M_B_CK_DP2")
	)
	(segment
		(start 159.382968 -14.6939)
		(end 156.525468 -17.5514)
		(width 0.1905)
		(layer "In9.Cu")
		(net "M_B_CK_DP2")
	)
	(segment
		(start 165.608 -8.819642)
		(end 165.1254 -9.302242)
		(width 0.1905)
		(layer "In9.Cu")
		(net "M_B_CK_DP2")
	)
	(segment
		(start 121.909078 -21.733764)
		(end 121.909078 -22.1361)
		(width 0.1905)
		(layer "In9.Cu")
		(net "M_B_CK_DP2")
	)
	(segment
		(start 124.118878 -22.4028)
		(end 123.661678 -22.4028)
		(width 0.1905)
		(layer "In9.Cu")
		(net "M_B_CK_DP2")
	)
	(segment
		(start 123.661678 -22.4028)
		(end 123.509278 -22.2504)
		(width 0.1905)
		(layer "In9.Cu")
		(net "M_B_CK_DP2")
	)
	(segment
		(start 117.0813 -21.9075)
		(end 114.08156 -21.9075)
		(width 0.1905)
		(layer "In9.Cu")
		(net "M_B_CK_DP2")
	)
	(segment
		(start 110.89005 -25.4254)
		(end 111.006636 -25.541986)
		(width 0.1016)
		(layer "In9.Cu")
		(net "M_B_CK_DP2")
	)
	(segment
		(start 164.7444 -12.723368)
		(end 164.1094 -13.358368)
		(width 0.1905)
		(layer "In9.Cu")
		(net "M_B_CK_DP2")
	)
	(segment
		(start 165.608 -7.757414)
		(end 165.608 -8.819642)
		(width 0.1905)
		(layer "In9.Cu")
		(net "M_B_CK_DP2")
	)
	(segment
		(start 107.391454 -29.059378)
		(end 107.198668 -29.266896)
		(width 0.1016)
		(layer "In9.Cu")
		(net "M_B_CK_DP2")
	)
	(segment
		(start 163.625022 -3.278378)
		(end 163.3728 -3.5306)
		(width 0.1905)
		(layer "In9.Cu")
		(net "M_B_CK_DP2")
	)
	(segment
		(start 164.1094 -13.358368)
		(end 164.1094 -13.580364)
		(width 0.1905)
		(layer "In9.Cu")
		(net "M_B_CK_DP2")
	)
	(segment
		(start 121.337578 -22.3266)
		(end 121.147078 -22.1361)
		(width 0.1905)
		(layer "In9.Cu")
		(net "M_B_CK_DP2")
	)
	(segment
		(start 120.711214 -21.2979)
		(end 117.6909 -21.2979)
		(width 0.1905)
		(layer "In9.Cu")
		(net "M_B_CK_DP2")
	)
	(segment
		(start 163.6395 -5.788914)
		(end 165.608 -7.757414)
		(width 0.1905)
		(layer "In9.Cu")
		(net "M_B_CK_DP2")
	)
	(segment
		(start 153.7716 -18.0848)
		(end 153.7716 -20.2438)
		(width 0.1905)
		(layer "In9.Cu")
		(net "M_B_CK_DP2")
	)
	(segment
		(start 121.147078 -22.1361)
		(end 121.147078 -21.733764)
		(width 0.1905)
		(layer "In9.Cu")
		(net "M_B_CK_DP2")
	)
	(segment
		(start 163.3728 -4.815078)
		(end 163.6395 -5.081778)
		(width 0.1905)
		(layer "In9.Cu")
		(net "M_B_CK_DP2")
	)
	(segment
		(start 164.1094 -13.580364)
		(end 162.995864 -14.6939)
		(width 0.1905)
		(layer "In9.Cu")
		(net "M_B_CK_DP2")
	)
	(segment
		(start 162.995864 -14.6939)
		(end 159.382968 -14.6939)
		(width 0.1905)
		(layer "In9.Cu")
		(net "M_B_CK_DP2")
	)
	(segment
		(start 114.08156 -21.9075)
		(end 110.89005 -25.09901)
		(width 0.1905)
		(layer "In9.Cu")
		(net "M_B_CK_DP2")
	)
	(segment
		(start 110.006384 -26.637488)
		(end 110.006384 -27.323288)
		(width 0.1016)
		(layer "In9.Cu")
		(net "M_B_CK_DP2")
	)
	(segment
		(start 124.271278 -21.733764)
		(end 124.271278 -22.2504)
		(width 0.1905)
		(layer "In9.Cu")
		(net "M_B_CK_DP2")
	)
	(segment
		(start 121.147078 -21.733764)
		(end 120.711214 -21.2979)
		(width 0.1905)
		(layer "In9.Cu")
		(net "M_B_CK_DP2")
	)
	(segment
		(start 165.1254 -11.303)
		(end 164.7444 -11.684)
		(width 0.1905)
		(layer "In9.Cu")
		(net "M_B_CK_DP2")
	)
	(segment
		(start 163.3728 -3.5306)
		(end 163.3728 -4.815078)
		(width 0.1905)
		(layer "In9.Cu")
		(net "M_B_CK_DP2")
	)
	(segment
		(start 165.1254 -9.302242)
		(end 165.1254 -11.303)
		(width 0.1905)
		(layer "In9.Cu")
		(net "M_B_CK_DP2")
	)
	(segment
		(start 123.509278 -21.733764)
		(end 123.073414 -21.2979)
		(width 0.1905)
		(layer "In9.Cu")
		(net "M_B_CK_DP2")
	)
	(segment
		(start 154.305 -17.5514)
		(end 153.7716 -18.0848)
		(width 0.1905)
		(layer "In9.Cu")
		(net "M_B_CK_DP2")
	)
	(segment
		(start 111.006636 -25.637236)
		(end 110.006384 -26.637488)
		(width 0.1016)
		(layer "In9.Cu")
		(net "M_B_CK_DP2")
	)
	(segment
		(start 122.344942 -21.2979)
		(end 121.909078 -21.733764)
		(width 0.1905)
		(layer "In9.Cu")
		(net "M_B_CK_DP2")
	)
	(segment
		(start 123.073414 -21.2979)
		(end 122.344942 -21.2979)
		(width 0.1905)
		(layer "In9.Cu")
		(net "M_B_CK_DP2")
	)
	(segment
		(start 124.271278 -22.2504)
		(end 124.118878 -22.4028)
		(width 0.1905)
		(layer "In9.Cu")
		(net "M_B_CK_DP2")
	)
	(segment
		(start 156.525468 -17.5514)
		(end 154.305 -17.5514)
		(width 0.1905)
		(layer "In9.Cu")
		(net "M_B_CK_DP2")
	)
	(segment
		(start 109.911388 -41.536874)
		(end 109.754416 -41.379902)
		(width 0.1778)
		(layer "F.Cu")
		(net "M_A_DQ2")
	)
	(segment
		(start 110.418118 -41.609518)
		(end 110.345474 -41.536874)
		(width 0.1778)
		(layer "F.Cu")
		(net "M_A_DQ2")
	)
	(segment
		(start 185.650124 -62.59322)
		(end 185.650124 -63.730124)
		(width 0.1778)
		(layer "F.Cu")
		(net "M_A_DQ2")
	)
	(segment
		(start 109.238796 -41.379902)
		(end 108.814108 -40.955214)
		(width 0.1778)
		(layer "F.Cu")
		(net "M_A_DQ2")
	)
	(segment
		(start 185.650124 -63.730124)
		(end 185.9788 -64.0588)
		(width 0.1778)
		(layer "F.Cu")
		(net "M_A_DQ2")
	)
	(segment
		(start 110.447836 -41.609518)
		(end 110.418118 -41.609518)
		(width 0.1778)
		(layer "F.Cu")
		(net "M_A_DQ2")
	)
	(segment
		(start 110.345474 -41.536874)
		(end 109.911388 -41.536874)
		(width 0.1778)
		(layer "F.Cu")
		(net "M_A_DQ2")
	)
	(segment
		(start 109.754416 -41.379902)
		(end 109.238796 -41.379902)
		(width 0.1778)
		(layer "F.Cu")
		(net "M_A_DQ2")
	)
	(via
		(at 110.447836 -41.609518)
		(size 0.4318)
		(drill 0.2032)
		(layers "F.Cu" "B.Cu")
		(net "M_A_DQ2")
	)
	(via
		(at 185.9788 -64.0588)
		(size 0.4318)
		(drill 0.2032)
		(layers "F.Cu" "B.Cu")
		(net "M_A_DQ2")
	)
	(segment
		(start 186.087004 -64.0588)
		(end 185.9788 -64.0588)
		(width 0.1778)
		(layer "B.Cu")
		(net "M_A_DQ2")
	)
	(segment
		(start 186.550046 -62.599824)
		(end 186.550046 -63.595758)
		(width 0.1778)
		(layer "B.Cu")
		(net "M_A_DQ2")
	)
	(segment
		(start 186.550046 -63.595758)
		(end 186.087004 -64.0588)
		(width 0.1778)
		(layer "B.Cu")
		(net "M_A_DQ2")
	)
	(segment
		(start 173.595284 -57.173876)
		(end 173.340776 -57.428384)
		(width 0.1524)
		(layer "In7.Cu")
		(net "M_A_DQ2")
	)
	(segment
		(start 158.970472 -49.276)
		(end 162.090862 -49.276)
		(width 0.1524)
		(layer "In7.Cu")
		(net "M_A_DQ2")
	)
	(segment
		(start 171.007532 -54.586124)
		(end 170.753024 -54.840632)
		(width 0.1524)
		(layer "In7.Cu")
		(net "M_A_DQ2")
	)
	(segment
		(start 178.189382 -61.33719)
		(end 178.189382 -61.552582)
		(width 0.1524)
		(layer "In7.Cu")
		(net "M_A_DQ2")
	)
	(segment
		(start 173.595284 -56.958484)
		(end 173.595284 -57.173876)
		(width 0.1524)
		(layer "In7.Cu")
		(net "M_A_DQ2")
	)
	(segment
		(start 172.909484 -56.997092)
		(end 173.163992 -56.742584)
		(width 0.1524)
		(layer "In7.Cu")
		(net "M_A_DQ2")
	)
	(segment
		(start 178.189382 -61.552582)
		(end 178.405282 -61.768482)
		(width 0.1524)
		(layer "In7.Cu")
		(net "M_A_DQ2")
	)
	(segment
		(start 173.556676 -57.859676)
		(end 173.772068 -57.859676)
		(width 0.1524)
		(layer "In7.Cu")
		(net "M_A_DQ2")
	)
	(segment
		(start 177.542698 -60.905898)
		(end 177.75809 -60.905898)
		(width 0.1524)
		(layer "In7.Cu")
		(net "M_A_DQ2")
	)
	(segment
		(start 173.379384 -56.742584)
		(end 173.595284 -56.958484)
		(width 0.1524)
		(layer "In7.Cu")
		(net "M_A_DQ2")
	)
	(segment
		(start 172.478192 -56.5658)
		(end 172.478192 -56.781192)
		(width 0.1524)
		(layer "In7.Cu")
		(net "M_A_DQ2")
	)
	(segment
		(start 176.527968 -59.36742)
		(end 176.37379 -59.521598)
		(width 0.1524)
		(layer "In7.Cu")
		(net "M_A_DQ2")
	)
	(segment
		(start 171.870116 -55.233316)
		(end 171.870116 -55.448708)
		(width 0.1524)
		(layer "In7.Cu")
		(net "M_A_DQ2")
	)
	(segment
		(start 179.954174 -61.297566)
		(end 179.051966 -62.199774)
		(width 0.1524)
		(layer "In7.Cu")
		(net "M_A_DQ2")
	)
	(segment
		(start 174.241968 -57.605168)
		(end 174.457868 -57.821068)
		(width 0.1524)
		(layer "In7.Cu")
		(net "M_A_DQ2")
	)
	(segment
		(start 178.533298 -60.13069)
		(end 178.74869 -60.13069)
		(width 0.1524)
		(layer "In7.Cu")
		(net "M_A_DQ2")
	)
	(segment
		(start 179.738274 -60.866274)
		(end 179.954174 -61.082174)
		(width 0.1524)
		(layer "In7.Cu")
		(net "M_A_DQ2")
	)
	(segment
		(start 174.41926 -58.72226)
		(end 174.634652 -58.72226)
		(width 0.1524)
		(layer "In7.Cu")
		(net "M_A_DQ2")
	)
	(segment
		(start 185.9788 -63.894208)
		(end 185.9788 -64.0588)
		(width 0.1524)
		(layer "In7.Cu")
		(net "M_A_DQ2")
	)
	(segment
		(start 177.75809 -60.905898)
		(end 178.533298 -60.13069)
		(width 0.1524)
		(layer "In7.Cu")
		(net "M_A_DQ2")
	)
	(segment
		(start 177.326798 -60.689998)
		(end 177.542698 -60.905898)
		(width 0.1524)
		(layer "In7.Cu")
		(net "M_A_DQ2")
	)
	(segment
		(start 173.772068 -57.859676)
		(end 174.026576 -57.605168)
		(width 0.1524)
		(layer "In7.Cu")
		(net "M_A_DQ2")
	)
	(segment
		(start 175.942498 -59.090306)
		(end 176.096676 -58.936128)
		(width 0.1524)
		(layer "In7.Cu")
		(net "M_A_DQ2")
	)
	(segment
		(start 184.3532 -62.8396)
		(end 185.137806 -63.624206)
		(width 0.1524)
		(layer "In7.Cu")
		(net "M_A_DQ2")
	)
	(segment
		(start 179.051966 -62.199774)
		(end 179.051966 -62.415166)
		(width 0.1524)
		(layer "In7.Cu")
		(net "M_A_DQ2")
	)
	(segment
		(start 174.634652 -58.72226)
		(end 174.88916 -58.467752)
		(width 0.1524)
		(layer "In7.Cu")
		(net "M_A_DQ2")
	)
	(segment
		(start 172.7327 -56.0959)
		(end 172.7327 -56.311292)
		(width 0.1524)
		(layer "In7.Cu")
		(net "M_A_DQ2")
	)
	(segment
		(start 172.0469 -56.134508)
		(end 172.301408 -55.88)
		(width 0.1524)
		(layer "In7.Cu")
		(net "M_A_DQ2")
	)
	(segment
		(start 170.753024 -54.840632)
		(end 170.753024 -55.056024)
		(width 0.1524)
		(layer "In7.Cu")
		(net "M_A_DQ2")
	)
	(segment
		(start 174.457868 -58.03646)
		(end 174.20336 -58.290968)
		(width 0.1524)
		(layer "In7.Cu")
		(net "M_A_DQ2")
	)
	(segment
		(start 152.56637 -42.871898)
		(end 158.970472 -49.276)
		(width 0.1524)
		(layer "In7.Cu")
		(net "M_A_DQ2")
	)
	(segment
		(start 172.7327 -56.311292)
		(end 172.478192 -56.5658)
		(width 0.1524)
		(layer "In7.Cu")
		(net "M_A_DQ2")
	)
	(segment
		(start 177.662332 -60.139072)
		(end 177.326798 -60.474606)
		(width 0.1524)
		(layer "In7.Cu")
		(net "M_A_DQ2")
	)
	(segment
		(start 178.74869 -60.13069)
		(end 178.96459 -60.34659)
		(width 0.1524)
		(layer "In7.Cu")
		(net "M_A_DQ2")
	)
	(segment
		(start 173.163992 -56.742584)
		(end 173.379384 -56.742584)
		(width 0.1524)
		(layer "In7.Cu")
		(net "M_A_DQ2")
	)
	(segment
		(start 171.184316 -55.271924)
		(end 171.438824 -55.017416)
		(width 0.1524)
		(layer "In7.Cu")
		(net "M_A_DQ2")
	)
	(segment
		(start 173.340776 -57.643776)
		(end 173.556676 -57.859676)
		(width 0.1524)
		(layer "In7.Cu")
		(net "M_A_DQ2")
	)
	(segment
		(start 110.447836 -41.609518)
		(end 110.556294 -41.609518)
		(width 0.1524)
		(layer "In7.Cu")
		(net "M_A_DQ2")
	)
	(segment
		(start 172.5168 -55.88)
		(end 172.7327 -56.0959)
		(width 0.1524)
		(layer "In7.Cu")
		(net "M_A_DQ2")
	)
	(segment
		(start 110.556294 -41.609518)
		(end 111.364776 -42.418)
		(width 0.1524)
		(layer "In7.Cu")
		(net "M_A_DQ2")
	)
	(segment
		(start 111.364776 -42.418)
		(end 113.792 -42.418)
		(width 0.1524)
		(layer "In7.Cu")
		(net "M_A_DQ2")
	)
	(segment
		(start 178.405282 -61.768482)
		(end 178.620674 -61.768482)
		(width 0.1524)
		(layer "In7.Cu")
		(net "M_A_DQ2")
	)
	(segment
		(start 176.37379 -59.73699)
		(end 176.680114 -60.043314)
		(width 0.1524)
		(layer "In7.Cu")
		(net "M_A_DQ2")
	)
	(segment
		(start 171.870116 -55.448708)
		(end 171.615608 -55.703216)
		(width 0.1524)
		(layer "In7.Cu")
		(net "M_A_DQ2")
	)
	(segment
		(start 171.831508 -56.134508)
		(end 172.0469 -56.134508)
		(width 0.1524)
		(layer "In7.Cu")
		(net "M_A_DQ2")
	)
	(segment
		(start 177.446432 -59.70778)
		(end 177.662332 -59.92368)
		(width 0.1524)
		(layer "In7.Cu")
		(net "M_A_DQ2")
	)
	(segment
		(start 172.301408 -55.88)
		(end 172.5168 -55.88)
		(width 0.1524)
		(layer "In7.Cu")
		(net "M_A_DQ2")
	)
	(segment
		(start 176.680114 -60.043314)
		(end 176.895506 -60.043314)
		(width 0.1524)
		(layer "In7.Cu")
		(net "M_A_DQ2")
	)
	(segment
		(start 177.662332 -59.92368)
		(end 177.662332 -60.139072)
		(width 0.1524)
		(layer "In7.Cu")
		(net "M_A_DQ2")
	)
	(segment
		(start 179.4764 -62.8396)
		(end 184.3532 -62.8396)
		(width 0.1524)
		(layer "In7.Cu")
		(net "M_A_DQ2")
	)
	(segment
		(start 114.173 -42.037)
		(end 117.602 -42.037)
		(width 0.1524)
		(layer "In7.Cu")
		(net "M_A_DQ2")
	)
	(segment
		(start 174.457868 -57.821068)
		(end 174.457868 -58.03646)
		(width 0.1524)
		(layer "In7.Cu")
		(net "M_A_DQ2")
	)
	(segment
		(start 174.88916 -58.467752)
		(end 175.104552 -58.467752)
		(width 0.1524)
		(layer "In7.Cu")
		(net "M_A_DQ2")
	)
	(segment
		(start 170.553634 -53.916834)
		(end 171.007532 -54.370732)
		(width 0.1524)
		(layer "In7.Cu")
		(net "M_A_DQ2")
	)
	(segment
		(start 171.007532 -54.370732)
		(end 171.007532 -54.586124)
		(width 0.1524)
		(layer "In7.Cu")
		(net "M_A_DQ2")
	)
	(segment
		(start 175.104552 -58.467752)
		(end 175.727106 -59.090306)
		(width 0.1524)
		(layer "In7.Cu")
		(net "M_A_DQ2")
	)
	(segment
		(start 185.708798 -63.624206)
		(end 185.9788 -63.894208)
		(width 0.1524)
		(layer "In7.Cu")
		(net "M_A_DQ2")
	)
	(segment
		(start 174.026576 -57.605168)
		(end 174.241968 -57.605168)
		(width 0.1524)
		(layer "In7.Cu")
		(net "M_A_DQ2")
	)
	(segment
		(start 118.436898 -42.871898)
		(end 152.56637 -42.871898)
		(width 0.1524)
		(layer "In7.Cu")
		(net "M_A_DQ2")
	)
	(segment
		(start 179.522882 -60.866274)
		(end 179.738274 -60.866274)
		(width 0.1524)
		(layer "In7.Cu")
		(net "M_A_DQ2")
	)
	(segment
		(start 177.23104 -59.70778)
		(end 177.446432 -59.70778)
		(width 0.1524)
		(layer "In7.Cu")
		(net "M_A_DQ2")
	)
	(segment
		(start 170.753024 -55.056024)
		(end 170.968924 -55.271924)
		(width 0.1524)
		(layer "In7.Cu")
		(net "M_A_DQ2")
	)
	(segment
		(start 176.312068 -58.936128)
		(end 176.527968 -59.152028)
		(width 0.1524)
		(layer "In7.Cu")
		(net "M_A_DQ2")
	)
	(segment
		(start 174.20336 -58.50636)
		(end 174.41926 -58.72226)
		(width 0.1524)
		(layer "In7.Cu")
		(net "M_A_DQ2")
	)
	(segment
		(start 177.326798 -60.474606)
		(end 177.326798 -60.689998)
		(width 0.1524)
		(layer "In7.Cu")
		(net "M_A_DQ2")
	)
	(segment
		(start 179.954174 -61.082174)
		(end 179.954174 -61.297566)
		(width 0.1524)
		(layer "In7.Cu")
		(net "M_A_DQ2")
	)
	(segment
		(start 175.727106 -59.090306)
		(end 175.942498 -59.090306)
		(width 0.1524)
		(layer "In7.Cu")
		(net "M_A_DQ2")
	)
	(segment
		(start 176.37379 -59.521598)
		(end 176.37379 -59.73699)
		(width 0.1524)
		(layer "In7.Cu")
		(net "M_A_DQ2")
	)
	(segment
		(start 171.615608 -55.918608)
		(end 171.831508 -56.134508)
		(width 0.1524)
		(layer "In7.Cu")
		(net "M_A_DQ2")
	)
	(segment
		(start 178.620674 -61.768482)
		(end 179.522882 -60.866274)
		(width 0.1524)
		(layer "In7.Cu")
		(net "M_A_DQ2")
	)
	(segment
		(start 117.602 -42.037)
		(end 118.436898 -42.871898)
		(width 0.1524)
		(layer "In7.Cu")
		(net "M_A_DQ2")
	)
	(segment
		(start 172.478192 -56.781192)
		(end 172.694092 -56.997092)
		(width 0.1524)
		(layer "In7.Cu")
		(net "M_A_DQ2")
	)
	(segment
		(start 179.051966 -62.415166)
		(end 179.4764 -62.8396)
		(width 0.1524)
		(layer "In7.Cu")
		(net "M_A_DQ2")
	)
	(segment
		(start 172.694092 -56.997092)
		(end 172.909484 -56.997092)
		(width 0.1524)
		(layer "In7.Cu")
		(net "M_A_DQ2")
	)
	(segment
		(start 173.340776 -57.428384)
		(end 173.340776 -57.643776)
		(width 0.1524)
		(layer "In7.Cu")
		(net "M_A_DQ2")
	)
	(segment
		(start 171.615608 -55.703216)
		(end 171.615608 -55.918608)
		(width 0.1524)
		(layer "In7.Cu")
		(net "M_A_DQ2")
	)
	(segment
		(start 113.792 -42.418)
		(end 114.173 -42.037)
		(width 0.1524)
		(layer "In7.Cu")
		(net "M_A_DQ2")
	)
	(segment
		(start 178.96459 -60.561982)
		(end 178.189382 -61.33719)
		(width 0.1524)
		(layer "In7.Cu")
		(net "M_A_DQ2")
	)
	(segment
		(start 162.090862 -49.276)
		(end 166.731696 -53.916834)
		(width 0.1524)
		(layer "In7.Cu")
		(net "M_A_DQ2")
	)
	(segment
		(start 176.096676 -58.936128)
		(end 176.312068 -58.936128)
		(width 0.1524)
		(layer "In7.Cu")
		(net "M_A_DQ2")
	)
	(segment
		(start 185.137806 -63.624206)
		(end 185.708798 -63.624206)
		(width 0.1524)
		(layer "In7.Cu")
		(net "M_A_DQ2")
	)
	(segment
		(start 174.20336 -58.290968)
		(end 174.20336 -58.50636)
		(width 0.1524)
		(layer "In7.Cu")
		(net "M_A_DQ2")
	)
	(segment
		(start 176.527968 -59.152028)
		(end 176.527968 -59.36742)
		(width 0.1524)
		(layer "In7.Cu")
		(net "M_A_DQ2")
	)
	(segment
		(start 166.731696 -53.916834)
		(end 170.553634 -53.916834)
		(width 0.1524)
		(layer "In7.Cu")
		(net "M_A_DQ2")
	)
	(segment
		(start 171.654216 -55.017416)
		(end 171.870116 -55.233316)
		(width 0.1524)
		(layer "In7.Cu")
		(net "M_A_DQ2")
	)
	(segment
		(start 176.895506 -60.043314)
		(end 177.23104 -59.70778)
		(width 0.1524)
		(layer "In7.Cu")
		(net "M_A_DQ2")
	)
	(segment
		(start 170.968924 -55.271924)
		(end 171.184316 -55.271924)
		(width 0.1524)
		(layer "In7.Cu")
		(net "M_A_DQ2")
	)
	(segment
		(start 178.96459 -60.34659)
		(end 178.96459 -60.561982)
		(width 0.1524)
		(layer "In7.Cu")
		(net "M_A_DQ2")
	)
	(segment
		(start 171.438824 -55.017416)
		(end 171.654216 -55.017416)
		(width 0.1524)
		(layer "In7.Cu")
		(net "M_A_DQ2")
	)
	(segment
		(start 97.9678 -29.5656)
		(end 97.976182 -29.5656)
		(width 0.1016)
		(layer "F.Cu")
		(net "M_B_DQ25")
	)
	(segment
		(start 144.84985 -8.580374)
		(end 144.996408 -8.433816)
		(width 0.1778)
		(layer "F.Cu")
		(net "M_B_DQ25")
	)
	(segment
		(start 144.84985 -9.897364)
		(end 144.84985 -8.580374)
		(width 0.1778)
		(layer "F.Cu")
		(net "M_B_DQ25")
	)
	(segment
		(start 97.976182 -29.5656)
		(end 98.306128 -29.235654)
		(width 0.1016)
		(layer "F.Cu")
		(net "M_B_DQ25")
	)
	(segment
		(start 97.9424 -29.591)
		(end 97.9678 -29.5656)
		(width 0.1016)
		(layer "F.Cu")
		(net "M_B_DQ25")
	)
	(via
		(at 144.996408 -8.433816)
		(size 0.4318)
		(drill 0.2032)
		(layers "F.Cu" "B.Cu")
		(net "M_B_DQ25")
	)
	(via
		(at 97.9424 -29.591)
		(size 0.4318)
		(drill 0.2032)
		(layers "F.Cu" "B.Cu")
		(net "M_B_DQ25")
	)
	(segment
		(start 145.149824 -8.587232)
		(end 144.996408 -8.433816)
		(width 0.1778)
		(layer "B.Cu")
		(net "M_B_DQ25")
	)
	(segment
		(start 145.149824 -9.89076)
		(end 145.149824 -8.587232)
		(width 0.1778)
		(layer "B.Cu")
		(net "M_B_DQ25")
	)
	(segment
		(start 104.509316 -26.556716)
		(end 100.900484 -26.556716)
		(width 0.1524)
		(layer "In4.Cu")
		(net "M_B_DQ25")
	)
	(segment
		(start 130.5306 -19.6088)
		(end 130.3782 -19.7612)
		(width 0.1524)
		(layer "In4.Cu")
		(net "M_B_DQ25")
	)
	(segment
		(start 105.8164 -25.249632)
		(end 104.509316 -26.556716)
		(width 0.1524)
		(layer "In4.Cu")
		(net "M_B_DQ25")
	)
	(segment
		(start 97.9424 -29.591)
		(end 98.5266 -29.0068)
		(width 0.1016)
		(layer "In4.Cu")
		(net "M_B_DQ25")
	)
	(segment
		(start 132.3594 -18.8468)
		(end 132.207 -18.6944)
		(width 0.1524)
		(layer "In4.Cu")
		(net "M_B_DQ25")
	)
	(segment
		(start 133.1214 -18.6944)
		(end 132.969 -18.8468)
		(width 0.1524)
		(layer "In4.Cu")
		(net "M_B_DQ25")
	)
	(segment
		(start 133.5786 -18.8468)
		(end 133.4262 -18.6944)
		(width 0.1524)
		(layer "In4.Cu")
		(net "M_B_DQ25")
	)
	(segment
		(start 144.907 -19.9644)
		(end 137.033 -19.9644)
		(width 0.1524)
		(layer "In4.Cu")
		(net "M_B_DQ25")
	)
	(segment
		(start 126.1618 -19.7612)
		(end 126.0094 -19.6088)
		(width 0.1524)
		(layer "In4.Cu")
		(net "M_B_DQ25")
	)
	(segment
		(start 131.7498 -18.8468)
		(end 131.7498 -19.6088)
		(width 0.1524)
		(layer "In4.Cu")
		(net "M_B_DQ25")
	)
	(segment
		(start 106.2228 -22.4282)
		(end 105.8164 -22.8346)
		(width 0.1524)
		(layer "In4.Cu")
		(net "M_B_DQ25")
	)
	(segment
		(start 131.1402 -18.8468)
		(end 130.9878 -18.6944)
		(width 0.1524)
		(layer "In4.Cu")
		(net "M_B_DQ25")
	)
	(segment
		(start 134.3152 -19.812)
		(end 133.731 -19.812)
		(width 0.1524)
		(layer "In4.Cu")
		(net "M_B_DQ25")
	)
	(segment
		(start 112.062514 -22.4282)
		(end 106.2228 -22.4282)
		(width 0.1524)
		(layer "In4.Cu")
		(net "M_B_DQ25")
	)
	(segment
		(start 125.3998 -19.6088)
		(end 125.2474 -19.7612)
		(width 0.1524)
		(layer "In4.Cu")
		(net "M_B_DQ25")
	)
	(segment
		(start 98.904552 -27.943048)
		(end 99.514152 -27.943048)
		(width 0.1016)
		(layer "In4.Cu")
		(net "M_B_DQ25")
	)
	(segment
		(start 132.3594 -19.6088)
		(end 132.3594 -18.8468)
		(width 0.1524)
		(layer "In4.Cu")
		(net "M_B_DQ25")
	)
	(segment
		(start 130.5306 -18.8468)
		(end 130.5306 -19.6088)
		(width 0.1524)
		(layer "In4.Cu")
		(net "M_B_DQ25")
	)
	(segment
		(start 131.9022 -18.6944)
		(end 131.7498 -18.8468)
		(width 0.1524)
		(layer "In4.Cu")
		(net "M_B_DQ25")
	)
	(segment
		(start 136.8806 -18.8468)
		(end 136.7282 -18.6944)
		(width 0.1524)
		(layer "In4.Cu")
		(net "M_B_DQ25")
	)
	(segment
		(start 130.3782 -19.7612)
		(end 126.1618 -19.7612)
		(width 0.1524)
		(layer "In4.Cu")
		(net "M_B_DQ25")
	)
	(segment
		(start 134.4676 -19.6596)
		(end 134.3152 -19.812)
		(width 0.1524)
		(layer "In4.Cu")
		(net "M_B_DQ25")
	)
	(segment
		(start 105.8164 -22.8346)
		(end 105.8164 -25.249632)
		(width 0.1524)
		(layer "In4.Cu")
		(net "M_B_DQ25")
	)
	(segment
		(start 132.8166 -19.7612)
		(end 132.5118 -19.7612)
		(width 0.1524)
		(layer "In4.Cu")
		(net "M_B_DQ25")
	)
	(segment
		(start 125.5268 -18.6944)
		(end 125.3998 -18.8214)
		(width 0.1524)
		(layer "In4.Cu")
		(net "M_B_DQ25")
	)
	(segment
		(start 131.2926 -19.7612)
		(end 131.1402 -19.6088)
		(width 0.1524)
		(layer "In4.Cu")
		(net "M_B_DQ25")
	)
	(segment
		(start 144.996408 -8.433816)
		(end 145.313654 -8.751062)
		(width 0.1524)
		(layer "In4.Cu")
		(net "M_B_DQ25")
	)
	(segment
		(start 132.969 -19.6088)
		(end 132.8166 -19.7612)
		(width 0.1524)
		(layer "In4.Cu")
		(net "M_B_DQ25")
	)
	(segment
		(start 125.2474 -19.7612)
		(end 124.1298 -19.7612)
		(width 0.1524)
		(layer "In4.Cu")
		(net "M_B_DQ25")
	)
	(segment
		(start 131.7498 -19.6088)
		(end 131.5974 -19.7612)
		(width 0.1524)
		(layer "In4.Cu")
		(net "M_B_DQ25")
	)
	(segment
		(start 126.0094 -19.6088)
		(end 126.0094 -18.8214)
		(width 0.1524)
		(layer "In4.Cu")
		(net "M_B_DQ25")
	)
	(segment
		(start 145.313654 -19.557746)
		(end 144.907 -19.9644)
		(width 0.1524)
		(layer "In4.Cu")
		(net "M_B_DQ25")
	)
	(segment
		(start 130.683 -18.6944)
		(end 130.5306 -18.8468)
		(width 0.1524)
		(layer "In4.Cu")
		(net "M_B_DQ25")
	)
	(segment
		(start 137.033 -19.9644)
		(end 136.8806 -19.812)
		(width 0.1524)
		(layer "In4.Cu")
		(net "M_B_DQ25")
	)
	(segment
		(start 130.9878 -18.6944)
		(end 130.683 -18.6944)
		(width 0.1524)
		(layer "In4.Cu")
		(net "M_B_DQ25")
	)
	(segment
		(start 124.1298 -19.7612)
		(end 123.9266 -19.9644)
		(width 0.1524)
		(layer "In4.Cu")
		(net "M_B_DQ25")
	)
	(segment
		(start 136.8806 -19.812)
		(end 136.8806 -18.8468)
		(width 0.1524)
		(layer "In4.Cu")
		(net "M_B_DQ25")
	)
	(segment
		(start 100.900484 -26.556716)
		(end 99.514152 -27.943048)
		(width 0.1524)
		(layer "In4.Cu")
		(net "M_B_DQ25")
	)
	(segment
		(start 132.5118 -19.7612)
		(end 132.3594 -19.6088)
		(width 0.1524)
		(layer "In4.Cu")
		(net "M_B_DQ25")
	)
	(segment
		(start 134.62 -18.6944)
		(end 134.4676 -18.8468)
		(width 0.1524)
		(layer "In4.Cu")
		(net "M_B_DQ25")
	)
	(segment
		(start 131.5974 -19.7612)
		(end 131.2926 -19.7612)
		(width 0.1524)
		(layer "In4.Cu")
		(net "M_B_DQ25")
	)
	(segment
		(start 123.9266 -19.9644)
		(end 114.526314 -19.9644)
		(width 0.1524)
		(layer "In4.Cu")
		(net "M_B_DQ25")
	)
	(segment
		(start 125.3998 -18.8214)
		(end 125.3998 -19.6088)
		(width 0.1524)
		(layer "In4.Cu")
		(net "M_B_DQ25")
	)
	(segment
		(start 114.526314 -19.9644)
		(end 112.062514 -22.4282)
		(width 0.1524)
		(layer "In4.Cu")
		(net "M_B_DQ25")
	)
	(segment
		(start 132.207 -18.6944)
		(end 131.9022 -18.6944)
		(width 0.1524)
		(layer "In4.Cu")
		(net "M_B_DQ25")
	)
	(segment
		(start 136.7282 -18.6944)
		(end 134.62 -18.6944)
		(width 0.1524)
		(layer "In4.Cu")
		(net "M_B_DQ25")
	)
	(segment
		(start 131.1402 -19.6088)
		(end 131.1402 -18.8468)
		(width 0.1524)
		(layer "In4.Cu")
		(net "M_B_DQ25")
	)
	(segment
		(start 132.969 -18.8468)
		(end 132.969 -19.6088)
		(width 0.1524)
		(layer "In4.Cu")
		(net "M_B_DQ25")
	)
	(segment
		(start 145.313654 -8.751062)
		(end 145.313654 -19.557746)
		(width 0.1524)
		(layer "In4.Cu")
		(net "M_B_DQ25")
	)
	(segment
		(start 98.5266 -29.0068)
		(end 98.5266 -28.321)
		(width 0.1016)
		(layer "In4.Cu")
		(net "M_B_DQ25")
	)
	(segment
		(start 133.4262 -18.6944)
		(end 133.1214 -18.6944)
		(width 0.1524)
		(layer "In4.Cu")
		(net "M_B_DQ25")
	)
	(segment
		(start 134.4676 -18.8468)
		(end 134.4676 -19.6596)
		(width 0.1524)
		(layer "In4.Cu")
		(net "M_B_DQ25")
	)
	(segment
		(start 133.731 -19.812)
		(end 133.5786 -19.6596)
		(width 0.1524)
		(layer "In4.Cu")
		(net "M_B_DQ25")
	)
	(segment
		(start 126.0094 -18.8214)
		(end 125.8824 -18.6944)
		(width 0.1524)
		(layer "In4.Cu")
		(net "M_B_DQ25")
	)
	(segment
		(start 125.8824 -18.6944)
		(end 125.5268 -18.6944)
		(width 0.1524)
		(layer "In4.Cu")
		(net "M_B_DQ25")
	)
	(segment
		(start 98.5266 -28.321)
		(end 98.904552 -27.943048)
		(width 0.1016)
		(layer "In4.Cu")
		(net "M_B_DQ25")
	)
	(segment
		(start 133.5786 -19.6596)
		(end 133.5786 -18.8468)
		(width 0.1524)
		(layer "In4.Cu")
		(net "M_B_DQ25")
	)
	(segment
		(start 108.9914 -48.182784)
		(end 108.814108 -48.360076)
		(width 0.1016)
		(layer "F.Cu")
		(net "M_A_MA11")
	)
	(segment
		(start 160.129728 -65.540128)
		(end 160.129728 -66.0654)
		(width 0.2413)
		(layer "F.Cu")
		(net "M_A_MA11")
	)
	(segment
		(start 159.250126 -64.660526)
		(end 160.129728 -65.540128)
		(width 0.2413)
		(layer "F.Cu")
		(net "M_A_MA11")
	)
	(segment
		(start 159.250126 -62.59322)
		(end 159.250126 -64.660526)
		(width 0.2413)
		(layer "F.Cu")
		(net "M_A_MA11")
	)
	(segment
		(start 108.814108 -48.360076)
		(end 108.814108 -48.900334)
		(width 0.1016)
		(layer "F.Cu")
		(net "M_A_MA11")
	)
	(via
		(at 160.129728 -66.0654)
		(size 0.4318)
		(drill 0.2032)
		(layers "F.Cu" "B.Cu")
		(net "M_A_MA11")
	)
	(via
		(at 108.9914 -48.182784)
		(size 0.4318)
		(drill 0.2032)
		(layers "F.Cu" "B.Cu")
		(net "M_A_MA11")
	)
	(segment
		(start 159.65932 -67.772534)
		(end 159.65932 -66.562478)
		(width 0.2413)
		(layer "B.Cu")
		(net "M_A_MA11")
	)
	(segment
		(start 160.129728 -66.09207)
		(end 160.129728 -66.0654)
		(width 0.2413)
		(layer "B.Cu")
		(net "M_A_MA11")
	)
	(segment
		(start 159.250126 -68.18122)
		(end 159.65932 -67.772534)
		(width 0.2413)
		(layer "B.Cu")
		(net "M_A_MA11")
	)
	(segment
		(start 159.250126 -70.79996)
		(end 159.250126 -68.18122)
		(width 0.2413)
		(layer "B.Cu")
		(net "M_A_MA11")
	)
	(segment
		(start 159.65932 -66.562478)
		(end 160.129728 -66.09207)
		(width 0.2413)
		(layer "B.Cu")
		(net "M_A_MA11")
	)
	(segment
		(start 150.306532 -49.555146)
		(end 149.665944 -49.555146)
		(width 0.1905)
		(layer "In9.Cu")
		(net "M_A_MA11")
	)
	(segment
		(start 149.665944 -49.555146)
		(end 149.66569 -49.5554)
		(width 0.1905)
		(layer "In9.Cu")
		(net "M_A_MA11")
	)
	(segment
		(start 159.639 -58.887614)
		(end 150.306532 -49.555146)
		(width 0.1905)
		(layer "In9.Cu")
		(net "M_A_MA11")
	)
	(segment
		(start 160.129728 -66.0654)
		(end 160.129728 -65.641728)
		(width 0.1905)
		(layer "In9.Cu")
		(net "M_A_MA11")
	)
	(segment
		(start 113.0173 -47.9933)
		(end 109.180884 -47.9933)
		(width 0.1016)
		(layer "In9.Cu")
		(net "M_A_MA11")
	)
	(segment
		(start 117.7544 -49.02835)
		(end 117.20195 -49.5808)
		(width 0.1016)
		(layer "In9.Cu")
		(net "M_A_MA11")
	)
	(segment
		(start 160.129728 -65.641728)
		(end 159.639 -65.151)
		(width 0.1905)
		(layer "In9.Cu")
		(net "M_A_MA11")
	)
	(segment
		(start 149.66569 -49.5554)
		(end 145.36039 -49.5554)
		(width 0.1905)
		(layer "In9.Cu")
		(net "M_A_MA11")
	)
	(segment
		(start 144.83334 -49.02835)
		(end 117.7544 -49.02835)
		(width 0.1905)
		(layer "In9.Cu")
		(net "M_A_MA11")
	)
	(segment
		(start 109.180884 -47.9933)
		(end 108.9914 -48.182784)
		(width 0.1016)
		(layer "In9.Cu")
		(net "M_A_MA11")
	)
	(segment
		(start 159.639 -65.151)
		(end 159.639 -58.887614)
		(width 0.1905)
		(layer "In9.Cu")
		(net "M_A_MA11")
	)
	(segment
		(start 117.20195 -49.5808)
		(end 114.6048 -49.5808)
		(width 0.1016)
		(layer "In9.Cu")
		(net "M_A_MA11")
	)
	(segment
		(start 145.36039 -49.5554)
		(end 144.83334 -49.02835)
		(width 0.1905)
		(layer "In9.Cu")
		(net "M_A_MA11")
	)
	(segment
		(start 114.6048 -49.5808)
		(end 113.0173 -47.9933)
		(width 0.1016)
		(layer "In9.Cu")
		(net "M_A_MA11")
	)
	(segment
		(start 111.148368 -29.090874)
		(end 111.148368 -28.958032)
		(width 0.2413)
		(layer "F.Cu")
		(net "M_B_MA13")
	)
	(segment
		(start 168.457372 -6.601206)
		(end 168.453308 -6.597142)
		(width 0.2413)
		(layer "F.Cu")
		(net "M_B_MA13")
	)
	(segment
		(start 111.148368 -28.958032)
		(end 111.4298 -28.6766)
		(width 0.2413)
		(layer "F.Cu")
		(net "M_B_MA13")
	)
	(segment
		(start 168.753028 -6.601206)
		(end 168.457372 -6.601206)
		(width 0.2413)
		(layer "F.Cu")
		(net "M_B_MA13")
	)
	(segment
		(start 169.450004 -9.897364)
		(end 169.450004 -7.298182)
		(width 0.2413)
		(layer "F.Cu")
		(net "M_B_MA13")
	)
	(segment
		(start 169.450004 -7.298182)
		(end 168.753028 -6.601206)
		(width 0.2413)
		(layer "F.Cu")
		(net "M_B_MA13")
	)
	(via
		(at 111.4298 -28.6766)
		(size 0.4318)
		(drill 0.2032)
		(layers "F.Cu" "B.Cu")
		(net "M_B_MA13")
	)
	(via
		(at 168.453308 -6.597142)
		(size 0.4318)
		(drill 0.2032)
		(layers "F.Cu" "B.Cu")
		(net "M_B_MA13")
	)
	(segment
		(start 168.94175 -4.973828)
		(end 168.94175 -6.164326)
		(width 0.2413)
		(layer "B.Cu")
		(net "M_B_MA13")
	)
	(segment
		(start 169.672 -4.243578)
		(end 168.94175 -4.973828)
		(width 0.2413)
		(layer "B.Cu")
		(net "M_B_MA13")
	)
	(segment
		(start 168.508934 -6.597142)
		(end 168.453308 -6.597142)
		(width 0.2413)
		(layer "B.Cu")
		(net "M_B_MA13")
	)
	(segment
		(start 168.94175 -6.164326)
		(end 168.508934 -6.597142)
		(width 0.2413)
		(layer "B.Cu")
		(net "M_B_MA13")
	)
	(segment
		(start 169.672 -2.985516)
		(end 169.672 -4.243578)
		(width 0.2413)
		(layer "B.Cu")
		(net "M_B_MA13")
	)
	(segment
		(start 169.450004 -2.76352)
		(end 169.672 -2.985516)
		(width 0.2413)
		(layer "B.Cu")
		(net "M_B_MA13")
	)
	(segment
		(start 169.450004 -1.690624)
		(end 169.450004 -2.76352)
		(width 0.2413)
		(layer "B.Cu")
		(net "M_B_MA13")
	)
	(segment
		(start 159.556196 -22.6441)
		(end 159.286956 -22.6441)
		(width 0.1905)
		(layer "In7.Cu")
		(net "M_B_MA13")
	)
	(segment
		(start 157.430978 -23.75281)
		(end 157.430978 -24.02205)
		(width 0.1905)
		(layer "In7.Cu")
		(net "M_B_MA13")
	)
	(segment
		(start 157.400244 -24.800052)
		(end 157.131004 -24.800052)
		(width 0.1905)
		(layer "In7.Cu")
		(net "M_B_MA13")
	)
	(segment
		(start 155.814014 -25.639014)
		(end 155.544774 -25.639014)
		(width 0.1905)
		(layer "In7.Cu")
		(net "M_B_MA13")
	)
	(segment
		(start 116.6368 -28.575)
		(end 111.5314 -28.575)
		(width 0.1905)
		(layer "In7.Cu")
		(net "M_B_MA13")
	)
	(segment
		(start 158.778702 -22.405086)
		(end 158.508954 -22.674834)
		(width 0.1905)
		(layer "In7.Cu")
		(net "M_B_MA13")
	)
	(segment
		(start 158.747968 -23.183088)
		(end 158.747968 -23.452328)
		(width 0.1905)
		(layer "In7.Cu")
		(net "M_B_MA13")
	)
	(segment
		(start 155.51404 -26.417016)
		(end 155.51404 -26.686256)
		(width 0.1905)
		(layer "In7.Cu")
		(net "M_B_MA13")
	)
	(segment
		(start 158.508954 -22.944074)
		(end 158.747968 -23.183088)
		(width 0.1905)
		(layer "In7.Cu")
		(net "M_B_MA13")
	)
	(segment
		(start 157.669992 -24.261064)
		(end 157.669992 -24.530304)
		(width 0.1905)
		(layer "In7.Cu")
		(net "M_B_MA13")
	)
	(segment
		(start 167.6146 -7.367778)
		(end 167.6146 -9.9314)
		(width 0.1905)
		(layer "In7.Cu")
		(net "M_B_MA13")
	)
	(segment
		(start 157.430978 -24.02205)
		(end 157.669992 -24.261064)
		(width 0.1905)
		(layer "In7.Cu")
		(net "M_B_MA13")
	)
	(segment
		(start 158.20898 -23.722076)
		(end 157.969966 -23.483062)
		(width 0.1905)
		(layer "In7.Cu")
		(net "M_B_MA13")
	)
	(segment
		(start 159.047942 -22.405086)
		(end 158.778702 -22.405086)
		(width 0.1905)
		(layer "In7.Cu")
		(net "M_B_MA13")
	)
	(segment
		(start 168.385236 -6.597142)
		(end 167.6146 -7.367778)
		(width 0.1905)
		(layer "In7.Cu")
		(net "M_B_MA13")
	)
	(segment
		(start 167.6146 -9.9314)
		(end 167.211248 -10.334752)
		(width 0.1905)
		(layer "In7.Cu")
		(net "M_B_MA13")
	)
	(segment
		(start 156.592016 -25.60828)
		(end 156.322268 -25.878028)
		(width 0.1905)
		(layer "In7.Cu")
		(net "M_B_MA13")
	)
	(segment
		(start 156.353002 -24.830786)
		(end 156.353002 -25.100026)
		(width 0.1905)
		(layer "In7.Cu")
		(net "M_B_MA13")
	)
	(segment
		(start 156.053028 -25.878028)
		(end 155.814014 -25.639014)
		(width 0.1905)
		(layer "In7.Cu")
		(net "M_B_MA13")
	)
	(segment
		(start 111.5314 -28.575)
		(end 111.4298 -28.6766)
		(width 0.1905)
		(layer "In7.Cu")
		(net "M_B_MA13")
	)
	(segment
		(start 155.544774 -25.639014)
		(end 155.275026 -25.908762)
		(width 0.1905)
		(layer "In7.Cu")
		(net "M_B_MA13")
	)
	(segment
		(start 156.592016 -25.33904)
		(end 156.592016 -25.60828)
		(width 0.1905)
		(layer "In7.Cu")
		(net "M_B_MA13")
	)
	(segment
		(start 155.51404 -26.686256)
		(end 155.073096 -27.1272)
		(width 0.1905)
		(layer "In7.Cu")
		(net "M_B_MA13")
	)
	(segment
		(start 156.89199 -24.561038)
		(end 156.62275 -24.561038)
		(width 0.1905)
		(layer "In7.Cu")
		(net "M_B_MA13")
	)
	(segment
		(start 167.211248 -10.334752)
		(end 167.211248 -14.989048)
		(width 0.1905)
		(layer "In7.Cu")
		(net "M_B_MA13")
	)
	(segment
		(start 157.700726 -23.483062)
		(end 157.430978 -23.75281)
		(width 0.1905)
		(layer "In7.Cu")
		(net "M_B_MA13")
	)
	(segment
		(start 159.286956 -22.6441)
		(end 159.047942 -22.405086)
		(width 0.1905)
		(layer "In7.Cu")
		(net "M_B_MA13")
	)
	(segment
		(start 155.073096 -27.1272)
		(end 118.0846 -27.1272)
		(width 0.1905)
		(layer "In7.Cu")
		(net "M_B_MA13")
	)
	(segment
		(start 156.322268 -25.878028)
		(end 156.053028 -25.878028)
		(width 0.1905)
		(layer "In7.Cu")
		(net "M_B_MA13")
	)
	(segment
		(start 157.969966 -23.483062)
		(end 157.700726 -23.483062)
		(width 0.1905)
		(layer "In7.Cu")
		(net "M_B_MA13")
	)
	(segment
		(start 155.275026 -25.908762)
		(end 155.275026 -26.178002)
		(width 0.1905)
		(layer "In7.Cu")
		(net "M_B_MA13")
	)
	(segment
		(start 157.669992 -24.530304)
		(end 157.400244 -24.800052)
		(width 0.1905)
		(layer "In7.Cu")
		(net "M_B_MA13")
	)
	(segment
		(start 158.47822 -23.722076)
		(end 158.20898 -23.722076)
		(width 0.1905)
		(layer "In7.Cu")
		(net "M_B_MA13")
	)
	(segment
		(start 156.353002 -25.100026)
		(end 156.592016 -25.33904)
		(width 0.1905)
		(layer "In7.Cu")
		(net "M_B_MA13")
	)
	(segment
		(start 157.131004 -24.800052)
		(end 156.89199 -24.561038)
		(width 0.1905)
		(layer "In7.Cu")
		(net "M_B_MA13")
	)
	(segment
		(start 167.211248 -14.989048)
		(end 159.556196 -22.6441)
		(width 0.1905)
		(layer "In7.Cu")
		(net "M_B_MA13")
	)
	(segment
		(start 158.747968 -23.452328)
		(end 158.47822 -23.722076)
		(width 0.1905)
		(layer "In7.Cu")
		(net "M_B_MA13")
	)
	(segment
		(start 156.62275 -24.561038)
		(end 156.353002 -24.830786)
		(width 0.1905)
		(layer "In7.Cu")
		(net "M_B_MA13")
	)
	(segment
		(start 158.508954 -22.674834)
		(end 158.508954 -22.944074)
		(width 0.1905)
		(layer "In7.Cu")
		(net "M_B_MA13")
	)
	(segment
		(start 155.275026 -26.178002)
		(end 155.51404 -26.417016)
		(width 0.1905)
		(layer "In7.Cu")
		(net "M_B_MA13")
	)
	(segment
		(start 168.453308 -6.597142)
		(end 168.385236 -6.597142)
		(width 0.1905)
		(layer "In7.Cu")
		(net "M_B_MA13")
	)
	(segment
		(start 118.0846 -27.1272)
		(end 116.6368 -28.575)
		(width 0.1905)
		(layer "In7.Cu")
		(net "M_B_MA13")
	)
	(segment
		(start 187.579 -45.5422)
		(end 187.579 -44.831)
		(width 0.254)
		(layer "F.Cu")
		(net "PV_VDDR_VREF_B")
	)
	(segment
		(start 186.5122 -43.7642)
		(end 186.309 -43.7642)
		(width 0.254)
		(layer "F.Cu")
		(net "PV_VDDR_VREF_B")
	)
	(segment
		(start 187.071 -44.323)
		(end 186.5122 -43.7642)
		(width 0.254)
		(layer "F.Cu")
		(net "PV_VDDR_VREF_B")
	)
	(segment
		(start 185.4708 -42.926)
		(end 185.4708 -43.688)
		(width 0.254)
		(layer "F.Cu")
		(net "PV_VDDR_VREF_B")
	)
	(segment
		(start 185.547 -43.7642)
		(end 186.309 -43.7642)
		(width 0.254)
		(layer "F.Cu")
		(net "PV_VDDR_VREF_B")
	)
	(segment
		(start 187.579 -44.831)
		(end 187.071 -44.323)
		(width 0.254)
		(layer "F.Cu")
		(net "PV_VDDR_VREF_B")
	)
	(segment
		(start 185.4708 -43.688)
		(end 185.547 -43.7642)
		(width 0.254)
		(layer "F.Cu")
		(net "PV_VDDR_VREF_B")
	)
	(via
		(at 187.071 -44.323)
		(size 0.7112)
		(drill 0.3556)
		(layers "F.Cu" "B.Cu")
		(net "PV_VDDR_VREF_B")
	)
	(segment
		(start 104.501188 -52.2605)
		(end 104.473248 -52.28844)
		(width 0.1016)
		(layer "F.Cu")
		(net "M_A_DQ40")
	)
	(segment
		(start 104.498648 -50.995834)
		(end 104.498648 -51.75504)
		(width 0.1016)
		(layer "F.Cu")
		(net "M_A_DQ40")
	)
	(segment
		(start 143.3576 -64.546226)
		(end 143.523716 -64.712342)
		(width 0.1778)
		(layer "F.Cu")
		(net "M_A_DQ40")
	)
	(segment
		(start 104.501188 -51.75758)
		(end 104.501188 -52.2605)
		(width 0.1016)
		(layer "F.Cu")
		(net "M_A_DQ40")
	)
	(segment
		(start 104.498648 -51.75504)
		(end 104.501188 -51.75758)
		(width 0.1016)
		(layer "F.Cu")
		(net "M_A_DQ40")
	)
	(segment
		(start 143.649954 -62.59322)
		(end 143.649954 -63.406274)
		(width 0.1778)
		(layer "F.Cu")
		(net "M_A_DQ40")
	)
	(segment
		(start 104.752648 -50.741834)
		(end 104.498648 -50.995834)
		(width 0.1016)
		(layer "F.Cu")
		(net "M_A_DQ40")
	)
	(segment
		(start 104.473248 -53.152548)
		(end 105.6132 -54.2925)
		(width 0.1016)
		(layer "F.Cu")
		(net "M_A_DQ40")
	)
	(segment
		(start 143.649954 -63.406274)
		(end 143.3576 -63.698628)
		(width 0.1778)
		(layer "F.Cu")
		(net "M_A_DQ40")
	)
	(segment
		(start 104.473248 -52.28844)
		(end 104.473248 -53.152548)
		(width 0.1016)
		(layer "F.Cu")
		(net "M_A_DQ40")
	)
	(segment
		(start 143.3576 -63.698628)
		(end 143.3576 -64.546226)
		(width 0.1778)
		(layer "F.Cu")
		(net "M_A_DQ40")
	)
	(segment
		(start 105.6132 -54.2925)
		(end 105.6132 -54.8386)
		(width 0.1016)
		(layer "F.Cu")
		(net "M_A_DQ40")
	)
	(via
		(at 143.523716 -64.712342)
		(size 0.4318)
		(drill 0.2032)
		(layers "F.Cu" "B.Cu")
		(net "M_A_DQ40")
	)
	(via
		(at 105.6132 -54.8386)
		(size 0.4318)
		(drill 0.2032)
		(layers "F.Cu" "B.Cu")
		(net "M_A_DQ40")
	)
	(segment
		(start 142.750032 -62.599824)
		(end 142.750032 -63.324232)
		(width 0.1778)
		(layer "B.Cu")
		(net "M_A_DQ40")
	)
	(segment
		(start 143.3068 -63.881)
		(end 143.3068 -64.5668)
		(width 0.1778)
		(layer "B.Cu")
		(net "M_A_DQ40")
	)
	(segment
		(start 143.425164 -64.685164)
		(end 143.496538 -64.685164)
		(width 0.1778)
		(layer "B.Cu")
		(net "M_A_DQ40")
	)
	(segment
		(start 142.750032 -63.324232)
		(end 143.3068 -63.881)
		(width 0.1778)
		(layer "B.Cu")
		(net "M_A_DQ40")
	)
	(segment
		(start 143.3068 -64.5668)
		(end 143.425164 -64.685164)
		(width 0.1778)
		(layer "B.Cu")
		(net "M_A_DQ40")
	)
	(segment
		(start 143.496538 -64.685164)
		(end 143.523716 -64.712342)
		(width 0.1778)
		(layer "B.Cu")
		(net "M_A_DQ40")
	)
	(segment
		(start 105.6132 -54.8386)
		(end 105.6259 -54.8386)
		(width 0.1524)
		(layer "In2.Cu")
		(net "M_A_DQ40")
	)
	(segment
		(start 124.019564 -56.873902)
		(end 124.171964 -56.721502)
		(width 0.1524)
		(layer "In2.Cu")
		(net "M_A_DQ40")
	)
	(segment
		(start 135.968232 -56.5404)
		(end 135.968232 -56.3626)
		(width 0.1524)
		(layer "In2.Cu")
		(net "M_A_DQ40")
	)
	(segment
		(start 138.709146 -56.6928)
		(end 139.801346 -57.785)
		(width 0.1524)
		(layer "In2.Cu")
		(net "M_A_DQ40")
	)
	(segment
		(start 133.6802 -55.8546)
		(end 134.5184 -56.6928)
		(width 0.1524)
		(layer "In2.Cu")
		(net "M_A_DQ40")
	)
	(segment
		(start 122.343164 -56.721502)
		(end 122.495564 -56.873902)
		(width 0.1524)
		(layer "In2.Cu")
		(net "M_A_DQ40")
	)
	(segment
		(start 107.921298 -56.873902)
		(end 118.513098 -56.873902)
		(width 0.1524)
		(layer "In2.Cu")
		(net "M_A_DQ40")
	)
	(segment
		(start 136.425432 -56.2102)
		(end 136.577832 -56.3626)
		(width 0.1524)
		(layer "In2.Cu")
		(net "M_A_DQ40")
	)
	(segment
		(start 139.801346 -57.785)
		(end 140.9192 -57.785)
		(width 0.1524)
		(layer "In2.Cu")
		(net "M_A_DQ40")
	)
	(segment
		(start 121.581164 -56.8198)
		(end 121.733564 -56.6674)
		(width 0.1524)
		(layer "In2.Cu")
		(net "M_A_DQ40")
	)
	(segment
		(start 124.171964 -56.721502)
		(end 124.171964 -56.007)
		(width 0.1524)
		(layer "In2.Cu")
		(net "M_A_DQ40")
	)
	(segment
		(start 135.968232 -56.3626)
		(end 136.120632 -56.2102)
		(width 0.1524)
		(layer "In2.Cu")
		(net "M_A_DQ40")
	)
	(segment
		(start 140.9192 -57.785)
		(end 143.7513 -60.6171)
		(width 0.1524)
		(layer "In2.Cu")
		(net "M_A_DQ40")
	)
	(segment
		(start 143.7513 -60.6171)
		(end 143.7513 -62.4459)
		(width 0.1524)
		(layer "In2.Cu")
		(net "M_A_DQ40")
	)
	(segment
		(start 122.952764 -56.721502)
		(end 122.952764 -56.007)
		(width 0.1524)
		(layer "In2.Cu")
		(net "M_A_DQ40")
	)
	(segment
		(start 143.3068 -64.5668)
		(end 143.425164 -64.685164)
		(width 0.1524)
		(layer "In2.Cu")
		(net "M_A_DQ40")
	)
	(segment
		(start 123.105164 -55.8546)
		(end 123.409964 -55.8546)
		(width 0.1524)
		(layer "In2.Cu")
		(net "M_A_DQ40")
	)
	(segment
		(start 120.971564 -55.8546)
		(end 121.123964 -56.007)
		(width 0.1524)
		(layer "In2.Cu")
		(net "M_A_DQ40")
	)
	(segment
		(start 123.562364 -56.007)
		(end 123.562364 -56.721502)
		(width 0.1524)
		(layer "In2.Cu")
		(net "M_A_DQ40")
	)
	(segment
		(start 121.733564 -56.6674)
		(end 121.733564 -56.007)
		(width 0.1524)
		(layer "In2.Cu")
		(net "M_A_DQ40")
	)
	(segment
		(start 122.495564 -56.873902)
		(end 122.800364 -56.873902)
		(width 0.1524)
		(layer "In2.Cu")
		(net "M_A_DQ40")
	)
	(segment
		(start 106.0958 -56.8452)
		(end 106.5276 -57.277)
		(width 0.1524)
		(layer "In2.Cu")
		(net "M_A_DQ40")
	)
	(segment
		(start 122.190764 -55.8546)
		(end 122.343164 -56.007)
		(width 0.1524)
		(layer "In2.Cu")
		(net "M_A_DQ40")
	)
	(segment
		(start 121.885964 -55.8546)
		(end 122.190764 -55.8546)
		(width 0.1524)
		(layer "In2.Cu")
		(net "M_A_DQ40")
	)
	(segment
		(start 106.5276 -57.277)
		(end 107.5182 -57.277)
		(width 0.1524)
		(layer "In2.Cu")
		(net "M_A_DQ40")
	)
	(segment
		(start 106.0958 -55.3085)
		(end 106.0958 -56.8452)
		(width 0.1524)
		(layer "In2.Cu")
		(net "M_A_DQ40")
	)
	(segment
		(start 123.714764 -56.873902)
		(end 124.019564 -56.873902)
		(width 0.1524)
		(layer "In2.Cu")
		(net "M_A_DQ40")
	)
	(segment
		(start 118.513098 -56.873902)
		(end 118.872 -56.515)
		(width 0.1524)
		(layer "In2.Cu")
		(net "M_A_DQ40")
	)
	(segment
		(start 122.952764 -56.007)
		(end 123.105164 -55.8546)
		(width 0.1524)
		(layer "In2.Cu")
		(net "M_A_DQ40")
	)
	(segment
		(start 118.872 -56.515)
		(end 118.872 -56.134)
		(width 0.1524)
		(layer "In2.Cu")
		(net "M_A_DQ40")
	)
	(segment
		(start 124.324364 -55.8546)
		(end 133.6802 -55.8546)
		(width 0.1524)
		(layer "In2.Cu")
		(net "M_A_DQ40")
	)
	(segment
		(start 143.496538 -64.685164)
		(end 143.523716 -64.712342)
		(width 0.1524)
		(layer "In2.Cu")
		(net "M_A_DQ40")
	)
	(segment
		(start 121.123964 -56.6674)
		(end 121.276364 -56.8198)
		(width 0.1524)
		(layer "In2.Cu")
		(net "M_A_DQ40")
	)
	(segment
		(start 136.120632 -56.2102)
		(end 136.425432 -56.2102)
		(width 0.1524)
		(layer "In2.Cu")
		(net "M_A_DQ40")
	)
	(segment
		(start 136.577832 -56.3626)
		(end 136.577832 -56.5404)
		(width 0.1524)
		(layer "In2.Cu")
		(net "M_A_DQ40")
	)
	(segment
		(start 136.730232 -56.6928)
		(end 138.709146 -56.6928)
		(width 0.1524)
		(layer "In2.Cu")
		(net "M_A_DQ40")
	)
	(segment
		(start 121.733564 -56.007)
		(end 121.885964 -55.8546)
		(width 0.1524)
		(layer "In2.Cu")
		(net "M_A_DQ40")
	)
	(segment
		(start 135.815832 -56.6928)
		(end 135.968232 -56.5404)
		(width 0.1524)
		(layer "In2.Cu")
		(net "M_A_DQ40")
	)
	(segment
		(start 134.5184 -56.6928)
		(end 135.815832 -56.6928)
		(width 0.1524)
		(layer "In2.Cu")
		(net "M_A_DQ40")
	)
	(segment
		(start 143.425164 -64.685164)
		(end 143.496538 -64.685164)
		(width 0.1524)
		(layer "In2.Cu")
		(net "M_A_DQ40")
	)
	(segment
		(start 124.171964 -56.007)
		(end 124.324364 -55.8546)
		(width 0.1524)
		(layer "In2.Cu")
		(net "M_A_DQ40")
	)
	(segment
		(start 122.800364 -56.873902)
		(end 122.952764 -56.721502)
		(width 0.1524)
		(layer "In2.Cu")
		(net "M_A_DQ40")
	)
	(segment
		(start 118.872 -56.134)
		(end 119.1514 -55.8546)
		(width 0.1524)
		(layer "In2.Cu")
		(net "M_A_DQ40")
	)
	(segment
		(start 136.577832 -56.5404)
		(end 136.730232 -56.6928)
		(width 0.1524)
		(layer "In2.Cu")
		(net "M_A_DQ40")
	)
	(segment
		(start 121.276364 -56.8198)
		(end 121.581164 -56.8198)
		(width 0.1524)
		(layer "In2.Cu")
		(net "M_A_DQ40")
	)
	(segment
		(start 121.123964 -56.007)
		(end 121.123964 -56.6674)
		(width 0.1524)
		(layer "In2.Cu")
		(net "M_A_DQ40")
	)
	(segment
		(start 107.5182 -57.277)
		(end 107.921298 -56.873902)
		(width 0.1524)
		(layer "In2.Cu")
		(net "M_A_DQ40")
	)
	(segment
		(start 123.409964 -55.8546)
		(end 123.562364 -56.007)
		(width 0.1524)
		(layer "In2.Cu")
		(net "M_A_DQ40")
	)
	(segment
		(start 143.7513 -62.4459)
		(end 143.3068 -62.8904)
		(width 0.1524)
		(layer "In2.Cu")
		(net "M_A_DQ40")
	)
	(segment
		(start 105.6259 -54.8386)
		(end 106.0958 -55.3085)
		(width 0.1524)
		(layer "In2.Cu")
		(net "M_A_DQ40")
	)
	(segment
		(start 122.343164 -56.007)
		(end 122.343164 -56.721502)
		(width 0.1524)
		(layer "In2.Cu")
		(net "M_A_DQ40")
	)
	(segment
		(start 119.1514 -55.8546)
		(end 120.971564 -55.8546)
		(width 0.1524)
		(layer "In2.Cu")
		(net "M_A_DQ40")
	)
	(segment
		(start 123.562364 -56.721502)
		(end 123.714764 -56.873902)
		(width 0.1524)
		(layer "In2.Cu")
		(net "M_A_DQ40")
	)
	(segment
		(start 143.3068 -62.8904)
		(end 143.3068 -64.5668)
		(width 0.1524)
		(layer "In2.Cu")
		(net "M_A_DQ40")
	)
	(segment
		(start 142.83309 -8.758428)
		(end 142.83309 -8.072374)
		(width 0.1778)
		(layer "F.Cu")
		(net "M_B_DQ18")
	)
	(segment
		(start 102.7684 -26.928826)
		(end 103.139748 -27.300174)
		(width 0.1016)
		(layer "F.Cu")
		(net "M_B_DQ18")
	)
	(segment
		(start 102.6922 -23.0632)
		(end 102.6922 -26.2636)
		(width 0.1016)
		(layer "F.Cu")
		(net "M_B_DQ18")
	)
	(segment
		(start 102.7684 -26.3398)
		(end 102.7684 -26.928826)
		(width 0.1016)
		(layer "F.Cu")
		(net "M_B_DQ18")
	)
	(segment
		(start 142.450058 -9.14146)
		(end 142.83309 -8.758428)
		(width 0.1778)
		(layer "F.Cu")
		(net "M_B_DQ18")
	)
	(segment
		(start 102.6922 -26.2636)
		(end 102.7684 -26.3398)
		(width 0.1016)
		(layer "F.Cu")
		(net "M_B_DQ18")
	)
	(segment
		(start 142.83309 -8.072374)
		(end 142.609824 -7.849108)
		(width 0.1778)
		(layer "F.Cu")
		(net "M_B_DQ18")
	)
	(segment
		(start 142.450058 -9.897364)
		(end 142.450058 -9.14146)
		(width 0.1778)
		(layer "F.Cu")
		(net "M_B_DQ18")
	)
	(segment
		(start 102.5398 -22.9108)
		(end 102.6922 -23.0632)
		(width 0.1016)
		(layer "F.Cu")
		(net "M_B_DQ18")
	)
	(via
		(at 102.5398 -22.9108)
		(size 0.4318)
		(drill 0.2032)
		(layers "F.Cu" "B.Cu")
		(net "M_B_DQ18")
	)
	(via
		(at 142.609824 -7.849108)
		(size 0.4318)
		(drill 0.2032)
		(layers "F.Cu" "B.Cu")
		(net "M_B_DQ18")
	)
	(segment
		(start 142.73149 -7.849108)
		(end 142.609824 -7.849108)
		(width 0.1778)
		(layer "B.Cu")
		(net "M_B_DQ18")
	)
	(segment
		(start 142.750032 -9.89076)
		(end 142.750032 -8.703818)
		(width 0.1778)
		(layer "B.Cu")
		(net "M_B_DQ18")
	)
	(segment
		(start 142.85976 -8.59409)
		(end 142.85976 -7.977378)
		(width 0.1778)
		(layer "B.Cu")
		(net "M_B_DQ18")
	)
	(segment
		(start 142.85976 -7.977378)
		(end 142.73149 -7.849108)
		(width 0.1778)
		(layer "B.Cu")
		(net "M_B_DQ18")
	)
	(segment
		(start 142.750032 -8.703818)
		(end 142.85976 -8.59409)
		(width 0.1778)
		(layer "B.Cu")
		(net "M_B_DQ18")
	)
	(segment
		(start 138.445494 -13.5382)
		(end 138.445494 -15.3416)
		(width 0.1524)
		(layer "In4.Cu")
		(net "M_B_DQ18")
	)
	(segment
		(start 138.445494 -15.3416)
		(end 138.293094 -15.494)
		(width 0.1524)
		(layer "In4.Cu")
		(net "M_B_DQ18")
	)
	(segment
		(start 140.536676 -12.434062)
		(end 140.536676 -12.435586)
		(width 0.1524)
		(layer "In4.Cu")
		(net "M_B_DQ18")
	)
	(segment
		(start 114.173 -16.7894)
		(end 113.210848 -16.7894)
		(width 0.1524)
		(layer "In4.Cu")
		(net "M_B_DQ18")
	)
	(segment
		(start 140.121894 -14.478)
		(end 139.512294 -14.478)
		(width 0.1524)
		(layer "In4.Cu")
		(net "M_B_DQ18")
	)
	(segment
		(start 139.512294 -14.478)
		(end 139.359894 -14.3256)
		(width 0.1524)
		(layer "In4.Cu")
		(net "M_B_DQ18")
	)
	(segment
		(start 102.108 -22.479)
		(end 102.5398 -22.9108)
		(width 0.1016)
		(layer "In4.Cu")
		(net "M_B_DQ18")
	)
	(segment
		(start 139.207494 -13.3858)
		(end 138.597894 -13.3858)
		(width 0.1524)
		(layer "In4.Cu")
		(net "M_B_DQ18")
	)
	(segment
		(start 142.609824 -7.892796)
		(end 142.82928 -8.112252)
		(width 0.1524)
		(layer "In4.Cu")
		(net "M_B_DQ18")
	)
	(segment
		(start 139.359894 -13.5382)
		(end 139.207494 -13.3858)
		(width 0.1524)
		(layer "In4.Cu")
		(net "M_B_DQ18")
	)
	(segment
		(start 140.536676 -12.435586)
		(end 140.274294 -12.697968)
		(width 0.1524)
		(layer "In4.Cu")
		(net "M_B_DQ18")
	)
	(segment
		(start 104.8004 -19.2532)
		(end 104.394 -19.6596)
		(width 0.1016)
		(layer "In4.Cu")
		(net "M_B_DQ18")
	)
	(segment
		(start 142.82928 -10.141458)
		(end 140.536676 -12.434062)
		(width 0.1524)
		(layer "In4.Cu")
		(net "M_B_DQ18")
	)
	(segment
		(start 114.3254 -15.6464)
		(end 114.3254 -16.637)
		(width 0.1524)
		(layer "In4.Cu")
		(net "M_B_DQ18")
	)
	(segment
		(start 113.210848 -16.7894)
		(end 110.747048 -19.2532)
		(width 0.1524)
		(layer "In4.Cu")
		(net "M_B_DQ18")
	)
	(segment
		(start 139.359894 -14.3256)
		(end 139.359894 -13.5382)
		(width 0.1524)
		(layer "In4.Cu")
		(net "M_B_DQ18")
	)
	(segment
		(start 142.82928 -8.112252)
		(end 142.82928 -10.141458)
		(width 0.1524)
		(layer "In4.Cu")
		(net "M_B_DQ18")
	)
	(segment
		(start 114.3254 -16.637)
		(end 114.173 -16.7894)
		(width 0.1524)
		(layer "In4.Cu")
		(net "M_B_DQ18")
	)
	(segment
		(start 102.108 -20.8788)
		(end 102.108 -22.479)
		(width 0.1016)
		(layer "In4.Cu")
		(net "M_B_DQ18")
	)
	(segment
		(start 142.609824 -7.849108)
		(end 142.609824 -7.892796)
		(width 0.1524)
		(layer "In4.Cu")
		(net "M_B_DQ18")
	)
	(segment
		(start 138.293094 -15.494)
		(end 114.4778 -15.494)
		(width 0.1524)
		(layer "In4.Cu")
		(net "M_B_DQ18")
	)
	(segment
		(start 138.597894 -13.3858)
		(end 138.445494 -13.5382)
		(width 0.1524)
		(layer "In4.Cu")
		(net "M_B_DQ18")
	)
	(segment
		(start 104.394 -19.6596)
		(end 103.3272 -19.6596)
		(width 0.1016)
		(layer "In4.Cu")
		(net "M_B_DQ18")
	)
	(segment
		(start 114.4778 -15.494)
		(end 114.3254 -15.6464)
		(width 0.1524)
		(layer "In4.Cu")
		(net "M_B_DQ18")
	)
	(segment
		(start 140.274294 -14.3256)
		(end 140.121894 -14.478)
		(width 0.1524)
		(layer "In4.Cu")
		(net "M_B_DQ18")
	)
	(segment
		(start 110.747048 -19.2532)
		(end 105.4608 -19.2532)
		(width 0.1524)
		(layer "In4.Cu")
		(net "M_B_DQ18")
	)
	(segment
		(start 140.274294 -12.697968)
		(end 140.274294 -14.3256)
		(width 0.1524)
		(layer "In4.Cu")
		(net "M_B_DQ18")
	)
	(segment
		(start 103.3272 -19.6596)
		(end 102.108 -20.8788)
		(width 0.1016)
		(layer "In4.Cu")
		(net "M_B_DQ18")
	)
	(segment
		(start 105.4608 -19.2532)
		(end 104.8004 -19.2532)
		(width 0.1016)
		(layer "In4.Cu")
		(net "M_B_DQ18")
	)
	(segment
		(start 187.579 -46.4058)
		(end 186.817 -46.4058)
		(width 0.254)
		(layer "F.Cu")
		(net "PV_VDDR_VREF_B_FB")
	)
	(segment
		(start 188.341 -46.90872)
		(end 188.13272 -47.117)
		(width 0.254)
		(layer "F.Cu")
		(net "PV_VDDR_VREF_B_FB")
	)
	(segment
		(start 188.341 -46.4058)
		(end 188.341 -46.90872)
		(width 0.254)
		(layer "F.Cu")
		(net "PV_VDDR_VREF_B_FB")
	)
	(segment
		(start 185.9026 -46.736)
		(end 185.9026 -47.371)
		(width 0.254)
		(layer "F.Cu")
		(net "PV_VDDR_VREF_B_FB")
	)
	(segment
		(start 186.2328 -46.4058)
		(end 185.9026 -46.736)
		(width 0.254)
		(layer "F.Cu")
		(net "PV_VDDR_VREF_B_FB")
	)
	(segment
		(start 188.13272 -47.117)
		(end 188.13272 -47.60976)
		(width 0.254)
		(layer "F.Cu")
		(net "PV_VDDR_VREF_B_FB")
	)
	(segment
		(start 188.341 -46.4058)
		(end 187.579 -46.4058)
		(width 0.254)
		(layer "F.Cu")
		(net "PV_VDDR_VREF_B_FB")
	)
	(segment
		(start 185.9026 -47.371)
		(end 186.14136 -47.60976)
		(width 0.254)
		(layer "F.Cu")
		(net "PV_VDDR_VREF_B_FB")
	)
	(segment
		(start 186.817 -46.4058)
		(end 186.2328 -46.4058)
		(width 0.254)
		(layer "F.Cu")
		(net "PV_VDDR_VREF_B_FB")
	)
	(segment
		(start 186.14136 -47.60976)
		(end 186.26328 -47.60976)
		(width 0.254)
		(layer "F.Cu")
		(net "PV_VDDR_VREF_B_FB")
	)
	(via
		(at 185.9026 -46.736)
		(size 0.7112)
		(drill 0.3556)
		(layers "F.Cu" "B.Cu")
		(net "PV_VDDR_VREF_B_FB")
	)
	(segment
		(start 106.5403 -54.4576)
		(end 105.1814 -53.0987)
		(width 0.1016)
		(layer "F.Cu")
		(net "M_A_DQ44")
	)
	(segment
		(start 106.5784 -54.9148)
		(end 106.5403 -54.8767)
		(width 0.1016)
		(layer "F.Cu")
		(net "M_A_DQ44")
	)
	(segment
		(start 105.1814 -53.0987)
		(end 105.1814 -52.150264)
		(width 0.1016)
		(layer "F.Cu")
		(net "M_A_DQ44")
	)
	(segment
		(start 142.750032 -69.905372)
		(end 143.1798 -69.475604)
		(width 0.1778)
		(layer "F.Cu")
		(net "M_A_DQ44")
	)
	(segment
		(start 143.1798 -68.961)
		(end 143.2814 -68.8594)
		(width 0.1778)
		(layer "F.Cu")
		(net "M_A_DQ44")
	)
	(segment
		(start 106.5403 -54.8767)
		(end 106.5403 -54.4576)
		(width 0.1016)
		(layer "F.Cu")
		(net "M_A_DQ44")
	)
	(segment
		(start 105.1814 -52.150264)
		(end 104.803448 -51.772312)
		(width 0.1016)
		(layer "F.Cu")
		(net "M_A_DQ44")
	)
	(segment
		(start 142.750032 -70.806564)
		(end 142.750032 -69.905372)
		(width 0.1778)
		(layer "F.Cu")
		(net "M_A_DQ44")
	)
	(segment
		(start 104.803448 -51.772312)
		(end 104.803448 -51.503834)
		(width 0.1016)
		(layer "F.Cu")
		(net "M_A_DQ44")
	)
	(segment
		(start 143.1798 -69.475604)
		(end 143.1798 -68.961)
		(width 0.1778)
		(layer "F.Cu")
		(net "M_A_DQ44")
	)
	(via
		(at 143.2814 -68.8594)
		(size 0.4318)
		(drill 0.2032)
		(layers "F.Cu" "B.Cu")
		(net "M_A_DQ44")
	)
	(via
		(at 106.5784 -54.9148)
		(size 0.4318)
		(drill 0.2032)
		(layers "F.Cu" "B.Cu")
		(net "M_A_DQ44")
	)
	(segment
		(start 143.21409 -69.50329)
		(end 143.21409 -68.97751)
		(width 0.1778)
		(layer "B.Cu")
		(net "M_A_DQ44")
	)
	(segment
		(start 143.2814 -68.9102)
		(end 143.2814 -68.8594)
		(width 0.1778)
		(layer "B.Cu")
		(net "M_A_DQ44")
	)
	(segment
		(start 143.649954 -69.939154)
		(end 143.21409 -69.50329)
		(width 0.1778)
		(layer "B.Cu")
		(net "M_A_DQ44")
	)
	(segment
		(start 143.21409 -68.97751)
		(end 143.2814 -68.9102)
		(width 0.1778)
		(layer "B.Cu")
		(net "M_A_DQ44")
	)
	(segment
		(start 143.649954 -70.79996)
		(end 143.649954 -69.939154)
		(width 0.1778)
		(layer "B.Cu")
		(net "M_A_DQ44")
	)
	(segment
		(start 108.5596 -55.6006)
		(end 117.6782 -55.6006)
		(width 0.1524)
		(layer "In2.Cu")
		(net "M_A_DQ44")
	)
	(segment
		(start 119.253 -54.0258)
		(end 120.5738 -54.0258)
		(width 0.1524)
		(layer "In2.Cu")
		(net "M_A_DQ44")
	)
	(segment
		(start 145.7452 -58.647838)
		(end 145.7452 -65.6082)
		(width 0.1524)
		(layer "In2.Cu")
		(net "M_A_DQ44")
	)
	(segment
		(start 120.904 -54.356)
		(end 122.0978 -54.356)
		(width 0.1524)
		(layer "In2.Cu")
		(net "M_A_DQ44")
	)
	(segment
		(start 143.21409 -68.79209)
		(end 143.2814 -68.8594)
		(width 0.1524)
		(layer "In2.Cu")
		(net "M_A_DQ44")
	)
	(segment
		(start 106.5784 -54.9148)
		(end 106.6038 -54.9402)
		(width 0.1524)
		(layer "In2.Cu")
		(net "M_A_DQ44")
	)
	(segment
		(start 122.0978 -54.356)
		(end 122.428 -54.0258)
		(width 0.1524)
		(layer "In2.Cu")
		(net "M_A_DQ44")
	)
	(segment
		(start 141.123162 -54.0258)
		(end 145.7452 -58.647838)
		(width 0.1524)
		(layer "In2.Cu")
		(net "M_A_DQ44")
	)
	(segment
		(start 117.6782 -55.6006)
		(end 119.253 -54.0258)
		(width 0.1524)
		(layer "In2.Cu")
		(net "M_A_DQ44")
	)
	(segment
		(start 107.8992 -54.9402)
		(end 108.5596 -55.6006)
		(width 0.1524)
		(layer "In2.Cu")
		(net "M_A_DQ44")
	)
	(segment
		(start 122.428 -54.0258)
		(end 141.123162 -54.0258)
		(width 0.1524)
		(layer "In2.Cu")
		(net "M_A_DQ44")
	)
	(segment
		(start 120.5738 -54.0258)
		(end 120.904 -54.356)
		(width 0.1524)
		(layer "In2.Cu")
		(net "M_A_DQ44")
	)
	(segment
		(start 106.6038 -54.9402)
		(end 107.8992 -54.9402)
		(width 0.1524)
		(layer "In2.Cu")
		(net "M_A_DQ44")
	)
	(segment
		(start 143.21409 -68.13931)
		(end 143.21409 -68.79209)
		(width 0.1524)
		(layer "In2.Cu")
		(net "M_A_DQ44")
	)
	(segment
		(start 145.7452 -65.6082)
		(end 143.21409 -68.13931)
		(width 0.1524)
		(layer "In2.Cu")
		(net "M_A_DQ44")
	)
	(segment
		(start 99.2505 -24.511)
		(end 99.296728 -24.557228)
		(width 0.1016)
		(layer "F.Cu")
		(net "M_B_DQ20")
	)
	(segment
		(start 139.7 -3.151378)
		(end 139.7 -3.176778)
		(width 0.1778)
		(layer "F.Cu")
		(net "M_B_DQ20")
	)
	(segment
		(start 139.149836 -2.601214)
		(end 139.7 -3.151378)
		(width 0.1778)
		(layer "F.Cu")
		(net "M_B_DQ20")
	)
	(segment
		(start 99.754436 -26.896314)
		(end 100.406708 -26.896314)
		(width 0.1016)
		(layer "F.Cu")
		(net "M_B_DQ20")
	)
	(segment
		(start 99.296728 -26.438606)
		(end 99.754436 -26.896314)
		(width 0.1016)
		(layer "F.Cu")
		(net "M_B_DQ20")
	)
	(segment
		(start 139.149836 -1.68402)
		(end 139.149836 -2.601214)
		(width 0.1778)
		(layer "F.Cu")
		(net "M_B_DQ20")
	)
	(segment
		(start 99.296728 -24.557228)
		(end 99.296728 -26.438606)
		(width 0.1016)
		(layer "F.Cu")
		(net "M_B_DQ20")
	)
	(via
		(at 99.2505 -24.511)
		(size 0.4318)
		(drill 0.2032)
		(layers "F.Cu" "B.Cu")
		(net "M_B_DQ20")
	)
	(via
		(at 139.7 -3.176778)
		(size 0.4318)
		(drill 0.2032)
		(layers "F.Cu" "B.Cu")
		(net "M_B_DQ20")
	)
	(segment
		(start 139.7 -2.922778)
		(end 139.7 -3.176778)
		(width 0.1778)
		(layer "B.Cu")
		(net "M_B_DQ20")
	)
	(segment
		(start 140.050012 -1.690624)
		(end 140.050012 -2.572766)
		(width 0.1778)
		(layer "B.Cu")
		(net "M_B_DQ20")
	)
	(segment
		(start 140.050012 -2.572766)
		(end 139.7 -2.922778)
		(width 0.1778)
		(layer "B.Cu")
		(net "M_B_DQ20")
	)
	(segment
		(start 128.8288 -7.062978)
		(end 128.016 -7.875778)
		(width 0.1524)
		(layer "In4.Cu")
		(net "M_B_DQ20")
	)
	(segment
		(start 133.431026 -5.818378)
		(end 133.431026 -6.27126)
		(width 0.1524)
		(layer "In4.Cu")
		(net "M_B_DQ20")
	)
	(segment
		(start 133.583426 -5.665978)
		(end 133.431026 -5.818378)
		(width 0.1524)
		(layer "In4.Cu")
		(net "M_B_DQ20")
	)
	(segment
		(start 134.193026 -6.42366)
		(end 134.040626 -6.27126)
		(width 0.1524)
		(layer "In4.Cu")
		(net "M_B_DQ20")
	)
	(segment
		(start 134.040626 -5.818378)
		(end 133.888226 -5.665978)
		(width 0.1524)
		(layer "In4.Cu")
		(net "M_B_DQ20")
	)
	(segment
		(start 125.2474 -9.9314)
		(end 124.587 -9.271)
		(width 0.1524)
		(layer "In4.Cu")
		(net "M_B_DQ20")
	)
	(segment
		(start 139.7 -3.176778)
		(end 139.7 -3.227578)
		(width 0.1524)
		(layer "In4.Cu")
		(net "M_B_DQ20")
	)
	(segment
		(start 98.806 -24.0665)
		(end 99.2505 -24.511)
		(width 0.1016)
		(layer "In4.Cu")
		(net "M_B_DQ20")
	)
	(segment
		(start 114.357404 -9.271)
		(end 108.744004 -14.8844)
		(width 0.1524)
		(layer "In4.Cu")
		(net "M_B_DQ20")
	)
	(segment
		(start 103.148892 -14.8844)
		(end 98.806 -19.227292)
		(width 0.1524)
		(layer "In4.Cu")
		(net "M_B_DQ20")
	)
	(segment
		(start 133.431026 -6.27126)
		(end 133.278626 -6.42366)
		(width 0.1524)
		(layer "In4.Cu")
		(net "M_B_DQ20")
	)
	(segment
		(start 133.888226 -5.665978)
		(end 133.583426 -5.665978)
		(width 0.1524)
		(layer "In4.Cu")
		(net "M_B_DQ20")
	)
	(segment
		(start 98.806 -19.227292)
		(end 98.806 -24.0665)
		(width 0.1016)
		(layer "In4.Cu")
		(net "M_B_DQ20")
	)
	(segment
		(start 134.040626 -6.27126)
		(end 134.040626 -5.818378)
		(width 0.1524)
		(layer "In4.Cu")
		(net "M_B_DQ20")
	)
	(segment
		(start 133.278626 -6.42366)
		(end 132.262118 -6.42366)
		(width 0.1524)
		(layer "In4.Cu")
		(net "M_B_DQ20")
	)
	(segment
		(start 128.016 -9.4996)
		(end 127.5842 -9.9314)
		(width 0.1524)
		(layer "In4.Cu")
		(net "M_B_DQ20")
	)
	(segment
		(start 127.5842 -9.9314)
		(end 125.2474 -9.9314)
		(width 0.1524)
		(layer "In4.Cu")
		(net "M_B_DQ20")
	)
	(segment
		(start 108.744004 -14.8844)
		(end 103.148892 -14.8844)
		(width 0.1524)
		(layer "In4.Cu")
		(net "M_B_DQ20")
	)
	(segment
		(start 124.587 -9.271)
		(end 114.357404 -9.271)
		(width 0.1524)
		(layer "In4.Cu")
		(net "M_B_DQ20")
	)
	(segment
		(start 136.503918 -6.42366)
		(end 134.193026 -6.42366)
		(width 0.1524)
		(layer "In4.Cu")
		(net "M_B_DQ20")
	)
	(segment
		(start 139.7 -3.227578)
		(end 136.503918 -6.42366)
		(width 0.1524)
		(layer "In4.Cu")
		(net "M_B_DQ20")
	)
	(segment
		(start 132.262118 -6.42366)
		(end 131.6228 -7.062978)
		(width 0.1524)
		(layer "In4.Cu")
		(net "M_B_DQ20")
	)
	(segment
		(start 131.6228 -7.062978)
		(end 128.8288 -7.062978)
		(width 0.1524)
		(layer "In4.Cu")
		(net "M_B_DQ20")
	)
	(segment
		(start 128.016 -7.875778)
		(end 128.016 -9.4996)
		(width 0.1524)
		(layer "In4.Cu")
		(net "M_B_DQ20")
	)
	(segment
		(start 156.011372 -69.156326)
		(end 155.7401 -68.885054)
		(width 0.2413)
		(layer "F.Cu")
		(net "M_A_MA0")
	)
	(segment
		(start 154.547062 -67.69227)
		(end 154.547062 -66.396616)
		(width 0.2413)
		(layer "F.Cu")
		(net "M_A_MA0")
	)
	(segment
		(start 155.950158 -70.806564)
		(end 155.950158 -69.602096)
		(width 0.2413)
		(layer "F.Cu")
		(net "M_A_MA0")
	)
	(segment
		(start 156.011372 -69.540882)
		(end 156.011372 -69.156326)
		(width 0.2413)
		(layer "F.Cu")
		(net "M_A_MA0")
	)
	(segment
		(start 155.7401 -68.885054)
		(end 155.739846 -68.885054)
		(width 0.2413)
		(layer "F.Cu")
		(net "M_A_MA0")
	)
	(segment
		(start 155.220416 -66.037206)
		(end 155.373324 -65.884298)
		(width 0.2413)
		(layer "F.Cu")
		(net "M_A_MA0")
	)
	(segment
		(start 106.977434 -49.865788)
		(end 106.977434 -49.909984)
		(width 0.1016)
		(layer "F.Cu")
		(net "M_A_MA0")
	)
	(segment
		(start 154.906472 -66.037206)
		(end 155.220416 -66.037206)
		(width 0.2413)
		(layer "F.Cu")
		(net "M_A_MA0")
	)
	(segment
		(start 107.297728 -49.545494)
		(end 106.977434 -49.865788)
		(width 0.1016)
		(layer "F.Cu")
		(net "M_A_MA0")
	)
	(segment
		(start 155.950158 -69.602096)
		(end 156.011372 -69.540882)
		(width 0.2413)
		(layer "F.Cu")
		(net "M_A_MA0")
	)
	(segment
		(start 154.547062 -66.396616)
		(end 154.906472 -66.037206)
		(width 0.2413)
		(layer "F.Cu")
		(net "M_A_MA0")
	)
	(segment
		(start 155.739846 -68.885054)
		(end 154.547062 -67.69227)
		(width 0.2413)
		(layer "F.Cu")
		(net "M_A_MA0")
	)
	(via
		(at 155.373324 -65.884298)
		(size 0.4318)
		(drill 0.2032)
		(layers "F.Cu" "B.Cu")
		(net "M_A_MA0")
	)
	(via
		(at 106.977434 -49.909984)
		(size 0.4318)
		(drill 0.2032)
		(layers "F.Cu" "B.Cu")
		(net "M_A_MA0")
	)
	(segment
		(start 155.369514 -65.46469)
		(end 155.369514 -65.880488)
		(width 0.2413)
		(layer "B.Cu")
		(net "M_A_MA0")
	)
	(segment
		(start 155.950158 -62.599824)
		(end 155.950158 -64.884046)
		(width 0.2413)
		(layer "B.Cu")
		(net "M_A_MA0")
	)
	(segment
		(start 155.369514 -65.880488)
		(end 155.373324 -65.884298)
		(width 0.2413)
		(layer "B.Cu")
		(net "M_A_MA0")
	)
	(segment
		(start 155.950158 -64.884046)
		(end 155.369514 -65.46469)
		(width 0.2413)
		(layer "B.Cu")
		(net "M_A_MA0")
	)
	(segment
		(start 125.06325 -54.43855)
		(end 125.06325 -54.19725)
		(width 0.1905)
		(layer "In9.Cu")
		(net "M_A_MA0")
	)
	(segment
		(start 145.64487 -54.62905)
		(end 129.283714 -54.62905)
		(width 0.1905)
		(layer "In9.Cu")
		(net "M_A_MA0")
	)
	(segment
		(start 155.373324 -65.884298)
		(end 155.471622 -65.884298)
		(width 0.1905)
		(layer "In9.Cu")
		(net "M_A_MA0")
	)
	(segment
		(start 146.091656 -55.075836)
		(end 145.64487 -54.62905)
		(width 0.1905)
		(layer "In9.Cu")
		(net "M_A_MA0")
	)
	(segment
		(start 108.4072 -52.7812)
		(end 107.823 -52.7812)
		(width 0.1016)
		(layer "In9.Cu")
		(net "M_A_MA0")
	)
	(segment
		(start 124.87275 -54.00675)
		(end 124.49175 -54.00675)
		(width 0.1905)
		(layer "In9.Cu")
		(net "M_A_MA0")
	)
	(segment
		(start 123.34875 -54.00675)
		(end 122.96775 -54.00675)
		(width 0.1905)
		(layer "In9.Cu")
		(net "M_A_MA0")
	)
	(segment
		(start 152.120854 -59.69635)
		(end 148.302726 -55.878222)
		(width 0.1905)
		(layer "In9.Cu")
		(net "M_A_MA0")
	)
	(segment
		(start 108.966 -53.34)
		(end 108.4072 -52.7812)
		(width 0.1016)
		(layer "In9.Cu")
		(net "M_A_MA0")
	)
	(segment
		(start 125.63475 -54.62905)
		(end 125.25375 -54.62905)
		(width 0.1905)
		(layer "In9.Cu")
		(net "M_A_MA0")
	)
	(segment
		(start 122.96775 -54.00675)
		(end 122.77725 -54.19725)
		(width 0.1905)
		(layer "In9.Cu")
		(net "M_A_MA0")
	)
	(segment
		(start 126.01575 -54.00675)
		(end 125.82525 -54.19725)
		(width 0.1905)
		(layer "In9.Cu")
		(net "M_A_MA0")
	)
	(segment
		(start 110.14075 -54.51475)
		(end 108.966 -53.34)
		(width 0.1905)
		(layer "In9.Cu")
		(net "M_A_MA0")
	)
	(segment
		(start 118.66245 -54.00675)
		(end 118.15445 -54.51475)
		(width 0.1905)
		(layer "In9.Cu")
		(net "M_A_MA0")
	)
	(segment
		(start 152.410922 -59.69635)
		(end 152.120854 -59.69635)
		(width 0.1905)
		(layer "In9.Cu")
		(net "M_A_MA0")
	)
	(segment
		(start 124.30125 -54.43855)
		(end 124.11075 -54.62905)
		(width 0.1905)
		(layer "In9.Cu")
		(net "M_A_MA0")
	)
	(segment
		(start 124.11075 -54.62905)
		(end 123.72975 -54.62905)
		(width 0.1905)
		(layer "In9.Cu")
		(net "M_A_MA0")
	)
	(segment
		(start 122.01525 -54.19725)
		(end 121.82475 -54.00675)
		(width 0.1905)
		(layer "In9.Cu")
		(net "M_A_MA0")
	)
	(segment
		(start 124.30125 -54.19725)
		(end 124.30125 -54.43855)
		(width 0.1905)
		(layer "In9.Cu")
		(net "M_A_MA0")
	)
	(segment
		(start 125.25375 -54.62905)
		(end 125.06325 -54.43855)
		(width 0.1905)
		(layer "In9.Cu")
		(net "M_A_MA0")
	)
	(segment
		(start 128.661414 -54.00675)
		(end 127.53975 -54.00675)
		(width 0.1905)
		(layer "In9.Cu")
		(net "M_A_MA0")
	)
	(segment
		(start 147.329398 -56.31307)
		(end 147.05965 -56.043322)
		(width 0.1905)
		(layer "In9.Cu")
		(net "M_A_MA0")
	)
	(segment
		(start 122.20575 -54.62905)
		(end 122.01525 -54.43855)
		(width 0.1905)
		(layer "In9.Cu")
		(net "M_A_MA0")
	)
	(segment
		(start 147.074636 -55.075836)
		(end 146.091656 -55.075836)
		(width 0.1905)
		(layer "In9.Cu")
		(net "M_A_MA0")
	)
	(segment
		(start 107.4166 -50.34915)
		(end 106.977434 -49.909984)
		(width 0.1016)
		(layer "In9.Cu")
		(net "M_A_MA0")
	)
	(segment
		(start 127.53975 -54.00675)
		(end 127.34925 -54.19725)
		(width 0.1905)
		(layer "In9.Cu")
		(net "M_A_MA0")
	)
	(segment
		(start 124.49175 -54.00675)
		(end 124.30125 -54.19725)
		(width 0.1905)
		(layer "In9.Cu")
		(net "M_A_MA0")
	)
	(segment
		(start 147.598638 -56.31307)
		(end 147.329398 -56.31307)
		(width 0.1905)
		(layer "In9.Cu")
		(net "M_A_MA0")
	)
	(segment
		(start 107.4166 -51.0794)
		(end 107.4166 -50.34915)
		(width 0.1016)
		(layer "In9.Cu")
		(net "M_A_MA0")
	)
	(segment
		(start 123.72975 -54.62905)
		(end 123.53925 -54.43855)
		(width 0.1905)
		(layer "In9.Cu")
		(net "M_A_MA0")
	)
	(segment
		(start 148.302726 -55.878222)
		(end 148.033486 -55.878222)
		(width 0.1905)
		(layer "In9.Cu")
		(net "M_A_MA0")
	)
	(segment
		(start 123.53925 -54.19725)
		(end 123.34875 -54.00675)
		(width 0.1905)
		(layer "In9.Cu")
		(net "M_A_MA0")
	)
	(segment
		(start 129.283714 -54.62905)
		(end 128.661414 -54.00675)
		(width 0.1905)
		(layer "In9.Cu")
		(net "M_A_MA0")
	)
	(segment
		(start 125.82525 -54.19725)
		(end 125.82525 -54.43855)
		(width 0.1905)
		(layer "In9.Cu")
		(net "M_A_MA0")
	)
	(segment
		(start 127.34925 -54.19725)
		(end 127.34925 -54.43855)
		(width 0.1905)
		(layer "In9.Cu")
		(net "M_A_MA0")
	)
	(segment
		(start 147.05965 -56.043322)
		(end 147.05965 -55.774082)
		(width 0.1905)
		(layer "In9.Cu")
		(net "M_A_MA0")
	)
	(segment
		(start 147.05965 -55.774082)
		(end 147.2692 -55.564532)
		(width 0.1905)
		(layer "In9.Cu")
		(net "M_A_MA0")
	)
	(segment
		(start 147.2692 -55.2704)
		(end 147.074636 -55.075836)
		(width 0.1905)
		(layer "In9.Cu")
		(net "M_A_MA0")
	)
	(segment
		(start 122.77725 -54.19725)
		(end 122.77725 -54.43855)
		(width 0.1905)
		(layer "In9.Cu")
		(net "M_A_MA0")
	)
	(segment
		(start 126.58725 -54.19725)
		(end 126.39675 -54.00675)
		(width 0.1905)
		(layer "In9.Cu")
		(net "M_A_MA0")
	)
	(segment
		(start 127.34925 -54.43855)
		(end 127.15875 -54.62905)
		(width 0.1905)
		(layer "In9.Cu")
		(net "M_A_MA0")
	)
	(segment
		(start 122.58675 -54.62905)
		(end 122.20575 -54.62905)
		(width 0.1905)
		(layer "In9.Cu")
		(net "M_A_MA0")
	)
	(segment
		(start 126.58725 -54.43855)
		(end 126.58725 -54.19725)
		(width 0.1905)
		(layer "In9.Cu")
		(net "M_A_MA0")
	)
	(segment
		(start 126.77775 -54.62905)
		(end 126.58725 -54.43855)
		(width 0.1905)
		(layer "In9.Cu")
		(net "M_A_MA0")
	)
	(segment
		(start 123.53925 -54.43855)
		(end 123.53925 -54.19725)
		(width 0.1905)
		(layer "In9.Cu")
		(net "M_A_MA0")
	)
	(segment
		(start 147.2692 -55.564532)
		(end 147.2692 -55.2704)
		(width 0.1905)
		(layer "In9.Cu")
		(net "M_A_MA0")
	)
	(segment
		(start 127.15875 -54.62905)
		(end 126.77775 -54.62905)
		(width 0.1905)
		(layer "In9.Cu")
		(net "M_A_MA0")
	)
	(segment
		(start 107.508294 -52.466494)
		(end 107.508294 -51.171094)
		(width 0.1016)
		(layer "In9.Cu")
		(net "M_A_MA0")
	)
	(segment
		(start 121.82475 -54.00675)
		(end 118.66245 -54.00675)
		(width 0.1905)
		(layer "In9.Cu")
		(net "M_A_MA0")
	)
	(segment
		(start 107.508294 -51.171094)
		(end 107.4166 -51.0794)
		(width 0.1016)
		(layer "In9.Cu")
		(net "M_A_MA0")
	)
	(segment
		(start 156.1592 -65.19672)
		(end 156.1592 -63.444628)
		(width 0.1905)
		(layer "In9.Cu")
		(net "M_A_MA0")
	)
	(segment
		(start 122.77725 -54.43855)
		(end 122.58675 -54.62905)
		(width 0.1905)
		(layer "In9.Cu")
		(net "M_A_MA0")
	)
	(segment
		(start 156.1592 -63.444628)
		(end 152.410922 -59.69635)
		(width 0.1905)
		(layer "In9.Cu")
		(net "M_A_MA0")
	)
	(segment
		(start 118.15445 -54.51475)
		(end 110.14075 -54.51475)
		(width 0.1905)
		(layer "In9.Cu")
		(net "M_A_MA0")
	)
	(segment
		(start 125.06325 -54.19725)
		(end 124.87275 -54.00675)
		(width 0.1905)
		(layer "In9.Cu")
		(net "M_A_MA0")
	)
	(segment
		(start 122.01525 -54.43855)
		(end 122.01525 -54.19725)
		(width 0.1905)
		(layer "In9.Cu")
		(net "M_A_MA0")
	)
	(segment
		(start 107.823 -52.7812)
		(end 107.508294 -52.466494)
		(width 0.1016)
		(layer "In9.Cu")
		(net "M_A_MA0")
	)
	(segment
		(start 155.471622 -65.884298)
		(end 156.1592 -65.19672)
		(width 0.1905)
		(layer "In9.Cu")
		(net "M_A_MA0")
	)
	(segment
		(start 148.033486 -55.878222)
		(end 147.598638 -56.31307)
		(width 0.1905)
		(layer "In9.Cu")
		(net "M_A_MA0")
	)
	(segment
		(start 126.39675 -54.00675)
		(end 126.01575 -54.00675)
		(width 0.1905)
		(layer "In9.Cu")
		(net "M_A_MA0")
	)
	(segment
		(start 125.82525 -54.43855)
		(end 125.63475 -54.62905)
		(width 0.1905)
		(layer "In9.Cu")
		(net "M_A_MA0")
	)
	(segment
		(start 116.4082 -30.8102)
		(end 114.8334 -30.8102)
		(width 0.1016)
		(layer "F.Cu")
		(net "M_B_DQ41")
	)
	(segment
		(start 111.734854 -33.947608)
		(end 111.603028 -34.079434)
		(width 0.1016)
		(layer "F.Cu")
		(net "M_B_DQ41")
	)
	(segment
		(start 116.8654 -31.2674)
		(end 116.4082 -30.8102)
		(width 0.1016)
		(layer "F.Cu")
		(net "M_B_DQ41")
	)
	(segment
		(start 175.9204 -7.774178)
		(end 176.0982 -7.774178)
		(width 0.1778)
		(layer "F.Cu")
		(net "M_B_DQ41")
	)
	(segment
		(start 114.5794 -31.0642)
		(end 114.5794 -31.622746)
		(width 0.1016)
		(layer "F.Cu")
		(net "M_B_DQ41")
	)
	(segment
		(start 175.6918 -8.002778)
		(end 175.9204 -7.774178)
		(width 0.1778)
		(layer "F.Cu")
		(net "M_B_DQ41")
	)
	(segment
		(start 114.8334 -30.8102)
		(end 114.5794 -31.0642)
		(width 0.1016)
		(layer "F.Cu")
		(net "M_B_DQ41")
	)
	(segment
		(start 175.449992 -8.879586)
		(end 175.6918 -8.637778)
		(width 0.1778)
		(layer "F.Cu")
		(net "M_B_DQ41")
	)
	(segment
		(start 114.5794 -31.622746)
		(end 112.254792 -33.947608)
		(width 0.1016)
		(layer "F.Cu")
		(net "M_B_DQ41")
	)
	(segment
		(start 175.6918 -8.637778)
		(end 175.6918 -8.002778)
		(width 0.1778)
		(layer "F.Cu")
		(net "M_B_DQ41")
	)
	(segment
		(start 112.254792 -33.947608)
		(end 111.734854 -33.947608)
		(width 0.1016)
		(layer "F.Cu")
		(net "M_B_DQ41")
	)
	(segment
		(start 175.449992 -9.897364)
		(end 175.449992 -8.879586)
		(width 0.1778)
		(layer "F.Cu")
		(net "M_B_DQ41")
	)
	(via
		(at 116.8654 -31.2674)
		(size 0.4318)
		(drill 0.2032)
		(layers "F.Cu" "B.Cu")
		(net "M_B_DQ41")
	)
	(via
		(at 176.0982 -7.774178)
		(size 0.4318)
		(drill 0.2032)
		(layers "F.Cu" "B.Cu")
		(net "M_B_DQ41")
	)
	(segment
		(start 176.349914 -9.89076)
		(end 176.349914 -9.194292)
		(width 0.1778)
		(layer "B.Cu")
		(net "M_B_DQ41")
	)
	(segment
		(start 175.768 -8.612378)
		(end 175.768 -8.104378)
		(width 0.1778)
		(layer "B.Cu")
		(net "M_B_DQ41")
	)
	(segment
		(start 176.349914 -9.194292)
		(end 175.768 -8.612378)
		(width 0.1778)
		(layer "B.Cu")
		(net "M_B_DQ41")
	)
	(segment
		(start 175.768 -8.104378)
		(end 176.0982 -7.774178)
		(width 0.1778)
		(layer "B.Cu")
		(net "M_B_DQ41")
	)
	(segment
		(start 155.411424 -26.503376)
		(end 155.195524 -26.719276)
		(width 0.1524)
		(layer "In2.Cu")
		(net "M_B_DQ41")
	)
	(segment
		(start 117.221 -31.2674)
		(end 118.455186 -30.033214)
		(width 0.1016)
		(layer "In2.Cu")
		(net "M_B_DQ41")
	)
	(segment
		(start 155.386024 -25.4)
		(end 155.170632 -25.4)
		(width 0.1524)
		(layer "In2.Cu")
		(net "M_B_DQ41")
	)
	(segment
		(start 156.033216 -24.537416)
		(end 155.817316 -24.753316)
		(width 0.1524)
		(layer "In2.Cu")
		(net "M_B_DQ41")
	)
	(segment
		(start 160.750504 -20.305268)
		(end 160.750504 -20.52066)
		(width 0.1524)
		(layer "In2.Cu")
		(net "M_B_DQ41")
	)
	(segment
		(start 155.842716 -25.856692)
		(end 155.386024 -25.4)
		(width 0.1524)
		(layer "In2.Cu")
		(net "M_B_DQ41")
	)
	(segment
		(start 155.817316 -24.968708)
		(end 156.274008 -25.4254)
		(width 0.1524)
		(layer "In2.Cu")
		(net "M_B_DQ41")
	)
	(segment
		(start 175.035718 -9.647682)
		(end 174.853346 -9.647682)
		(width 0.1524)
		(layer "In2.Cu")
		(net "M_B_DQ41")
	)
	(segment
		(start 160.647126 -21.064474)
		(end 160.431734 -21.064474)
		(width 0.1524)
		(layer "In2.Cu")
		(net "M_B_DQ41")
	)
	(segment
		(start 155.817316 -24.753316)
		(end 155.817316 -24.968708)
		(width 0.1524)
		(layer "In2.Cu")
		(net "M_B_DQ41")
	)
	(segment
		(start 156.248608 -24.537416)
		(end 156.033216 -24.537416)
		(width 0.1524)
		(layer "In2.Cu")
		(net "M_B_DQ41")
	)
	(segment
		(start 161.61131 -20.30349)
		(end 161.395918 -20.30349)
		(width 0.1524)
		(layer "In2.Cu")
		(net "M_B_DQ41")
	)
	(segment
		(start 154.13482 -27.77998)
		(end 125.839728 -27.77998)
		(width 0.1524)
		(layer "In2.Cu")
		(net "M_B_DQ41")
	)
	(segment
		(start 155.170632 -25.4)
		(end 154.954732 -25.6159)
		(width 0.1524)
		(layer "In2.Cu")
		(net "M_B_DQ41")
	)
	(segment
		(start 159.733234 -21.013166)
		(end 159.733234 -21.228558)
		(width 0.1524)
		(layer "In2.Cu")
		(net "M_B_DQ41")
	)
	(segment
		(start 154.092148 -26.693876)
		(end 154.54884 -27.150568)
		(width 0.1524)
		(layer "In2.Cu")
		(net "M_B_DQ41")
	)
	(segment
		(start 154.092148 -26.478484)
		(end 154.092148 -26.693876)
		(width 0.1524)
		(layer "In2.Cu")
		(net "M_B_DQ41")
	)
	(segment
		(start 161.181796 -20.089368)
		(end 160.966404 -20.089368)
		(width 0.1524)
		(layer "In2.Cu")
		(net "M_B_DQ41")
	)
	(segment
		(start 154.954732 -25.831292)
		(end 155.411424 -26.287984)
		(width 0.1524)
		(layer "In2.Cu")
		(net "M_B_DQ41")
	)
	(segment
		(start 154.954732 -25.6159)
		(end 154.954732 -25.831292)
		(width 0.1524)
		(layer "In2.Cu")
		(net "M_B_DQ41")
	)
	(segment
		(start 155.195524 -26.719276)
		(end 154.980132 -26.719276)
		(width 0.1524)
		(layer "In2.Cu")
		(net "M_B_DQ41")
	)
	(segment
		(start 160.863026 -20.848574)
		(end 160.647126 -21.064474)
		(width 0.1524)
		(layer "In2.Cu")
		(net "M_B_DQ41")
	)
	(segment
		(start 160.164526 -20.797266)
		(end 159.949134 -20.797266)
		(width 0.1524)
		(layer "In2.Cu")
		(net "M_B_DQ41")
	)
	(segment
		(start 156.7053 -24.994108)
		(end 156.248608 -24.537416)
		(width 0.1524)
		(layer "In2.Cu")
		(net "M_B_DQ41")
	)
	(segment
		(start 175.3743 -9.3091)
		(end 175.035718 -9.647682)
		(width 0.1524)
		(layer "In2.Cu")
		(net "M_B_DQ41")
	)
	(segment
		(start 154.54884 -27.36596)
		(end 154.13482 -27.77998)
		(width 0.1524)
		(layer "In2.Cu")
		(net "M_B_DQ41")
	)
	(segment
		(start 154.980132 -26.719276)
		(end 154.52344 -26.262584)
		(width 0.1524)
		(layer "In2.Cu")
		(net "M_B_DQ41")
	)
	(segment
		(start 123.586494 -30.033214)
		(end 118.455186 -30.033214)
		(width 0.1524)
		(layer "In2.Cu")
		(net "M_B_DQ41")
	)
	(segment
		(start 159.949134 -20.797266)
		(end 159.733234 -21.013166)
		(width 0.1524)
		(layer "In2.Cu")
		(net "M_B_DQ41")
	)
	(segment
		(start 159.733234 -21.228558)
		(end 160.102042 -21.597366)
		(width 0.1524)
		(layer "In2.Cu")
		(net "M_B_DQ41")
	)
	(segment
		(start 154.54884 -27.150568)
		(end 154.54884 -27.36596)
		(width 0.1524)
		(layer "In2.Cu")
		(net "M_B_DQ41")
	)
	(segment
		(start 160.750504 -20.52066)
		(end 160.863026 -20.633182)
		(width 0.1524)
		(layer "In2.Cu")
		(net "M_B_DQ41")
	)
	(segment
		(start 160.966404 -20.089368)
		(end 160.750504 -20.305268)
		(width 0.1524)
		(layer "In2.Cu")
		(net "M_B_DQ41")
	)
	(segment
		(start 155.411424 -26.287984)
		(end 155.411424 -26.503376)
		(width 0.1524)
		(layer "In2.Cu")
		(net "M_B_DQ41")
	)
	(segment
		(start 165.1 -16.8148)
		(end 161.61131 -20.30349)
		(width 0.1524)
		(layer "In2.Cu")
		(net "M_B_DQ41")
	)
	(segment
		(start 167.686228 -16.8148)
		(end 165.1 -16.8148)
		(width 0.1524)
		(layer "In2.Cu")
		(net "M_B_DQ41")
	)
	(segment
		(start 174.853346 -9.647682)
		(end 167.686228 -16.8148)
		(width 0.1524)
		(layer "In2.Cu")
		(net "M_B_DQ41")
	)
	(segment
		(start 116.8654 -31.2674)
		(end 117.221 -31.2674)
		(width 0.1016)
		(layer "In2.Cu")
		(net "M_B_DQ41")
	)
	(segment
		(start 156.920692 -24.994108)
		(end 156.7053 -24.994108)
		(width 0.1524)
		(layer "In2.Cu")
		(net "M_B_DQ41")
	)
	(segment
		(start 176.0474 -7.774178)
		(end 175.3743 -8.447278)
		(width 0.1524)
		(layer "In2.Cu")
		(net "M_B_DQ41")
	)
	(segment
		(start 160.102042 -21.597366)
		(end 160.102042 -21.812758)
		(width 0.1524)
		(layer "In2.Cu")
		(net "M_B_DQ41")
	)
	(segment
		(start 156.274008 -25.4254)
		(end 156.274008 -25.640792)
		(width 0.1524)
		(layer "In2.Cu")
		(net "M_B_DQ41")
	)
	(segment
		(start 154.52344 -26.262584)
		(end 154.308048 -26.262584)
		(width 0.1524)
		(layer "In2.Cu")
		(net "M_B_DQ41")
	)
	(segment
		(start 176.0982 -7.774178)
		(end 176.0474 -7.774178)
		(width 0.1524)
		(layer "In2.Cu")
		(net "M_B_DQ41")
	)
	(segment
		(start 156.274008 -25.640792)
		(end 156.058108 -25.856692)
		(width 0.1524)
		(layer "In2.Cu")
		(net "M_B_DQ41")
	)
	(segment
		(start 156.058108 -25.856692)
		(end 155.842716 -25.856692)
		(width 0.1524)
		(layer "In2.Cu")
		(net "M_B_DQ41")
	)
	(segment
		(start 125.839728 -27.77998)
		(end 123.586494 -30.033214)
		(width 0.1524)
		(layer "In2.Cu")
		(net "M_B_DQ41")
	)
	(segment
		(start 161.395918 -20.30349)
		(end 161.181796 -20.089368)
		(width 0.1524)
		(layer "In2.Cu")
		(net "M_B_DQ41")
	)
	(segment
		(start 160.863026 -20.633182)
		(end 160.863026 -20.848574)
		(width 0.1524)
		(layer "In2.Cu")
		(net "M_B_DQ41")
	)
	(segment
		(start 160.102042 -21.812758)
		(end 156.920692 -24.994108)
		(width 0.1524)
		(layer "In2.Cu")
		(net "M_B_DQ41")
	)
	(segment
		(start 175.3743 -8.447278)
		(end 175.3743 -9.3091)
		(width 0.1524)
		(layer "In2.Cu")
		(net "M_B_DQ41")
	)
	(segment
		(start 154.308048 -26.262584)
		(end 154.092148 -26.478484)
		(width 0.1524)
		(layer "In2.Cu")
		(net "M_B_DQ41")
	)
	(segment
		(start 160.431734 -21.064474)
		(end 160.164526 -20.797266)
		(width 0.1524)
		(layer "In2.Cu")
		(net "M_B_DQ41")
	)
	(segment
		(start 96.4438 -55.6768)
		(end 96.8375 -55.2831)
		(width 0.1016)
		(layer "F.Cu")
		(net "M_A_DQ56")
	)
	(segment
		(start 96.8375 -55.2831)
		(end 96.8375 -53.6829)
		(width 0.1016)
		(layer "F.Cu")
		(net "M_A_DQ56")
	)
	(segment
		(start 96.477836 -51.964082)
		(end 96.467168 -51.953414)
		(width 0.1016)
		(layer "F.Cu")
		(net "M_A_DQ56")
	)
	(segment
		(start 133.5278 -63.85433)
		(end 133.5278 -64.389)
		(width 0.1778)
		(layer "F.Cu")
		(net "M_A_DQ56")
	)
	(segment
		(start 133.78561 -64.64681)
		(end 133.78561 -64.6938)
		(width 0.1778)
		(layer "F.Cu")
		(net "M_A_DQ56")
	)
	(segment
		(start 96.8375 -53.6829)
		(end 96.477836 -53.323236)
		(width 0.1016)
		(layer "F.Cu")
		(net "M_A_DQ56")
	)
	(segment
		(start 133.5278 -64.389)
		(end 133.78561 -64.64681)
		(width 0.1778)
		(layer "F.Cu")
		(net "M_A_DQ56")
	)
	(segment
		(start 96.477836 -53.323236)
		(end 96.477836 -51.964082)
		(width 0.1016)
		(layer "F.Cu")
		(net "M_A_DQ56")
	)
	(segment
		(start 134.050024 -63.332106)
		(end 133.5278 -63.85433)
		(width 0.1778)
		(layer "F.Cu")
		(net "M_A_DQ56")
	)
	(segment
		(start 134.050024 -62.59322)
		(end 134.050024 -63.332106)
		(width 0.1778)
		(layer "F.Cu")
		(net "M_A_DQ56")
	)
	(via
		(at 96.4438 -55.6768)
		(size 0.4318)
		(drill 0.2032)
		(layers "F.Cu" "B.Cu")
		(net "M_A_DQ56")
	)
	(via
		(at 133.78561 -64.6938)
		(size 0.4318)
		(drill 0.2032)
		(layers "F.Cu" "B.Cu")
		(net "M_A_DQ56")
	)
	(segment
		(start 133.150102 -63.528702)
		(end 133.4008 -63.7794)
		(width 0.1778)
		(layer "B.Cu")
		(net "M_A_DQ56")
	)
	(segment
		(start 133.4008 -63.7794)
		(end 133.4008 -64.30899)
		(width 0.1778)
		(layer "B.Cu")
		(net "M_A_DQ56")
	)
	(segment
		(start 133.4008 -64.30899)
		(end 133.78561 -64.6938)
		(width 0.1778)
		(layer "B.Cu")
		(net "M_A_DQ56")
	)
	(segment
		(start 133.150102 -62.599824)
		(end 133.150102 -63.528702)
		(width 0.1778)
		(layer "B.Cu")
		(net "M_A_DQ56")
	)
	(segment
		(start 132.8674 -63.6016)
		(end 132.715 -63.4492)
		(width 0.1524)
		(layer "In7.Cu")
		(net "M_A_DQ56")
	)
	(segment
		(start 123.1646 -63.8048)
		(end 123.1646 -64.163702)
		(width 0.1524)
		(layer "In7.Cu")
		(net "M_A_DQ56")
	)
	(segment
		(start 96.393 -58.4708)
		(end 96.393 -55.7276)
		(width 0.1016)
		(layer "In7.Cu")
		(net "M_A_DQ56")
	)
	(segment
		(start 97.863152 -59.940952)
		(end 96.393 -58.4708)
		(width 0.1016)
		(layer "In7.Cu")
		(net "M_A_DQ56")
	)
	(segment
		(start 133.1468 -63.6016)
		(end 132.8674 -63.6016)
		(width 0.1524)
		(layer "In7.Cu")
		(net "M_A_DQ56")
	)
	(segment
		(start 122.379486 -63.6524)
		(end 122.074686 -63.6524)
		(width 0.1524)
		(layer "In7.Cu")
		(net "M_A_DQ56")
	)
	(segment
		(start 126.7714 -63.7286)
		(end 126.619 -63.881)
		(width 0.1524)
		(layer "In7.Cu")
		(net "M_A_DQ56")
	)
	(segment
		(start 97.863152 -61.339476)
		(end 97.863152 -59.940952)
		(width 0.1524)
		(layer "In7.Cu")
		(net "M_A_DQ56")
	)
	(segment
		(start 133.71195 -62.8142)
		(end 133.4516 -62.8142)
		(width 0.1524)
		(layer "In7.Cu")
		(net "M_A_DQ56")
	)
	(segment
		(start 132.4864 -62.6872)
		(end 127 -62.6872)
		(width 0.1524)
		(layer "In7.Cu")
		(net "M_A_DQ56")
	)
	(segment
		(start 116.841524 -63.7286)
		(end 116.689124 -63.881)
		(width 0.1524)
		(layer "In7.Cu")
		(net "M_A_DQ56")
	)
	(segment
		(start 117.451124 -64.316102)
		(end 117.298724 -64.163702)
		(width 0.1524)
		(layer "In7.Cu")
		(net "M_A_DQ56")
	)
	(segment
		(start 115.469924 -64.163702)
		(end 115.317524 -64.316102)
		(width 0.1524)
		(layer "In7.Cu")
		(net "M_A_DQ56")
	)
	(segment
		(start 116.536724 -64.316102)
		(end 116.231924 -64.316102)
		(width 0.1524)
		(layer "In7.Cu")
		(net "M_A_DQ56")
	)
	(segment
		(start 115.622324 -63.7794)
		(end 115.469924 -63.9318)
		(width 0.1524)
		(layer "In7.Cu")
		(net "M_A_DQ56")
	)
	(segment
		(start 114.707924 -63.6524)
		(end 114.403124 -63.6524)
		(width 0.1524)
		(layer "In7.Cu")
		(net "M_A_DQ56")
	)
	(segment
		(start 121.769886 -64.316102)
		(end 121.465086 -64.316102)
		(width 0.1524)
		(layer "In7.Cu")
		(net "M_A_DQ56")
	)
	(segment
		(start 116.231924 -64.316102)
		(end 116.079524 -64.163702)
		(width 0.1524)
		(layer "In7.Cu")
		(net "M_A_DQ56")
	)
	(segment
		(start 120.703086 -64.163702)
		(end 120.550686 -64.316102)
		(width 0.1524)
		(layer "In7.Cu")
		(net "M_A_DQ56")
	)
	(segment
		(start 116.689124 -63.881)
		(end 116.689124 -64.163702)
		(width 0.1524)
		(layer "In7.Cu")
		(net "M_A_DQ56")
	)
	(segment
		(start 126.619 -63.881)
		(end 125.8824 -63.881)
		(width 0.1524)
		(layer "In7.Cu")
		(net "M_A_DQ56")
	)
	(segment
		(start 96.393 -55.7276)
		(end 96.4438 -55.6768)
		(width 0.1016)
		(layer "In7.Cu")
		(net "M_A_DQ56")
	)
	(segment
		(start 117.298724 -63.881)
		(end 117.146324 -63.7286)
		(width 0.1524)
		(layer "In7.Cu")
		(net "M_A_DQ56")
	)
	(segment
		(start 123.1646 -64.163702)
		(end 123.0122 -64.316102)
		(width 0.1524)
		(layer "In7.Cu")
		(net "M_A_DQ56")
	)
	(segment
		(start 133.5405 -64.418464)
		(end 133.5405 -63.859664)
		(width 0.1524)
		(layer "In7.Cu")
		(net "M_A_DQ56")
	)
	(segment
		(start 100.785676 -64.262)
		(end 97.863152 -61.339476)
		(width 0.1524)
		(layer "In7.Cu")
		(net "M_A_DQ56")
	)
	(segment
		(start 121.312686 -63.8048)
		(end 121.160286 -63.6524)
		(width 0.1524)
		(layer "In7.Cu")
		(net "M_A_DQ56")
	)
	(segment
		(start 133.5405 -63.859664)
		(end 133.86435 -63.535814)
		(width 0.1524)
		(layer "In7.Cu")
		(net "M_A_DQ56")
	)
	(segment
		(start 115.927124 -63.7794)
		(end 115.622324 -63.7794)
		(width 0.1524)
		(layer "In7.Cu")
		(net "M_A_DQ56")
	)
	(segment
		(start 133.2992 -63.4492)
		(end 133.1468 -63.6016)
		(width 0.1524)
		(layer "In7.Cu")
		(net "M_A_DQ56")
	)
	(segment
		(start 133.86435 -62.9666)
		(end 133.71195 -62.8142)
		(width 0.1524)
		(layer "In7.Cu")
		(net "M_A_DQ56")
	)
	(segment
		(start 114.860324 -63.8048)
		(end 114.707924 -63.6524)
		(width 0.1524)
		(layer "In7.Cu")
		(net "M_A_DQ56")
	)
	(segment
		(start 117.298724 -64.163702)
		(end 117.298724 -63.881)
		(width 0.1524)
		(layer "In7.Cu")
		(net "M_A_DQ56")
	)
	(segment
		(start 115.469924 -63.9318)
		(end 115.469924 -64.163702)
		(width 0.1524)
		(layer "In7.Cu")
		(net "M_A_DQ56")
	)
	(segment
		(start 133.78561 -64.6938)
		(end 133.78561 -64.663574)
		(width 0.1524)
		(layer "In7.Cu")
		(net "M_A_DQ56")
	)
	(segment
		(start 105.037382 -63.913258)
		(end 104.299258 -63.913258)
		(width 0.1524)
		(layer "In7.Cu")
		(net "M_A_DQ56")
	)
	(segment
		(start 125.6538 -63.6524)
		(end 123.317 -63.6524)
		(width 0.1524)
		(layer "In7.Cu")
		(net "M_A_DQ56")
	)
	(segment
		(start 127 -62.6872)
		(end 126.7714 -62.9158)
		(width 0.1524)
		(layer "In7.Cu")
		(net "M_A_DQ56")
	)
	(segment
		(start 120.703086 -63.8048)
		(end 120.703086 -64.163702)
		(width 0.1524)
		(layer "In7.Cu")
		(net "M_A_DQ56")
	)
	(segment
		(start 114.250724 -63.8048)
		(end 114.250724 -64.163702)
		(width 0.1524)
		(layer "In7.Cu")
		(net "M_A_DQ56")
	)
	(segment
		(start 125.8824 -63.881)
		(end 125.6538 -63.6524)
		(width 0.1524)
		(layer "In7.Cu")
		(net "M_A_DQ56")
	)
	(segment
		(start 123.317 -63.6524)
		(end 123.1646 -63.8048)
		(width 0.1524)
		(layer "In7.Cu")
		(net "M_A_DQ56")
	)
	(segment
		(start 120.550686 -64.316102)
		(end 117.451124 -64.316102)
		(width 0.1524)
		(layer "In7.Cu")
		(net "M_A_DQ56")
	)
	(segment
		(start 121.922286 -64.163702)
		(end 121.769886 -64.316102)
		(width 0.1524)
		(layer "In7.Cu")
		(net "M_A_DQ56")
	)
	(segment
		(start 120.855486 -63.6524)
		(end 120.703086 -63.8048)
		(width 0.1524)
		(layer "In7.Cu")
		(net "M_A_DQ56")
	)
	(segment
		(start 117.146324 -63.7286)
		(end 116.841524 -63.7286)
		(width 0.1524)
		(layer "In7.Cu")
		(net "M_A_DQ56")
	)
	(segment
		(start 114.403124 -63.6524)
		(end 114.250724 -63.8048)
		(width 0.1524)
		(layer "In7.Cu")
		(net "M_A_DQ56")
	)
	(segment
		(start 115.012724 -64.316102)
		(end 114.860324 -64.163702)
		(width 0.1524)
		(layer "In7.Cu")
		(net "M_A_DQ56")
	)
	(segment
		(start 116.079524 -64.163702)
		(end 116.079524 -63.9318)
		(width 0.1524)
		(layer "In7.Cu")
		(net "M_A_DQ56")
	)
	(segment
		(start 133.2992 -62.9666)
		(end 133.2992 -63.4492)
		(width 0.1524)
		(layer "In7.Cu")
		(net "M_A_DQ56")
	)
	(segment
		(start 132.715 -63.4492)
		(end 132.715 -62.9158)
		(width 0.1524)
		(layer "In7.Cu")
		(net "M_A_DQ56")
	)
	(segment
		(start 132.715 -62.9158)
		(end 132.4864 -62.6872)
		(width 0.1524)
		(layer "In7.Cu")
		(net "M_A_DQ56")
	)
	(segment
		(start 114.250724 -64.163702)
		(end 114.098324 -64.316102)
		(width 0.1524)
		(layer "In7.Cu")
		(net "M_A_DQ56")
	)
	(segment
		(start 115.317524 -64.316102)
		(end 115.012724 -64.316102)
		(width 0.1524)
		(layer "In7.Cu")
		(net "M_A_DQ56")
	)
	(segment
		(start 122.074686 -63.6524)
		(end 121.922286 -63.8048)
		(width 0.1524)
		(layer "In7.Cu")
		(net "M_A_DQ56")
	)
	(segment
		(start 114.860324 -64.163702)
		(end 114.860324 -63.8048)
		(width 0.1524)
		(layer "In7.Cu")
		(net "M_A_DQ56")
	)
	(segment
		(start 121.922286 -63.8048)
		(end 121.922286 -64.163702)
		(width 0.1524)
		(layer "In7.Cu")
		(net "M_A_DQ56")
	)
	(segment
		(start 121.312686 -64.163702)
		(end 121.312686 -63.8048)
		(width 0.1524)
		(layer "In7.Cu")
		(net "M_A_DQ56")
	)
	(segment
		(start 123.0122 -64.316102)
		(end 122.684286 -64.316102)
		(width 0.1524)
		(layer "In7.Cu")
		(net "M_A_DQ56")
	)
	(segment
		(start 121.160286 -63.6524)
		(end 120.855486 -63.6524)
		(width 0.1524)
		(layer "In7.Cu")
		(net "M_A_DQ56")
	)
	(segment
		(start 122.531886 -63.8048)
		(end 122.379486 -63.6524)
		(width 0.1524)
		(layer "In7.Cu")
		(net "M_A_DQ56")
	)
	(segment
		(start 126.7714 -62.9158)
		(end 126.7714 -63.7286)
		(width 0.1524)
		(layer "In7.Cu")
		(net "M_A_DQ56")
	)
	(segment
		(start 122.684286 -64.316102)
		(end 122.531886 -64.163702)
		(width 0.1524)
		(layer "In7.Cu")
		(net "M_A_DQ56")
	)
	(segment
		(start 105.440226 -64.316102)
		(end 105.037382 -63.913258)
		(width 0.1524)
		(layer "In7.Cu")
		(net "M_A_DQ56")
	)
	(segment
		(start 121.465086 -64.316102)
		(end 121.312686 -64.163702)
		(width 0.1524)
		(layer "In7.Cu")
		(net "M_A_DQ56")
	)
	(segment
		(start 133.78561 -64.663574)
		(end 133.5405 -64.418464)
		(width 0.1524)
		(layer "In7.Cu")
		(net "M_A_DQ56")
	)
	(segment
		(start 103.950516 -64.262)
		(end 100.785676 -64.262)
		(width 0.1524)
		(layer "In7.Cu")
		(net "M_A_DQ56")
	)
	(segment
		(start 122.531886 -64.163702)
		(end 122.531886 -63.8048)
		(width 0.1524)
		(layer "In7.Cu")
		(net "M_A_DQ56")
	)
	(segment
		(start 133.4516 -62.8142)
		(end 133.2992 -62.9666)
		(width 0.1524)
		(layer "In7.Cu")
		(net "M_A_DQ56")
	)
	(segment
		(start 104.299258 -63.913258)
		(end 103.950516 -64.262)
		(width 0.1524)
		(layer "In7.Cu")
		(net "M_A_DQ56")
	)
	(segment
		(start 116.079524 -63.9318)
		(end 115.927124 -63.7794)
		(width 0.1524)
		(layer "In7.Cu")
		(net "M_A_DQ56")
	)
	(segment
		(start 133.86435 -63.535814)
		(end 133.86435 -62.9666)
		(width 0.1524)
		(layer "In7.Cu")
		(net "M_A_DQ56")
	)
	(segment
		(start 114.098324 -64.316102)
		(end 105.440226 -64.316102)
		(width 0.1524)
		(layer "In7.Cu")
		(net "M_A_DQ56")
	)
	(segment
		(start 116.689124 -64.163702)
		(end 116.536724 -64.316102)
		(width 0.1524)
		(layer "In7.Cu")
		(net "M_A_DQ56")
	)
	(segment
		(start 164.11829 -2.728468)
		(end 164.11829 -3.726688)
		(width 0.2159)
		(layer "F.Cu")
		(net "M_B_CK_DN2")
	)
	(segment
		(start 164.11829 -3.726688)
		(end 163.9062 -3.938778)
		(width 0.2159)
		(layer "F.Cu")
		(net "M_B_CK_DN2")
	)
	(segment
		(start 107.536488 -28.868116)
		(end 107.536488 -28.854654)
		(width 0.1016)
		(layer "F.Cu")
		(net "M_B_CK_DN2")
	)
	(segment
		(start 164.349938 -2.49682)
		(end 164.11829 -2.728468)
		(width 0.2159)
		(layer "F.Cu")
		(net "M_B_CK_DN2")
	)
	(segment
		(start 107.8738 -29.21)
		(end 107.8738 -29.205428)
		(width 0.1016)
		(layer "F.Cu")
		(net "M_B_CK_DN2")
	)
	(segment
		(start 107.8738 -29.205428)
		(end 107.536488 -28.868116)
		(width 0.1016)
		(layer "F.Cu")
		(net "M_B_CK_DN2")
	)
	(segment
		(start 164.349938 -1.68402)
		(end 164.349938 -2.49682)
		(width 0.2159)
		(layer "F.Cu")
		(net "M_B_CK_DN2")
	)
	(via
		(at 163.9062 -3.938778)
		(size 0.4318)
		(drill 0.2032)
		(layers "F.Cu" "B.Cu")
		(net "M_B_CK_DN2")
	)
	(via
		(at 107.8738 -29.21)
		(size 0.4318)
		(drill 0.2032)
		(layers "F.Cu" "B.Cu")
		(net "M_B_CK_DN2")
	)
	(segment
		(start 111.209836 -25.721564)
		(end 111.209836 -25.524714)
		(width 0.1016)
		(layer "In9.Cu")
		(net "M_B_CK_DN2")
	)
	(segment
		(start 165.5445 -11.476736)
		(end 165.1635 -11.857736)
		(width 0.1905)
		(layer "In9.Cu")
		(net "M_B_CK_DN2")
	)
	(segment
		(start 164.0586 -5.615178)
		(end 165.94455 -7.501128)
		(width 0.1905)
		(layer "In9.Cu")
		(net "M_B_CK_DN2")
	)
	(segment
		(start 165.1635 -11.857736)
		(end 165.1635 -12.897104)
		(width 0.1905)
		(layer "In9.Cu")
		(net "M_B_CK_DN2")
	)
	(segment
		(start 123.090178 -22.424136)
		(end 123.090178 -21.9075)
		(width 0.1905)
		(layer "In9.Cu")
		(net "M_B_CK_DN2")
	)
	(segment
		(start 117.864636 -21.717)
		(end 117.255036 -22.3266)
		(width 0.1905)
		(layer "In9.Cu")
		(net "M_B_CK_DN2")
	)
	(segment
		(start 164.5285 -13.7541)
		(end 163.1696 -15.113)
		(width 0.1905)
		(layer "In9.Cu")
		(net "M_B_CK_DN2")
	)
	(segment
		(start 163.9062 -3.938778)
		(end 163.7919 -4.053078)
		(width 0.1905)
		(layer "In9.Cu")
		(net "M_B_CK_DN2")
	)
	(segment
		(start 156.699204 -17.9705)
		(end 154.478736 -17.9705)
		(width 0.1905)
		(layer "In9.Cu")
		(net "M_B_CK_DN2")
	)
	(segment
		(start 111.30915 -25.272746)
		(end 111.30915 -25.4254)
		(width 0.1905)
		(layer "In9.Cu")
		(net "M_B_CK_DN2")
	)
	(segment
		(start 124.292614 -22.8219)
		(end 123.487942 -22.8219)
		(width 0.1905)
		(layer "In9.Cu")
		(net "M_B_CK_DN2")
	)
	(segment
		(start 164.5285 -13.532104)
		(end 164.5285 -13.7541)
		(width 0.1905)
		(layer "In9.Cu")
		(net "M_B_CK_DN2")
	)
	(segment
		(start 154.1907 -20.417536)
		(end 152.891236 -21.717)
		(width 0.1905)
		(layer "In9.Cu")
		(net "M_B_CK_DN2")
	)
	(segment
		(start 110.209584 -27.407616)
		(end 110.209584 -26.721816)
		(width 0.1016)
		(layer "In9.Cu")
		(net "M_B_CK_DN2")
	)
	(segment
		(start 122.518678 -21.717)
		(end 122.328178 -21.9075)
		(width 0.1905)
		(layer "In9.Cu")
		(net "M_B_CK_DN2")
	)
	(segment
		(start 124.690378 -21.9075)
		(end 124.690378 -22.424136)
		(width 0.1905)
		(layer "In9.Cu")
		(net "M_B_CK_DN2")
	)
	(segment
		(start 163.7919 -4.641342)
		(end 164.0586 -4.908042)
		(width 0.1905)
		(layer "In9.Cu")
		(net "M_B_CK_DN2")
	)
	(segment
		(start 120.727978 -21.9075)
		(end 120.537478 -21.717)
		(width 0.1905)
		(layer "In9.Cu")
		(net "M_B_CK_DN2")
	)
	(segment
		(start 111.209836 -25.524714)
		(end 111.30915 -25.4254)
		(width 0.1016)
		(layer "In9.Cu")
		(net "M_B_CK_DN2")
	)
	(segment
		(start 120.537478 -21.717)
		(end 117.864636 -21.717)
		(width 0.1905)
		(layer "In9.Cu")
		(net "M_B_CK_DN2")
	)
	(segment
		(start 109.5248 -28.0924)
		(end 110.209584 -27.407616)
		(width 0.1016)
		(layer "In9.Cu")
		(net "M_B_CK_DN2")
	)
	(segment
		(start 163.1696 -15.113)
		(end 159.556704 -15.113)
		(width 0.1905)
		(layer "In9.Cu")
		(net "M_B_CK_DN2")
	)
	(segment
		(start 122.899678 -21.717)
		(end 122.518678 -21.717)
		(width 0.1905)
		(layer "In9.Cu")
		(net "M_B_CK_DN2")
	)
	(segment
		(start 124.880878 -21.717)
		(end 124.690378 -21.9075)
		(width 0.1905)
		(layer "In9.Cu")
		(net "M_B_CK_DN2")
	)
	(segment
		(start 163.7919 -4.053078)
		(end 163.7919 -4.641342)
		(width 0.1905)
		(layer "In9.Cu")
		(net "M_B_CK_DN2")
	)
	(segment
		(start 107.8738 -29.21)
		(end 107.594654 -28.930854)
		(width 0.1016)
		(layer "In9.Cu")
		(net "M_B_CK_DN2")
	)
	(segment
		(start 117.255036 -22.3266)
		(end 114.255296 -22.3266)
		(width 0.1905)
		(layer "In9.Cu")
		(net "M_B_CK_DN2")
	)
	(segment
		(start 154.478736 -17.9705)
		(end 154.1907 -18.258536)
		(width 0.1905)
		(layer "In9.Cu")
		(net "M_B_CK_DN2")
	)
	(segment
		(start 108.1532 -28.0924)
		(end 109.5248 -28.0924)
		(width 0.1016)
		(layer "In9.Cu")
		(net "M_B_CK_DN2")
	)
	(segment
		(start 164.0586 -4.908042)
		(end 164.0586 -5.615178)
		(width 0.1905)
		(layer "In9.Cu")
		(net "M_B_CK_DN2")
	)
	(segment
		(start 114.255296 -22.3266)
		(end 111.30915 -25.272746)
		(width 0.1905)
		(layer "In9.Cu")
		(net "M_B_CK_DN2")
	)
	(segment
		(start 165.1635 -12.897104)
		(end 164.5285 -13.532104)
		(width 0.1905)
		(layer "In9.Cu")
		(net "M_B_CK_DN2")
	)
	(segment
		(start 159.556704 -15.113)
		(end 156.699204 -17.9705)
		(width 0.1905)
		(layer "In9.Cu")
		(net "M_B_CK_DN2")
	)
	(segment
		(start 121.163842 -22.7457)
		(end 120.727978 -22.309836)
		(width 0.1905)
		(layer "In9.Cu")
		(net "M_B_CK_DN2")
	)
	(segment
		(start 120.727978 -22.309836)
		(end 120.727978 -21.9075)
		(width 0.1905)
		(layer "In9.Cu")
		(net "M_B_CK_DN2")
	)
	(segment
		(start 122.328178 -21.9075)
		(end 122.328178 -22.309836)
		(width 0.1905)
		(layer "In9.Cu")
		(net "M_B_CK_DN2")
	)
	(segment
		(start 122.328178 -22.309836)
		(end 121.892314 -22.7457)
		(width 0.1905)
		(layer "In9.Cu")
		(net "M_B_CK_DN2")
	)
	(segment
		(start 165.5445 -9.475978)
		(end 165.5445 -11.476736)
		(width 0.1905)
		(layer "In9.Cu")
		(net "M_B_CK_DN2")
	)
	(segment
		(start 165.94455 -7.501128)
		(end 165.94455 -9.075928)
		(width 0.1905)
		(layer "In9.Cu")
		(net "M_B_CK_DN2")
	)
	(segment
		(start 123.090178 -21.9075)
		(end 122.899678 -21.717)
		(width 0.1905)
		(layer "In9.Cu")
		(net "M_B_CK_DN2")
	)
	(segment
		(start 165.94455 -9.075928)
		(end 165.5445 -9.475978)
		(width 0.1905)
		(layer "In9.Cu")
		(net "M_B_CK_DN2")
	)
	(segment
		(start 107.594654 -28.930854)
		(end 107.594654 -28.650946)
		(width 0.1016)
		(layer "In9.Cu")
		(net "M_B_CK_DN2")
	)
	(segment
		(start 121.892314 -22.7457)
		(end 121.163842 -22.7457)
		(width 0.1905)
		(layer "In9.Cu")
		(net "M_B_CK_DN2")
	)
	(segment
		(start 107.594654 -28.650946)
		(end 108.1532 -28.0924)
		(width 0.1016)
		(layer "In9.Cu")
		(net "M_B_CK_DN2")
	)
	(segment
		(start 123.487942 -22.8219)
		(end 123.090178 -22.424136)
		(width 0.1905)
		(layer "In9.Cu")
		(net "M_B_CK_DN2")
	)
	(segment
		(start 124.690378 -22.424136)
		(end 124.292614 -22.8219)
		(width 0.1905)
		(layer "In9.Cu")
		(net "M_B_CK_DN2")
	)
	(segment
		(start 154.1907 -18.258536)
		(end 154.1907 -20.417536)
		(width 0.1905)
		(layer "In9.Cu")
		(net "M_B_CK_DN2")
	)
	(segment
		(start 152.891236 -21.717)
		(end 124.880878 -21.717)
		(width 0.1905)
		(layer "In9.Cu")
		(net "M_B_CK_DN2")
	)
	(segment
		(start 110.209584 -26.721816)
		(end 111.209836 -25.721564)
		(width 0.1016)
		(layer "In9.Cu")
		(net "M_B_CK_DN2")
	)
	(segment
		(start 149.730968 -64.255142)
		(end 149.2758 -64.71031)
		(width 0.1778)
		(layer "F.Cu")
		(net "M_A_ODT3")
	)
	(segment
		(start 100.053648 -48.783494)
		(end 99.7204 -48.450246)
		(width 0.1016)
		(layer "F.Cu")
		(net "M_A_ODT3")
	)
	(segment
		(start 149.730968 -63.843154)
		(end 149.730968 -64.255142)
		(width 0.1778)
		(layer "F.Cu")
		(net "M_A_ODT3")
	)
	(segment
		(start 149.2758 -64.71031)
		(end 149.2758 -64.8462)
		(width 0.1778)
		(layer "F.Cu")
		(net "M_A_ODT3")
	)
	(segment
		(start 149.649942 -62.59322)
		(end 149.649942 -63.762128)
		(width 0.1778)
		(layer "F.Cu")
		(net "M_A_ODT3")
	)
	(segment
		(start 149.649942 -63.762128)
		(end 149.730968 -63.843154)
		(width 0.1778)
		(layer "F.Cu")
		(net "M_A_ODT3")
	)
	(segment
		(start 99.7204 -48.450246)
		(end 99.7204 -48.4124)
		(width 0.1016)
		(layer "F.Cu")
		(net "M_A_ODT3")
	)
	(via
		(at 149.2758 -64.8462)
		(size 0.4318)
		(drill 0.2032)
		(layers "F.Cu" "B.Cu")
		(net "M_A_ODT3")
	)
	(via
		(at 99.7204 -48.4124)
		(size 0.4318)
		(drill 0.2032)
		(layers "F.Cu" "B.Cu")
		(net "M_A_ODT3")
	)
	(segment
		(start 147.6756 -66.8528)
		(end 147.828 -66.7004)
		(width 0.1524)
		(layer "In7.Cu")
		(net "M_A_ODT3")
	)
	(segment
		(start 148.463 -66.0908)
		(end 147.828 -66.0908)
		(width 0.1524)
		(layer "In7.Cu")
		(net "M_A_ODT3")
	)
	(segment
		(start 146.5326 -64.2112)
		(end 146.3802 -64.3636)
		(width 0.1524)
		(layer "In7.Cu")
		(net "M_A_ODT3")
	)
	(segment
		(start 99.7204 -48.48606)
		(end 99.7204 -48.4124)
		(width 0.1016)
		(layer "In7.Cu")
		(net "M_A_ODT3")
	)
	(segment
		(start 134.540244 -59.4106)
		(end 134.540244 -59.2328)
		(width 0.1524)
		(layer "In7.Cu")
		(net "M_A_ODT3")
	)
	(segment
		(start 139.7762 -62.8142)
		(end 136.0424 -59.0804)
		(width 0.1524)
		(layer "In7.Cu")
		(net "M_A_ODT3")
	)
	(segment
		(start 135.302244 -59.0804)
		(end 135.149844 -59.2328)
		(width 0.1524)
		(layer "In7.Cu")
		(net "M_A_ODT3")
	)
	(segment
		(start 147.6756 -67.1576)
		(end 147.6756 -66.8528)
		(width 0.1524)
		(layer "In7.Cu")
		(net "M_A_ODT3")
	)
	(segment
		(start 132.254244 -59.563)
		(end 132.101844 -59.4106)
		(width 0.1524)
		(layer "In7.Cu")
		(net "M_A_ODT3")
	)
	(segment
		(start 145.603722 -63.4746)
		(end 141.224 -63.4746)
		(width 0.1524)
		(layer "In7.Cu")
		(net "M_A_ODT3")
	)
	(segment
		(start 134.540244 -59.2328)
		(end 134.387844 -59.0804)
		(width 0.1524)
		(layer "In7.Cu")
		(net "M_A_ODT3")
	)
	(segment
		(start 147.6756 -65.6336)
		(end 147.828 -65.4812)
		(width 0.1524)
		(layer "In7.Cu")
		(net "M_A_ODT3")
	)
	(segment
		(start 145.756122 -64.2112)
		(end 145.756122 -63.627)
		(width 0.1524)
		(layer "In7.Cu")
		(net "M_A_ODT3")
	)
	(segment
		(start 149.0726 -67.31)
		(end 147.828 -67.31)
		(width 0.1524)
		(layer "In7.Cu")
		(net "M_A_ODT3")
	)
	(segment
		(start 99.9236 -52.7812)
		(end 99.9236 -49.9491)
		(width 0.1016)
		(layer "In7.Cu")
		(net "M_A_ODT3")
	)
	(segment
		(start 129.54 -59.32805)
		(end 102.66045 -59.32805)
		(width 0.1524)
		(layer "In7.Cu")
		(net "M_A_ODT3")
	)
	(segment
		(start 134.083044 -59.0804)
		(end 133.930644 -59.2328)
		(width 0.1524)
		(layer "In7.Cu")
		(net "M_A_ODT3")
	)
	(segment
		(start 132.711444 -59.2328)
		(end 132.711444 -59.4106)
		(width 0.1524)
		(layer "In7.Cu")
		(net "M_A_ODT3")
	)
	(segment
		(start 132.101844 -59.2328)
		(end 131.949444 -59.0804)
		(width 0.1524)
		(layer "In7.Cu")
		(net "M_A_ODT3")
	)
	(segment
		(start 132.863844 -59.0804)
		(end 132.711444 -59.2328)
		(width 0.1524)
		(layer "In7.Cu")
		(net "M_A_ODT3")
	)
	(segment
		(start 148.6154 -66.2432)
		(end 148.463 -66.0908)
		(width 0.1524)
		(layer "In7.Cu")
		(net "M_A_ODT3")
	)
	(segment
		(start 147.828 -66.0908)
		(end 147.6756 -65.9384)
		(width 0.1524)
		(layer "In7.Cu")
		(net "M_A_ODT3")
	)
	(segment
		(start 132.711444 -59.4106)
		(end 132.559044 -59.563)
		(width 0.1524)
		(layer "In7.Cu")
		(net "M_A_ODT3")
	)
	(segment
		(start 99.3394 -48.86706)
		(end 99.7204 -48.48606)
		(width 0.1016)
		(layer "In7.Cu")
		(net "M_A_ODT3")
	)
	(segment
		(start 102.66045 -59.32805)
		(end 101.0412 -57.7088)
		(width 0.1524)
		(layer "In7.Cu")
		(net "M_A_ODT3")
	)
	(segment
		(start 133.778244 -59.563)
		(end 133.473444 -59.563)
		(width 0.1524)
		(layer "In7.Cu")
		(net "M_A_ODT3")
	)
	(segment
		(start 145.908522 -64.3636)
		(end 145.756122 -64.2112)
		(width 0.1524)
		(layer "In7.Cu")
		(net "M_A_ODT3")
	)
	(segment
		(start 99.3394 -49.3649)
		(end 99.3394 -48.86706)
		(width 0.1016)
		(layer "In7.Cu")
		(net "M_A_ODT3")
	)
	(segment
		(start 148.02866 -63.4746)
		(end 146.685 -63.4746)
		(width 0.1524)
		(layer "In7.Cu")
		(net "M_A_ODT3")
	)
	(segment
		(start 133.930644 -59.2328)
		(end 133.930644 -59.4106)
		(width 0.1524)
		(layer "In7.Cu")
		(net "M_A_ODT3")
	)
	(segment
		(start 141.224 -63.4746)
		(end 140.5636 -62.8142)
		(width 0.1524)
		(layer "In7.Cu")
		(net "M_A_ODT3")
	)
	(segment
		(start 134.387844 -59.0804)
		(end 134.083044 -59.0804)
		(width 0.1524)
		(layer "In7.Cu")
		(net "M_A_ODT3")
	)
	(segment
		(start 134.997444 -59.563)
		(end 134.692644 -59.563)
		(width 0.1524)
		(layer "In7.Cu")
		(net "M_A_ODT3")
	)
	(segment
		(start 140.5636 -62.8142)
		(end 139.7762 -62.8142)
		(width 0.1524)
		(layer "In7.Cu")
		(net "M_A_ODT3")
	)
	(segment
		(start 148.463 -65.3288)
		(end 148.463 -63.90894)
		(width 0.1524)
		(layer "In7.Cu")
		(net "M_A_ODT3")
	)
	(segment
		(start 133.321044 -59.4106)
		(end 133.321044 -59.2328)
		(width 0.1524)
		(layer "In7.Cu")
		(net "M_A_ODT3")
	)
	(segment
		(start 146.685 -63.4746)
		(end 146.5326 -63.627)
		(width 0.1524)
		(layer "In7.Cu")
		(net "M_A_ODT3")
	)
	(segment
		(start 101.0412 -55.0164)
		(end 101.0412 -53.8988)
		(width 0.1016)
		(layer "In7.Cu")
		(net "M_A_ODT3")
	)
	(segment
		(start 135.149844 -59.2328)
		(end 135.149844 -59.4106)
		(width 0.1524)
		(layer "In7.Cu")
		(net "M_A_ODT3")
	)
	(segment
		(start 148.463 -63.90894)
		(end 148.02866 -63.4746)
		(width 0.1524)
		(layer "In7.Cu")
		(net "M_A_ODT3")
	)
	(segment
		(start 133.321044 -59.2328)
		(end 133.168644 -59.0804)
		(width 0.1524)
		(layer "In7.Cu")
		(net "M_A_ODT3")
	)
	(segment
		(start 133.168644 -59.0804)
		(end 132.863844 -59.0804)
		(width 0.1524)
		(layer "In7.Cu")
		(net "M_A_ODT3")
	)
	(segment
		(start 135.149844 -59.4106)
		(end 134.997444 -59.563)
		(width 0.1524)
		(layer "In7.Cu")
		(net "M_A_ODT3")
	)
	(segment
		(start 148.6154 -66.548)
		(end 148.6154 -66.2432)
		(width 0.1524)
		(layer "In7.Cu")
		(net "M_A_ODT3")
	)
	(segment
		(start 129.78765 -59.0804)
		(end 129.54 -59.32805)
		(width 0.1524)
		(layer "In7.Cu")
		(net "M_A_ODT3")
	)
	(segment
		(start 99.9236 -49.9491)
		(end 99.3394 -49.3649)
		(width 0.1016)
		(layer "In7.Cu")
		(net "M_A_ODT3")
	)
	(segment
		(start 146.3802 -64.3636)
		(end 145.908522 -64.3636)
		(width 0.1524)
		(layer "In7.Cu")
		(net "M_A_ODT3")
	)
	(segment
		(start 148.463 -66.7004)
		(end 148.6154 -66.548)
		(width 0.1524)
		(layer "In7.Cu")
		(net "M_A_ODT3")
	)
	(segment
		(start 147.828 -65.4812)
		(end 148.3106 -65.4812)
		(width 0.1524)
		(layer "In7.Cu")
		(net "M_A_ODT3")
	)
	(segment
		(start 133.930644 -59.4106)
		(end 133.778244 -59.563)
		(width 0.1524)
		(layer "In7.Cu")
		(net "M_A_ODT3")
	)
	(segment
		(start 134.692644 -59.563)
		(end 134.540244 -59.4106)
		(width 0.1524)
		(layer "In7.Cu")
		(net "M_A_ODT3")
	)
	(segment
		(start 147.828 -67.31)
		(end 147.6756 -67.1576)
		(width 0.1524)
		(layer "In7.Cu")
		(net "M_A_ODT3")
	)
	(segment
		(start 132.101844 -59.4106)
		(end 132.101844 -59.2328)
		(width 0.1524)
		(layer "In7.Cu")
		(net "M_A_ODT3")
	)
	(segment
		(start 149.2758 -64.8462)
		(end 149.2758 -67.1068)
		(width 0.1524)
		(layer "In7.Cu")
		(net "M_A_ODT3")
	)
	(segment
		(start 136.0424 -59.0804)
		(end 135.302244 -59.0804)
		(width 0.1524)
		(layer "In7.Cu")
		(net "M_A_ODT3")
	)
	(segment
		(start 133.473444 -59.563)
		(end 133.321044 -59.4106)
		(width 0.1524)
		(layer "In7.Cu")
		(net "M_A_ODT3")
	)
	(segment
		(start 148.3106 -65.4812)
		(end 148.463 -65.3288)
		(width 0.1524)
		(layer "In7.Cu")
		(net "M_A_ODT3")
	)
	(segment
		(start 131.949444 -59.0804)
		(end 129.78765 -59.0804)
		(width 0.1524)
		(layer "In7.Cu")
		(net "M_A_ODT3")
	)
	(segment
		(start 147.828 -66.7004)
		(end 148.463 -66.7004)
		(width 0.1524)
		(layer "In7.Cu")
		(net "M_A_ODT3")
	)
	(segment
		(start 146.5326 -63.627)
		(end 146.5326 -64.2112)
		(width 0.1524)
		(layer "In7.Cu")
		(net "M_A_ODT3")
	)
	(segment
		(start 147.6756 -65.9384)
		(end 147.6756 -65.6336)
		(width 0.1524)
		(layer "In7.Cu")
		(net "M_A_ODT3")
	)
	(segment
		(start 101.0412 -57.7088)
		(end 101.0412 -55.0164)
		(width 0.1524)
		(layer "In7.Cu")
		(net "M_A_ODT3")
	)
	(segment
		(start 101.0412 -53.8988)
		(end 99.9236 -52.7812)
		(width 0.1016)
		(layer "In7.Cu")
		(net "M_A_ODT3")
	)
	(segment
		(start 132.559044 -59.563)
		(end 132.254244 -59.563)
		(width 0.1524)
		(layer "In7.Cu")
		(net "M_A_ODT3")
	)
	(segment
		(start 145.756122 -63.627)
		(end 145.603722 -63.4746)
		(width 0.1524)
		(layer "In7.Cu")
		(net "M_A_ODT3")
	)
	(segment
		(start 149.2758 -67.1068)
		(end 149.0726 -67.31)
		(width 0.1524)
		(layer "In7.Cu")
		(net "M_A_ODT3")
	)
	(segment
		(start 94.9452 -24.8666)
		(end 95.706184 -25.627584)
		(width 0.1016)
		(layer "F.Cu")
		(net "M_B_DQ13")
	)
	(segment
		(start 134.349998 -2.659126)
		(end 134.7724 -3.081528)
		(width 0.1778)
		(layer "F.Cu")
		(net "M_B_DQ13")
	)
	(segment
		(start 96.233488 -26.344626)
		(end 96.545146 -26.656284)
		(width 0.1016)
		(layer "F.Cu")
		(net "M_B_DQ13")
	)
	(segment
		(start 94.9452 -22.1742)
		(end 94.9452 -24.8666)
		(width 0.1016)
		(layer "F.Cu")
		(net "M_B_DQ13")
	)
	(segment
		(start 96.552258 -26.656284)
		(end 96.767904 -26.87193)
		(width 0.1016)
		(layer "F.Cu")
		(net "M_B_DQ13")
	)
	(segment
		(start 94.4626 -21.6916)
		(end 94.9452 -22.1742)
		(width 0.1016)
		(layer "F.Cu")
		(net "M_B_DQ13")
	)
	(segment
		(start 96.069912 -25.627584)
		(end 96.233488 -25.79116)
		(width 0.1016)
		(layer "F.Cu")
		(net "M_B_DQ13")
	)
	(segment
		(start 96.545146 -26.656284)
		(end 96.552258 -26.656284)
		(width 0.1016)
		(layer "F.Cu")
		(net "M_B_DQ13")
	)
	(segment
		(start 96.767904 -26.87193)
		(end 96.767904 -27.311858)
		(width 0.1016)
		(layer "F.Cu")
		(net "M_B_DQ13")
	)
	(segment
		(start 95.706184 -25.627584)
		(end 96.069912 -25.627584)
		(width 0.1016)
		(layer "F.Cu")
		(net "M_B_DQ13")
	)
	(segment
		(start 134.7724 -3.887978)
		(end 134.7978 -3.913378)
		(width 0.1778)
		(layer "F.Cu")
		(net "M_B_DQ13")
	)
	(segment
		(start 134.7724 -3.081528)
		(end 134.7724 -3.887978)
		(width 0.1778)
		(layer "F.Cu")
		(net "M_B_DQ13")
	)
	(segment
		(start 96.767904 -27.311858)
		(end 96.632268 -27.447494)
		(width 0.1016)
		(layer "F.Cu")
		(net "M_B_DQ13")
	)
	(segment
		(start 96.233488 -25.79116)
		(end 96.233488 -26.344626)
		(width 0.1016)
		(layer "F.Cu")
		(net "M_B_DQ13")
	)
	(segment
		(start 134.349998 -1.68402)
		(end 134.349998 -2.659126)
		(width 0.1778)
		(layer "F.Cu")
		(net "M_B_DQ13")
	)
	(via
		(at 134.7978 -3.913378)
		(size 0.4318)
		(drill 0.2032)
		(layers "F.Cu" "B.Cu")
		(net "M_B_DQ13")
	)
	(via
		(at 94.4626 -21.6916)
		(size 0.4318)
		(drill 0.2032)
		(layers "F.Cu" "B.Cu")
		(net "M_B_DQ13")
	)
	(segment
		(start 135.24992 -2.557018)
		(end 134.7724 -3.034538)
		(width 0.1778)
		(layer "B.Cu")
		(net "M_B_DQ13")
	)
	(segment
		(start 134.7724 -3.034538)
		(end 134.7724 -3.887978)
		(width 0.1778)
		(layer "B.Cu")
		(net "M_B_DQ13")
	)
	(segment
		(start 134.7724 -3.887978)
		(end 134.7978 -3.913378)
		(width 0.1778)
		(layer "B.Cu")
		(net "M_B_DQ13")
	)
	(segment
		(start 135.24992 -1.690624)
		(end 135.24992 -2.557018)
		(width 0.1778)
		(layer "B.Cu")
		(net "M_B_DQ13")
	)
	(segment
		(start 94.4626 -19.969988)
		(end 94.4626 -21.6916)
		(width 0.1524)
		(layer "In2.Cu")
		(net "M_B_DQ13")
	)
	(segment
		(start 127.372872 -11.049)
		(end 124.333 -11.049)
		(width 0.1524)
		(layer "In2.Cu")
		(net "M_B_DQ13")
	)
	(segment
		(start 115.581938 -9.4742)
		(end 113.321338 -11.7348)
		(width 0.1524)
		(layer "In2.Cu")
		(net "M_B_DQ13")
	)
	(segment
		(start 134.7978 -3.913378)
		(end 134.7978 -4.649978)
		(width 0.1524)
		(layer "In2.Cu")
		(net "M_B_DQ13")
	)
	(segment
		(start 127.525272 -11.5824)
		(end 127.525272 -11.2014)
		(width 0.1524)
		(layer "In2.Cu")
		(net "M_B_DQ13")
	)
	(segment
		(start 105.931462 -15.4432)
		(end 98.989388 -15.4432)
		(width 0.1524)
		(layer "In2.Cu")
		(net "M_B_DQ13")
	)
	(segment
		(start 127.677672 -11.7348)
		(end 127.525272 -11.5824)
		(width 0.1524)
		(layer "In2.Cu")
		(net "M_B_DQ13")
	)
	(segment
		(start 127.525272 -11.2014)
		(end 127.372872 -11.049)
		(width 0.1524)
		(layer "In2.Cu")
		(net "M_B_DQ13")
	)
	(segment
		(start 134.7978 -4.649978)
		(end 129.7432 -9.704578)
		(width 0.1524)
		(layer "In2.Cu")
		(net "M_B_DQ13")
	)
	(segment
		(start 122.7582 -9.4742)
		(end 115.581938 -9.4742)
		(width 0.1524)
		(layer "In2.Cu")
		(net "M_B_DQ13")
	)
	(segment
		(start 128.744472 -11.5824)
		(end 128.744472 -11.2014)
		(width 0.1524)
		(layer "In2.Cu")
		(net "M_B_DQ13")
	)
	(segment
		(start 127.982472 -11.7348)
		(end 127.677672 -11.7348)
		(width 0.1524)
		(layer "In2.Cu")
		(net "M_B_DQ13")
	)
	(segment
		(start 124.333 -11.049)
		(end 122.7582 -9.4742)
		(width 0.1524)
		(layer "In2.Cu")
		(net "M_B_DQ13")
	)
	(segment
		(start 128.744472 -11.2014)
		(end 128.592072 -11.049)
		(width 0.1524)
		(layer "In2.Cu")
		(net "M_B_DQ13")
	)
	(segment
		(start 128.134872 -11.5824)
		(end 127.982472 -11.7348)
		(width 0.1524)
		(layer "In2.Cu")
		(net "M_B_DQ13")
	)
	(segment
		(start 128.134872 -11.2014)
		(end 128.134872 -11.5824)
		(width 0.1524)
		(layer "In2.Cu")
		(net "M_B_DQ13")
	)
	(segment
		(start 129.4638 -11.7348)
		(end 128.896872 -11.7348)
		(width 0.1524)
		(layer "In2.Cu")
		(net "M_B_DQ13")
	)
	(segment
		(start 129.7432 -9.704578)
		(end 129.7432 -11.4554)
		(width 0.1524)
		(layer "In2.Cu")
		(net "M_B_DQ13")
	)
	(segment
		(start 98.989388 -15.4432)
		(end 94.4626 -19.969988)
		(width 0.1524)
		(layer "In2.Cu")
		(net "M_B_DQ13")
	)
	(segment
		(start 128.592072 -11.049)
		(end 128.287272 -11.049)
		(width 0.1524)
		(layer "In2.Cu")
		(net "M_B_DQ13")
	)
	(segment
		(start 128.287272 -11.049)
		(end 128.134872 -11.2014)
		(width 0.1524)
		(layer "In2.Cu")
		(net "M_B_DQ13")
	)
	(segment
		(start 129.7432 -11.4554)
		(end 129.4638 -11.7348)
		(width 0.1524)
		(layer "In2.Cu")
		(net "M_B_DQ13")
	)
	(segment
		(start 113.321338 -11.7348)
		(end 109.639862 -11.7348)
		(width 0.1524)
		(layer "In2.Cu")
		(net "M_B_DQ13")
	)
	(segment
		(start 128.896872 -11.7348)
		(end 128.744472 -11.5824)
		(width 0.1524)
		(layer "In2.Cu")
		(net "M_B_DQ13")
	)
	(segment
		(start 109.639862 -11.7348)
		(end 105.931462 -15.4432)
		(width 0.1524)
		(layer "In2.Cu")
		(net "M_B_DQ13")
	)
	(segment
		(start 133.150102 -70.097396)
		(end 133.5532 -69.694298)
		(width 0.1778)
		(layer "F.Cu")
		(net "M_A_DQ60")
	)
	(segment
		(start 133.5532 -69.694298)
		(end 133.5532 -69.318632)
		(width 0.1778)
		(layer "F.Cu")
		(net "M_A_DQ60")
	)
	(segment
		(start 97.6122 -57.7723)
		(end 97.6122 -53.594)
		(width 0.1016)
		(layer "F.Cu")
		(net "M_A_DQ60")
	)
	(segment
		(start 133.5532 -69.318632)
		(end 133.56463 -69.307202)
		(width 0.1778)
		(layer "F.Cu")
		(net "M_A_DQ60")
	)
	(segment
		(start 133.150102 -70.806564)
		(end 133.150102 -70.097396)
		(width 0.1778)
		(layer "F.Cu")
		(net "M_A_DQ60")
	)
	(segment
		(start 96.975168 -52.188618)
		(end 96.975168 -51.463194)
		(width 0.1016)
		(layer "F.Cu")
		(net "M_A_DQ60")
	)
	(segment
		(start 97.2185 -58.166)
		(end 97.6122 -57.7723)
		(width 0.1016)
		(layer "F.Cu")
		(net "M_A_DQ60")
	)
	(segment
		(start 96.906588 -52.257198)
		(end 96.975168 -52.188618)
		(width 0.1016)
		(layer "F.Cu")
		(net "M_A_DQ60")
	)
	(segment
		(start 96.975168 -51.463194)
		(end 96.954848 -51.442874)
		(width 0.1016)
		(layer "F.Cu")
		(net "M_A_DQ60")
	)
	(segment
		(start 96.906588 -52.888388)
		(end 96.906588 -52.257198)
		(width 0.1016)
		(layer "F.Cu")
		(net "M_A_DQ60")
	)
	(segment
		(start 97.6122 -53.594)
		(end 96.906588 -52.888388)
		(width 0.1016)
		(layer "F.Cu")
		(net "M_A_DQ60")
	)
	(via
		(at 133.56463 -69.307202)
		(size 0.4318)
		(drill 0.2032)
		(layers "F.Cu" "B.Cu")
		(net "M_A_DQ60")
	)
	(via
		(at 97.2185 -58.166)
		(size 0.4318)
		(drill 0.2032)
		(layers "F.Cu" "B.Cu")
		(net "M_A_DQ60")
	)
	(segment
		(start 134.050024 -70.79996)
		(end 134.050024 -69.892164)
		(width 0.1778)
		(layer "B.Cu")
		(net "M_A_DQ60")
	)
	(segment
		(start 134.050024 -69.892164)
		(end 133.56463 -69.40677)
		(width 0.1778)
		(layer "B.Cu")
		(net "M_A_DQ60")
	)
	(segment
		(start 133.56463 -69.40677)
		(end 133.56463 -69.307202)
		(width 0.1778)
		(layer "B.Cu")
		(net "M_A_DQ60")
	)
	(segment
		(start 133.638798 -68.3768)
		(end 133.4516 -68.563998)
		(width 0.1524)
		(layer "In7.Cu")
		(net "M_A_DQ60")
	)
	(segment
		(start 99.031552 -59.979052)
		(end 99.031552 -60.855352)
		(width 0.1524)
		(layer "In7.Cu")
		(net "M_A_DQ60")
	)
	(segment
		(start 133.4516 -69.194172)
		(end 133.56463 -69.307202)
		(width 0.1524)
		(layer "In7.Cu")
		(net "M_A_DQ60")
	)
	(segment
		(start 133.4516 -68.563998)
		(end 133.4516 -69.194172)
		(width 0.1524)
		(layer "In7.Cu")
		(net "M_A_DQ60")
	)
	(segment
		(start 118.071138 -62.4586)
		(end 118.76024 -63.147702)
		(width 0.1524)
		(layer "In7.Cu")
		(net "M_A_DQ60")
	)
	(segment
		(start 136.5123 -64.7065)
		(end 133.638798 -67.580002)
		(width 0.1524)
		(layer "In7.Cu")
		(net "M_A_DQ60")
	)
	(segment
		(start 118.76024 -63.147702)
		(end 119.3292 -63.147702)
		(width 0.1524)
		(layer "In7.Cu")
		(net "M_A_DQ60")
	)
	(segment
		(start 134.501636 -62.0014)
		(end 136.5123 -64.012064)
		(width 0.1524)
		(layer "In7.Cu")
		(net "M_A_DQ60")
	)
	(segment
		(start 99.031552 -60.855352)
		(end 101.2698 -63.0936)
		(width 0.1524)
		(layer "In7.Cu")
		(net "M_A_DQ60")
	)
	(segment
		(start 113.6396 -62.4586)
		(end 118.071138 -62.4586)
		(width 0.1524)
		(layer "In7.Cu")
		(net "M_A_DQ60")
	)
	(segment
		(start 105.521506 -62.744858)
		(end 105.921048 -63.1444)
		(width 0.1524)
		(layer "In7.Cu")
		(net "M_A_DQ60")
	)
	(segment
		(start 101.2698 -63.0936)
		(end 103.466138 -63.0936)
		(width 0.1524)
		(layer "In7.Cu")
		(net "M_A_DQ60")
	)
	(segment
		(start 133.638798 -67.580002)
		(end 133.638798 -68.3768)
		(width 0.1524)
		(layer "In7.Cu")
		(net "M_A_DQ60")
	)
	(segment
		(start 136.5123 -64.012064)
		(end 136.5123 -64.7065)
		(width 0.1524)
		(layer "In7.Cu")
		(net "M_A_DQ60")
	)
	(segment
		(start 120.475502 -62.0014)
		(end 134.501636 -62.0014)
		(width 0.1524)
		(layer "In7.Cu")
		(net "M_A_DQ60")
	)
	(segment
		(start 98.434652 -59.382152)
		(end 98.498152 -59.382152)
		(width 0.1016)
		(layer "In7.Cu")
		(net "M_A_DQ60")
	)
	(segment
		(start 103.81488 -62.744858)
		(end 105.521506 -62.744858)
		(width 0.1524)
		(layer "In7.Cu")
		(net "M_A_DQ60")
	)
	(segment
		(start 112.9538 -63.1444)
		(end 113.6396 -62.4586)
		(width 0.1524)
		(layer "In7.Cu")
		(net "M_A_DQ60")
	)
	(segment
		(start 103.466138 -63.0936)
		(end 103.81488 -62.744858)
		(width 0.1524)
		(layer "In7.Cu")
		(net "M_A_DQ60")
	)
	(segment
		(start 97.2185 -58.166)
		(end 98.434652 -59.382152)
		(width 0.1016)
		(layer "In7.Cu")
		(net "M_A_DQ60")
	)
	(segment
		(start 119.3292 -63.147702)
		(end 120.475502 -62.0014)
		(width 0.1524)
		(layer "In7.Cu")
		(net "M_A_DQ60")
	)
	(segment
		(start 98.498152 -59.382152)
		(end 99.031552 -59.915552)
		(width 0.1016)
		(layer "In7.Cu")
		(net "M_A_DQ60")
	)
	(segment
		(start 105.921048 -63.1444)
		(end 112.9538 -63.1444)
		(width 0.1524)
		(layer "In7.Cu")
		(net "M_A_DQ60")
	)
	(segment
		(start 99.031552 -59.915552)
		(end 99.031552 -59.979052)
		(width 0.1016)
		(layer "In7.Cu")
		(net "M_A_DQ60")
	)
	(segment
		(start 185.547 -8.485378)
		(end 185.547 -7.596378)
		(width 0.1778)
		(layer "F.Cu")
		(net "M_B_DQ57")
	)
	(segment
		(start 108.727494 -37.683694)
		(end 108.814108 -37.683694)
		(width 0.1016)
		(layer "F.Cu")
		(net "M_B_DQ57")
	)
	(segment
		(start 185.049922 -8.982456)
		(end 185.547 -8.485378)
		(width 0.1778)
		(layer "F.Cu")
		(net "M_B_DQ57")
	)
	(segment
		(start 185.049922 -9.897364)
		(end 185.049922 -8.982456)
		(width 0.1778)
		(layer "F.Cu")
		(net "M_B_DQ57")
	)
	(segment
		(start 108.4326 -37.3634)
		(end 108.4326 -37.3888)
		(width 0.1016)
		(layer "F.Cu")
		(net "M_B_DQ57")
	)
	(segment
		(start 108.4326 -37.3888)
		(end 108.727494 -37.683694)
		(width 0.1016)
		(layer "F.Cu")
		(net "M_B_DQ57")
	)
	(via
		(at 108.4326 -37.3634)
		(size 0.4318)
		(drill 0.2032)
		(layers "F.Cu" "B.Cu")
		(net "M_B_DQ57")
	)
	(via
		(at 185.547 -7.596378)
		(size 0.4318)
		(drill 0.2032)
		(layers "F.Cu" "B.Cu")
		(net "M_B_DQ57")
	)
	(segment
		(start 185.949844 -9.89076)
		(end 185.949844 -8.888222)
		(width 0.1778)
		(layer "B.Cu")
		(net "M_B_DQ57")
	)
	(segment
		(start 185.7756 -7.824978)
		(end 185.547 -7.596378)
		(width 0.1778)
		(layer "B.Cu")
		(net "M_B_DQ57")
	)
	(segment
		(start 185.7756 -8.713978)
		(end 185.7756 -7.824978)
		(width 0.1778)
		(layer "B.Cu")
		(net "M_B_DQ57")
	)
	(segment
		(start 185.949844 -8.888222)
		(end 185.7756 -8.713978)
		(width 0.1778)
		(layer "B.Cu")
		(net "M_B_DQ57")
	)
	(segment
		(start 145.8214 -34.612834)
		(end 145.9738 -34.460434)
		(width 0.1524)
		(layer "In2.Cu")
		(net "M_B_DQ57")
	)
	(segment
		(start 110.0836 -35.982402)
		(end 110.0836 -37.0078)
		(width 0.1016)
		(layer "In2.Cu")
		(net "M_B_DQ57")
	)
	(segment
		(start 148.857462 -35.2552)
		(end 148.857462 -34.612834)
		(width 0.1524)
		(layer "In2.Cu")
		(net "M_B_DQ57")
	)
	(segment
		(start 117.841014 -35.875214)
		(end 111.110014 -35.875214)
		(width 0.1016)
		(layer "In2.Cu")
		(net "M_B_DQ57")
	)
	(segment
		(start 150.076662 -34.612834)
		(end 150.229062 -34.460434)
		(width 0.1524)
		(layer "In2.Cu")
		(net "M_B_DQ57")
	)
	(segment
		(start 136.435846 -35.750754)
		(end 136.779 -35.4076)
		(width 0.1524)
		(layer "In2.Cu")
		(net "M_B_DQ57")
	)
	(segment
		(start 150.076662 -35.2552)
		(end 150.076662 -34.612834)
		(width 0.1524)
		(layer "In2.Cu")
		(net "M_B_DQ57")
	)
	(segment
		(start 155.817062 -35.2552)
		(end 155.969462 -35.4076)
		(width 0.1524)
		(layer "In2.Cu")
		(net "M_B_DQ57")
	)
	(segment
		(start 154.445462 -34.460434)
		(end 154.597862 -34.612834)
		(width 0.1524)
		(layer "In2.Cu")
		(net "M_B_DQ57")
	)
	(segment
		(start 149.619462 -35.4076)
		(end 149.924262 -35.4076)
		(width 0.1524)
		(layer "In2.Cu")
		(net "M_B_DQ57")
	)
	(segment
		(start 150.533862 -34.460434)
		(end 150.686262 -34.612834)
		(width 0.1524)
		(layer "In2.Cu")
		(net "M_B_DQ57")
	)
	(segment
		(start 139.08024 -35.750754)
		(end 139.423394 -35.4076)
		(width 0.1524)
		(layer "In2.Cu")
		(net "M_B_DQ57")
	)
	(segment
		(start 136.03224 -35.750754)
		(end 136.435846 -35.750754)
		(width 0.1524)
		(layer "In2.Cu")
		(net "M_B_DQ57")
	)
	(segment
		(start 155.817062 -34.8234)
		(end 155.817062 -35.2552)
		(width 0.1524)
		(layer "In2.Cu")
		(net "M_B_DQ57")
	)
	(segment
		(start 154.140662 -34.460434)
		(end 154.445462 -34.460434)
		(width 0.1524)
		(layer "In2.Cu")
		(net "M_B_DQ57")
	)
	(segment
		(start 149.467062 -34.612834)
		(end 149.467062 -35.2552)
		(width 0.1524)
		(layer "In2.Cu")
		(net "M_B_DQ57")
	)
	(segment
		(start 155.207462 -34.8234)
		(end 155.359862 -34.671)
		(width 0.1524)
		(layer "In2.Cu")
		(net "M_B_DQ57")
	)
	(segment
		(start 138.0998 -35.4076)
		(end 138.432286 -35.4076)
		(width 0.1524)
		(layer "In2.Cu")
		(net "M_B_DQ57")
	)
	(segment
		(start 145.9738 -34.460434)
		(end 148.095462 -34.460434)
		(width 0.1524)
		(layer "In2.Cu")
		(net "M_B_DQ57")
	)
	(segment
		(start 157.284166 -35.4076)
		(end 158.231078 -34.460434)
		(width 0.1524)
		(layer "In2.Cu")
		(net "M_B_DQ57")
	)
	(segment
		(start 139.7762 -35.4076)
		(end 140.105384 -35.736784)
		(width 0.1524)
		(layer "In2.Cu")
		(net "M_B_DQ57")
	)
	(segment
		(start 150.686262 -35.2552)
		(end 150.838662 -35.4076)
		(width 0.1524)
		(layer "In2.Cu")
		(net "M_B_DQ57")
	)
	(segment
		(start 153.835862 -35.4076)
		(end 153.988262 -35.2552)
		(width 0.1524)
		(layer "In2.Cu")
		(net "M_B_DQ57")
	)
	(segment
		(start 149.924262 -35.4076)
		(end 150.076662 -35.2552)
		(width 0.1524)
		(layer "In2.Cu")
		(net "M_B_DQ57")
	)
	(segment
		(start 145.8214 -35.2552)
		(end 145.8214 -34.612834)
		(width 0.1524)
		(layer "In2.Cu")
		(net "M_B_DQ57")
	)
	(segment
		(start 184.290462 -8.929116)
		(end 185.5216 -7.697978)
		(width 0.1524)
		(layer "In2.Cu")
		(net "M_B_DQ57")
	)
	(segment
		(start 110.0836 -37.0078)
		(end 109.7026 -37.3888)
		(width 0.1016)
		(layer "In2.Cu")
		(net "M_B_DQ57")
	)
	(segment
		(start 138.432286 -35.4076)
		(end 138.77544 -35.750754)
		(width 0.1524)
		(layer "In2.Cu")
		(net "M_B_DQ57")
	)
	(segment
		(start 183.76265 -8.929116)
		(end 184.290462 -8.929116)
		(width 0.1524)
		(layer "In2.Cu")
		(net "M_B_DQ57")
	)
	(segment
		(start 150.838662 -35.4076)
		(end 153.835862 -35.4076)
		(width 0.1524)
		(layer "In2.Cu")
		(net "M_B_DQ57")
	)
	(segment
		(start 139.423394 -35.4076)
		(end 139.7762 -35.4076)
		(width 0.1524)
		(layer "In2.Cu")
		(net "M_B_DQ57")
	)
	(segment
		(start 155.664662 -34.671)
		(end 155.817062 -34.8234)
		(width 0.1524)
		(layer "In2.Cu")
		(net "M_B_DQ57")
	)
	(segment
		(start 110.338362 -35.72764)
		(end 110.0836 -35.982402)
		(width 0.1016)
		(layer "In2.Cu")
		(net "M_B_DQ57")
	)
	(segment
		(start 153.988262 -35.2552)
		(end 153.988262 -34.612834)
		(width 0.1524)
		(layer "In2.Cu")
		(net "M_B_DQ57")
	)
	(segment
		(start 138.77544 -35.750754)
		(end 139.08024 -35.750754)
		(width 0.1524)
		(layer "In2.Cu")
		(net "M_B_DQ57")
	)
	(segment
		(start 149.314662 -34.460434)
		(end 149.467062 -34.612834)
		(width 0.1524)
		(layer "In2.Cu")
		(net "M_B_DQ57")
	)
	(segment
		(start 155.055062 -35.4076)
		(end 155.207462 -35.2552)
		(width 0.1524)
		(layer "In2.Cu")
		(net "M_B_DQ57")
	)
	(segment
		(start 185.5216 -7.697978)
		(end 185.5216 -7.621778)
		(width 0.1524)
		(layer "In2.Cu")
		(net "M_B_DQ57")
	)
	(segment
		(start 131.913376 -35.749484)
		(end 132.25526 -35.4076)
		(width 0.1524)
		(layer "In2.Cu")
		(net "M_B_DQ57")
	)
	(segment
		(start 148.247862 -34.612834)
		(end 148.247862 -35.2552)
		(width 0.1524)
		(layer "In2.Cu")
		(net "M_B_DQ57")
	)
	(segment
		(start 149.009862 -34.460434)
		(end 149.314662 -34.460434)
		(width 0.1524)
		(layer "In2.Cu")
		(net "M_B_DQ57")
	)
	(segment
		(start 117.841014 -35.875214)
		(end 131.7879 -35.875214)
		(width 0.1524)
		(layer "In2.Cu")
		(net "M_B_DQ57")
	)
	(segment
		(start 155.969462 -35.4076)
		(end 157.284166 -35.4076)
		(width 0.1524)
		(layer "In2.Cu")
		(net "M_B_DQ57")
	)
	(segment
		(start 132.25526 -35.4076)
		(end 135.689086 -35.4076)
		(width 0.1524)
		(layer "In2.Cu")
		(net "M_B_DQ57")
	)
	(segment
		(start 131.913376 -35.749738)
		(end 131.913376 -35.749484)
		(width 0.1524)
		(layer "In2.Cu")
		(net "M_B_DQ57")
	)
	(segment
		(start 140.916914 -35.4076)
		(end 145.669 -35.4076)
		(width 0.1524)
		(layer "In2.Cu")
		(net "M_B_DQ57")
	)
	(segment
		(start 154.597862 -35.2552)
		(end 154.750262 -35.4076)
		(width 0.1524)
		(layer "In2.Cu")
		(net "M_B_DQ57")
	)
	(segment
		(start 158.231332 -34.460434)
		(end 183.76265 -8.929116)
		(width 0.1524)
		(layer "In2.Cu")
		(net "M_B_DQ57")
	)
	(segment
		(start 108.4834 -37.3888)
		(end 108.458 -37.3634)
		(width 0.1016)
		(layer "In2.Cu")
		(net "M_B_DQ57")
	)
	(segment
		(start 153.988262 -34.612834)
		(end 154.140662 -34.460434)
		(width 0.1524)
		(layer "In2.Cu")
		(net "M_B_DQ57")
	)
	(segment
		(start 158.231078 -34.460434)
		(end 158.231332 -34.460434)
		(width 0.1524)
		(layer "In2.Cu")
		(net "M_B_DQ57")
	)
	(segment
		(start 110.96244 -35.72764)
		(end 110.338362 -35.72764)
		(width 0.1016)
		(layer "In2.Cu")
		(net "M_B_DQ57")
	)
	(segment
		(start 140.58773 -35.736784)
		(end 140.916914 -35.4076)
		(width 0.1524)
		(layer "In2.Cu")
		(net "M_B_DQ57")
	)
	(segment
		(start 148.400262 -35.4076)
		(end 148.705062 -35.4076)
		(width 0.1524)
		(layer "In2.Cu")
		(net "M_B_DQ57")
	)
	(segment
		(start 150.229062 -34.460434)
		(end 150.533862 -34.460434)
		(width 0.1524)
		(layer "In2.Cu")
		(net "M_B_DQ57")
	)
	(segment
		(start 148.705062 -35.4076)
		(end 148.857462 -35.2552)
		(width 0.1524)
		(layer "In2.Cu")
		(net "M_B_DQ57")
	)
	(segment
		(start 154.597862 -34.612834)
		(end 154.597862 -35.2552)
		(width 0.1524)
		(layer "In2.Cu")
		(net "M_B_DQ57")
	)
	(segment
		(start 137.503154 -35.750754)
		(end 137.756646 -35.750754)
		(width 0.1524)
		(layer "In2.Cu")
		(net "M_B_DQ57")
	)
	(segment
		(start 149.467062 -35.2552)
		(end 149.619462 -35.4076)
		(width 0.1524)
		(layer "In2.Cu")
		(net "M_B_DQ57")
	)
	(segment
		(start 137.756646 -35.750754)
		(end 138.0998 -35.4076)
		(width 0.1524)
		(layer "In2.Cu")
		(net "M_B_DQ57")
	)
	(segment
		(start 137.16 -35.4076)
		(end 137.503154 -35.750754)
		(width 0.1524)
		(layer "In2.Cu")
		(net "M_B_DQ57")
	)
	(segment
		(start 148.247862 -35.2552)
		(end 148.400262 -35.4076)
		(width 0.1524)
		(layer "In2.Cu")
		(net "M_B_DQ57")
	)
	(segment
		(start 154.750262 -35.4076)
		(end 155.055062 -35.4076)
		(width 0.1524)
		(layer "In2.Cu")
		(net "M_B_DQ57")
	)
	(segment
		(start 135.689086 -35.4076)
		(end 136.03224 -35.750754)
		(width 0.1524)
		(layer "In2.Cu")
		(net "M_B_DQ57")
	)
	(segment
		(start 148.095462 -34.460434)
		(end 148.247862 -34.612834)
		(width 0.1524)
		(layer "In2.Cu")
		(net "M_B_DQ57")
	)
	(segment
		(start 155.359862 -34.671)
		(end 155.664662 -34.671)
		(width 0.1524)
		(layer "In2.Cu")
		(net "M_B_DQ57")
	)
	(segment
		(start 131.7879 -35.875214)
		(end 131.913376 -35.749738)
		(width 0.1524)
		(layer "In2.Cu")
		(net "M_B_DQ57")
	)
	(segment
		(start 140.105384 -35.736784)
		(end 140.58773 -35.736784)
		(width 0.1524)
		(layer "In2.Cu")
		(net "M_B_DQ57")
	)
	(segment
		(start 150.686262 -34.612834)
		(end 150.686262 -35.2552)
		(width 0.1524)
		(layer "In2.Cu")
		(net "M_B_DQ57")
	)
	(segment
		(start 155.207462 -35.2552)
		(end 155.207462 -34.8234)
		(width 0.1524)
		(layer "In2.Cu")
		(net "M_B_DQ57")
	)
	(segment
		(start 136.779 -35.4076)
		(end 137.16 -35.4076)
		(width 0.1524)
		(layer "In2.Cu")
		(net "M_B_DQ57")
	)
	(segment
		(start 109.7026 -37.3888)
		(end 108.4834 -37.3888)
		(width 0.1016)
		(layer "In2.Cu")
		(net "M_B_DQ57")
	)
	(segment
		(start 145.669 -35.4076)
		(end 145.8214 -35.2552)
		(width 0.1524)
		(layer "In2.Cu")
		(net "M_B_DQ57")
	)
	(segment
		(start 111.110014 -35.875214)
		(end 110.96244 -35.72764)
		(width 0.1016)
		(layer "In2.Cu")
		(net "M_B_DQ57")
	)
	(segment
		(start 108.458 -37.3634)
		(end 108.4326 -37.3634)
		(width 0.1016)
		(layer "In2.Cu")
		(net "M_B_DQ57")
	)
	(segment
		(start 148.857462 -34.612834)
		(end 149.009862 -34.460434)
		(width 0.1524)
		(layer "In2.Cu")
		(net "M_B_DQ57")
	)
	(segment
		(start 185.5216 -7.621778)
		(end 185.547 -7.596378)
		(width 0.1524)
		(layer "In2.Cu")
		(net "M_B_DQ57")
	)
	(segment
		(start 94.6658 -53.4416)
		(end 95.0976 -53.0098)
		(width 0.1016)
		(layer "F.Cu")
		(net "M_A_DQ63")
	)
	(segment
		(start 95.291148 -52.159662)
		(end 95.291148 -51.85283)
		(width 0.1016)
		(layer "F.Cu")
		(net "M_A_DQ63")
	)
	(segment
		(start 129.980944 -69.37375)
		(end 129.980944 -69.342254)
		(width 0.1778)
		(layer "F.Cu")
		(net "M_A_DQ63")
	)
	(segment
		(start 130.150108 -70.806564)
		(end 130.150108 -69.542914)
		(width 0.1778)
		(layer "F.Cu")
		(net "M_A_DQ63")
	)
	(segment
		(start 95.291148 -51.85283)
		(end 95.067628 -51.62931)
		(width 0.1016)
		(layer "F.Cu")
		(net "M_A_DQ63")
	)
	(segment
		(start 95.0976 -53.0098)
		(end 95.0976 -52.35321)
		(width 0.1016)
		(layer "F.Cu")
		(net "M_A_DQ63")
	)
	(segment
		(start 95.067628 -51.62931)
		(end 95.067628 -50.952654)
		(width 0.1016)
		(layer "F.Cu")
		(net "M_A_DQ63")
	)
	(segment
		(start 130.150108 -69.542914)
		(end 129.980944 -69.37375)
		(width 0.1778)
		(layer "F.Cu")
		(net "M_A_DQ63")
	)
	(segment
		(start 95.0976 -52.35321)
		(end 95.291148 -52.159662)
		(width 0.1016)
		(layer "F.Cu")
		(net "M_A_DQ63")
	)
	(segment
		(start 94.6658 -54.2798)
		(end 94.6658 -53.4416)
		(width 0.1016)
		(layer "F.Cu")
		(net "M_A_DQ63")
	)
	(via
		(at 129.980944 -69.342254)
		(size 0.4318)
		(drill 0.2032)
		(layers "F.Cu" "B.Cu")
		(net "M_A_DQ63")
	)
	(via
		(at 94.6658 -54.2798)
		(size 0.4318)
		(drill 0.2032)
		(layers "F.Cu" "B.Cu")
		(net "M_A_DQ63")
	)
	(segment
		(start 129.850134 -70.79996)
		(end 129.850134 -69.473064)
		(width 0.1778)
		(layer "B.Cu")
		(net "M_A_DQ63")
	)
	(segment
		(start 129.850134 -69.473064)
		(end 129.980944 -69.342254)
		(width 0.1778)
		(layer "B.Cu")
		(net "M_A_DQ63")
	)
	(segment
		(start 131.022598 -64.855598)
		(end 130.38074 -64.21374)
		(width 0.1524)
		(layer "In7.Cu")
		(net "M_A_DQ63")
	)
	(segment
		(start 94.361 -55.8546)
		(end 94.361 -54.5846)
		(width 0.1016)
		(layer "In7.Cu")
		(net "M_A_DQ63")
	)
	(segment
		(start 100.438204 -67.6148)
		(end 95.246952 -62.423548)
		(width 0.1524)
		(layer "In7.Cu")
		(net "M_A_DQ63")
	)
	(segment
		(start 131.022598 -65.784476)
		(end 131.022598 -64.855598)
		(width 0.1524)
		(layer "In7.Cu")
		(net "M_A_DQ63")
	)
	(segment
		(start 119.126 -67.056)
		(end 118.5672 -67.6148)
		(width 0.1524)
		(layer "In7.Cu")
		(net "M_A_DQ63")
	)
	(segment
		(start 95.246952 -62.423548)
		(end 95.246952 -59.763152)
		(width 0.1524)
		(layer "In7.Cu")
		(net "M_A_DQ63")
	)
	(segment
		(start 95.246952 -59.763152)
		(end 94.1832 -58.6994)
		(width 0.1016)
		(layer "In7.Cu")
		(net "M_A_DQ63")
	)
	(segment
		(start 129.980944 -69.304662)
		(end 129.981198 -69.304408)
		(width 0.1524)
		(layer "In7.Cu")
		(net "M_A_DQ63")
	)
	(segment
		(start 129.981198 -69.304408)
		(end 129.981198 -66.82613)
		(width 0.1524)
		(layer "In7.Cu")
		(net "M_A_DQ63")
	)
	(segment
		(start 94.1832 -58.6994)
		(end 94.1832 -56.0324)
		(width 0.1016)
		(layer "In7.Cu")
		(net "M_A_DQ63")
	)
	(segment
		(start 125.793246 -68.223892)
		(end 124.42063 -68.223892)
		(width 0.1524)
		(layer "In7.Cu")
		(net "M_A_DQ63")
	)
	(segment
		(start 129.803398 -64.21374)
		(end 125.793246 -68.223892)
		(width 0.1524)
		(layer "In7.Cu")
		(net "M_A_DQ63")
	)
	(segment
		(start 129.981198 -66.82613)
		(end 130.886962 -65.920366)
		(width 0.1524)
		(layer "In7.Cu")
		(net "M_A_DQ63")
	)
	(segment
		(start 130.38074 -64.21374)
		(end 129.803398 -64.21374)
		(width 0.1524)
		(layer "In7.Cu")
		(net "M_A_DQ63")
	)
	(segment
		(start 123.252738 -67.056)
		(end 119.126 -67.056)
		(width 0.1524)
		(layer "In7.Cu")
		(net "M_A_DQ63")
	)
	(segment
		(start 129.980944 -69.342254)
		(end 129.980944 -69.304662)
		(width 0.1524)
		(layer "In7.Cu")
		(net "M_A_DQ63")
	)
	(segment
		(start 94.361 -54.5846)
		(end 94.6658 -54.2798)
		(width 0.1016)
		(layer "In7.Cu")
		(net "M_A_DQ63")
	)
	(segment
		(start 118.5672 -67.6148)
		(end 100.438204 -67.6148)
		(width 0.1524)
		(layer "In7.Cu")
		(net "M_A_DQ63")
	)
	(segment
		(start 130.886962 -65.920366)
		(end 131.022598 -65.784476)
		(width 0.1524)
		(layer "In7.Cu")
		(net "M_A_DQ63")
	)
	(segment
		(start 124.42063 -68.223892)
		(end 123.252738 -67.056)
		(width 0.1524)
		(layer "In7.Cu")
		(net "M_A_DQ63")
	)
	(segment
		(start 94.1832 -56.0324)
		(end 94.361 -55.8546)
		(width 0.1016)
		(layer "In7.Cu")
		(net "M_A_DQ63")
	)
	(segment
		(start 108.433108 -31.724854)
		(end 108.43768 -31.724854)
		(width 0.1778)
		(layer "F.Cu")
		(net "M_B_ODT2")
	)
	(segment
		(start 168.249854 -9.897364)
		(end 168.249854 -9.196578)
		(width 0.1778)
		(layer "F.Cu")
		(net "M_B_ODT2")
	)
	(segment
		(start 168.068752 -8.87857)
		(end 167.456612 -8.115554)
		(width 0.1778)
		(layer "F.Cu")
		(net "M_B_ODT2")
	)
	(segment
		(start 167.456612 -8.115554)
		(end 167.431974 -8.090916)
		(width 0.1778)
		(layer "F.Cu")
		(net "M_B_ODT2")
	)
	(segment
		(start 168.249854 -9.196578)
		(end 168.068752 -8.87857)
		(width 0.1778)
		(layer "F.Cu")
		(net "M_B_ODT2")
	)
	(segment
		(start 167.431974 -8.090916)
		(end 167.1066 -7.79526)
		(width 0.1778)
		(layer "F.Cu")
		(net "M_B_ODT2")
	)
	(segment
		(start 108.43768 -31.724854)
		(end 108.77677 -32.063944)
		(width 0.1778)
		(layer "F.Cu")
		(net "M_B_ODT2")
	)
	(via
		(at 167.1066 -7.79526)
		(size 0.4318)
		(drill 0.2032)
		(layers "F.Cu" "B.Cu")
		(net "M_B_ODT2")
	)
	(via
		(at 108.77677 -32.063944)
		(size 0.4318)
		(drill 0.2032)
		(layers "F.Cu" "B.Cu")
		(net "M_B_ODT2")
	)
	(segment
		(start 113.316512 -26.129488)
		(end 113.316512 -27.138376)
		(width 0.1524)
		(layer "In9.Cu")
		(net "M_B_ODT2")
	)
	(segment
		(start 156.21 -21.252942)
		(end 155.331414 -22.131528)
		(width 0.1524)
		(layer "In9.Cu")
		(net "M_B_ODT2")
	)
	(segment
		(start 154.68473 -22.778212)
		(end 154.46883 -22.994112)
		(width 0.1524)
		(layer "In9.Cu")
		(net "M_B_ODT2")
	)
	(segment
		(start 152.959562 -24.50338)
		(end 152.545796 -24.917146)
		(width 0.1524)
		(layer "In9.Cu")
		(net "M_B_ODT2")
	)
	(segment
		(start 155.196286 -23.074376)
		(end 154.900122 -22.778212)
		(width 0.1524)
		(layer "In9.Cu")
		(net "M_B_ODT2")
	)
	(segment
		(start 167.1066 -7.79526)
		(end 167.110918 -7.799578)
		(width 0.1524)
		(layer "In9.Cu")
		(net "M_B_ODT2")
	)
	(segment
		(start 154.333702 -23.93696)
		(end 154.037538 -23.640796)
		(width 0.1524)
		(layer "In9.Cu")
		(net "M_B_ODT2")
	)
	(segment
		(start 164.47135 -17.13865)
		(end 160.324292 -17.13865)
		(width 0.1524)
		(layer "In9.Cu")
		(net "M_B_ODT2")
	)
	(segment
		(start 114.182652 -25.263348)
		(end 113.316512 -26.129488)
		(width 0.1524)
		(layer "In9.Cu")
		(net "M_B_ODT2")
	)
	(segment
		(start 156.3624 -19.99615)
		(end 156.21 -20.14855)
		(width 0.1524)
		(layer "In9.Cu")
		(net "M_B_ODT2")
	)
	(segment
		(start 155.411678 -23.074376)
		(end 155.196286 -23.074376)
		(width 0.1524)
		(layer "In9.Cu")
		(net "M_B_ODT2")
	)
	(segment
		(start 155.331414 -22.131528)
		(end 155.331414 -22.34692)
		(width 0.1524)
		(layer "In9.Cu")
		(net "M_B_ODT2")
	)
	(segment
		(start 154.549094 -23.93696)
		(end 154.333702 -23.93696)
		(width 0.1524)
		(layer "In9.Cu")
		(net "M_B_ODT2")
	)
	(segment
		(start 153.174954 -24.50338)
		(end 152.959562 -24.50338)
		(width 0.1524)
		(layer "In9.Cu")
		(net "M_B_ODT2")
	)
	(segment
		(start 154.46883 -22.994112)
		(end 154.46883 -23.209504)
		(width 0.1524)
		(layer "In9.Cu")
		(net "M_B_ODT2")
	)
	(segment
		(start 154.764994 -23.505668)
		(end 154.764994 -23.72106)
		(width 0.1524)
		(layer "In9.Cu")
		(net "M_B_ODT2")
	)
	(segment
		(start 110.0074 -28.951936)
		(end 110.0074 -29.6672)
		(width 0.1524)
		(layer "In9.Cu")
		(net "M_B_ODT2")
	)
	(segment
		(start 167.110918 -7.799578)
		(end 167.123364 -7.799578)
		(width 0.1524)
		(layer "In9.Cu")
		(net "M_B_ODT2")
	)
	(segment
		(start 167.386 -10.872724)
		(end 168.224454 -11.711178)
		(width 0.1524)
		(layer "In9.Cu")
		(net "M_B_ODT2")
	)
	(segment
		(start 168.224454 -11.711178)
		(end 168.224454 -13.385546)
		(width 0.1524)
		(layer "In9.Cu")
		(net "M_B_ODT2")
	)
	(segment
		(start 114.182906 -25.263348)
		(end 114.182652 -25.263348)
		(width 0.1524)
		(layer "In9.Cu")
		(net "M_B_ODT2")
	)
	(segment
		(start 155.331414 -22.34692)
		(end 155.627578 -22.643084)
		(width 0.1524)
		(layer "In9.Cu")
		(net "M_B_ODT2")
	)
	(segment
		(start 154.900122 -22.778212)
		(end 154.68473 -22.778212)
		(width 0.1524)
		(layer "In9.Cu")
		(net "M_B_ODT2")
	)
	(segment
		(start 153.90241 -24.368252)
		(end 153.90241 -24.583644)
		(width 0.1524)
		(layer "In9.Cu")
		(net "M_B_ODT2")
	)
	(segment
		(start 153.606246 -24.072088)
		(end 153.90241 -24.368252)
		(width 0.1524)
		(layer "In9.Cu")
		(net "M_B_ODT2")
	)
	(segment
		(start 154.764994 -23.72106)
		(end 154.549094 -23.93696)
		(width 0.1524)
		(layer "In9.Cu")
		(net "M_B_ODT2")
	)
	(segment
		(start 167.564562 -8.240776)
		(end 167.564562 -8.619744)
		(width 0.1524)
		(layer "In9.Cu")
		(net "M_B_ODT2")
	)
	(segment
		(start 153.471118 -24.799544)
		(end 153.174954 -24.50338)
		(width 0.1524)
		(layer "In9.Cu")
		(net "M_B_ODT2")
	)
	(segment
		(start 168.224454 -13.385546)
		(end 164.47135 -17.13865)
		(width 0.1524)
		(layer "In9.Cu")
		(net "M_B_ODT2")
	)
	(segment
		(start 113.316512 -27.138376)
		(end 112.171988 -28.2829)
		(width 0.1524)
		(layer "In9.Cu")
		(net "M_B_ODT2")
	)
	(segment
		(start 109.748066 -29.926534)
		(end 109.748066 -30.52572)
		(width 0.1524)
		(layer "In9.Cu")
		(net "M_B_ODT2")
	)
	(segment
		(start 154.037538 -23.640796)
		(end 153.822146 -23.640796)
		(width 0.1524)
		(layer "In9.Cu")
		(net "M_B_ODT2")
	)
	(segment
		(start 112.171988 -28.2829)
		(end 110.676436 -28.2829)
		(width 0.1524)
		(layer "In9.Cu")
		(net "M_B_ODT2")
	)
	(segment
		(start 109.748066 -30.52572)
		(end 108.77677 -31.497016)
		(width 0.1524)
		(layer "In9.Cu")
		(net "M_B_ODT2")
	)
	(segment
		(start 167.386 -8.798306)
		(end 167.386 -10.872724)
		(width 0.1524)
		(layer "In9.Cu")
		(net "M_B_ODT2")
	)
	(segment
		(start 110.0074 -29.6672)
		(end 109.748066 -29.926534)
		(width 0.1524)
		(layer "In9.Cu")
		(net "M_B_ODT2")
	)
	(segment
		(start 156.21 -20.14855)
		(end 156.21 -21.252942)
		(width 0.1524)
		(layer "In9.Cu")
		(net "M_B_ODT2")
	)
	(segment
		(start 155.627578 -22.643084)
		(end 155.627578 -22.858476)
		(width 0.1524)
		(layer "In9.Cu")
		(net "M_B_ODT2")
	)
	(segment
		(start 167.564562 -8.619744)
		(end 167.386 -8.798306)
		(width 0.1524)
		(layer "In9.Cu")
		(net "M_B_ODT2")
	)
	(segment
		(start 114.529108 -24.917146)
		(end 114.182906 -25.263348)
		(width 0.1524)
		(layer "In9.Cu")
		(net "M_B_ODT2")
	)
	(segment
		(start 157.466792 -19.99615)
		(end 156.3624 -19.99615)
		(width 0.1524)
		(layer "In9.Cu")
		(net "M_B_ODT2")
	)
	(segment
		(start 155.627578 -22.858476)
		(end 155.411678 -23.074376)
		(width 0.1524)
		(layer "In9.Cu")
		(net "M_B_ODT2")
	)
	(segment
		(start 153.68651 -24.799544)
		(end 153.471118 -24.799544)
		(width 0.1524)
		(layer "In9.Cu")
		(net "M_B_ODT2")
	)
	(segment
		(start 167.123364 -7.799578)
		(end 167.564562 -8.240776)
		(width 0.1524)
		(layer "In9.Cu")
		(net "M_B_ODT2")
	)
	(segment
		(start 152.545796 -24.917146)
		(end 114.529108 -24.917146)
		(width 0.1524)
		(layer "In9.Cu")
		(net "M_B_ODT2")
	)
	(segment
		(start 160.324292 -17.13865)
		(end 157.466792 -19.99615)
		(width 0.1524)
		(layer "In9.Cu")
		(net "M_B_ODT2")
	)
	(segment
		(start 153.90241 -24.583644)
		(end 153.68651 -24.799544)
		(width 0.1524)
		(layer "In9.Cu")
		(net "M_B_ODT2")
	)
	(segment
		(start 153.606246 -23.856696)
		(end 153.606246 -24.072088)
		(width 0.1524)
		(layer "In9.Cu")
		(net "M_B_ODT2")
	)
	(segment
		(start 108.77677 -31.497016)
		(end 108.77677 -32.063944)
		(width 0.1524)
		(layer "In9.Cu")
		(net "M_B_ODT2")
	)
	(segment
		(start 154.46883 -23.209504)
		(end 154.764994 -23.505668)
		(width 0.1524)
		(layer "In9.Cu")
		(net "M_B_ODT2")
	)
	(segment
		(start 110.676436 -28.2829)
		(end 110.0074 -28.951936)
		(width 0.1524)
		(layer "In9.Cu")
		(net "M_B_ODT2")
	)
	(segment
		(start 153.822146 -23.640796)
		(end 153.606246 -23.856696)
		(width 0.1524)
		(layer "In9.Cu")
		(net "M_B_ODT2")
	)
	(segment
		(start 183.66613 -63.71717)
		(end 183.66613 -64.349122)
		(width 0.1778)
		(layer "F.Cu")
		(net "M_A_DQ9")
	)
	(segment
		(start 183.261 -64.754252)
		(end 183.261 -64.77)
		(width 0.1778)
		(layer "F.Cu")
		(net "M_A_DQ9")
	)
	(segment
		(start 183.66613 -64.349122)
		(end 183.261 -64.754252)
		(width 0.1778)
		(layer "F.Cu")
		(net "M_A_DQ9")
	)
	(segment
		(start 183.250078 -63.301118)
		(end 183.66613 -63.71717)
		(width 0.1778)
		(layer "F.Cu")
		(net "M_A_DQ9")
	)
	(segment
		(start 106.147108 -43.642534)
		(end 106.194098 -43.642534)
		(width 0.1016)
		(layer "F.Cu")
		(net "M_A_DQ9")
	)
	(segment
		(start 106.194098 -43.642534)
		(end 106.541062 -43.989498)
		(width 0.1016)
		(layer "F.Cu")
		(net "M_A_DQ9")
	)
	(segment
		(start 183.250078 -62.59322)
		(end 183.250078 -63.301118)
		(width 0.1778)
		(layer "F.Cu")
		(net "M_A_DQ9")
	)
	(via
		(at 106.541062 -43.989498)
		(size 0.4318)
		(drill 0.2032)
		(layers "F.Cu" "B.Cu")
		(net "M_A_DQ9")
	)
	(via
		(at 183.261 -64.77)
		(size 0.4318)
		(drill 0.2032)
		(layers "F.Cu" "B.Cu")
		(net "M_A_DQ9")
	)
	(segment
		(start 184.15 -63.3222)
		(end 183.66613 -63.80607)
		(width 0.1778)
		(layer "B.Cu")
		(net "M_A_DQ9")
	)
	(segment
		(start 183.66613 -63.80607)
		(end 183.66613 -64.300608)
		(width 0.1778)
		(layer "B.Cu")
		(net "M_A_DQ9")
	)
	(segment
		(start 183.288178 -64.742822)
		(end 183.261 -64.77)
		(width 0.1778)
		(layer "B.Cu")
		(net "M_A_DQ9")
	)
	(segment
		(start 183.66613 -64.300608)
		(end 183.288178 -64.742822)
		(width 0.1778)
		(layer "B.Cu")
		(net "M_A_DQ9")
	)
	(segment
		(start 184.15 -62.599824)
		(end 184.15 -63.3222)
		(width 0.1778)
		(layer "B.Cu")
		(net "M_A_DQ9")
	)
	(segment
		(start 131.863084 -42.822622)
		(end 131.710684 -42.670222)
		(width 0.1524)
		(layer "In4.Cu")
		(net "M_A_DQ9")
	)
	(segment
		(start 126.681484 -42.3926)
		(end 126.376684 -42.3926)
		(width 0.1524)
		(layer "In4.Cu")
		(net "M_A_DQ9")
	)
	(segment
		(start 134.149084 -42.545)
		(end 133.996684 -42.3926)
		(width 0.1524)
		(layer "In4.Cu")
		(net "M_A_DQ9")
	)
	(segment
		(start 109.752384 -42.673016)
		(end 110.236 -42.1894)
		(width 0.1016)
		(layer "In4.Cu")
		(net "M_A_DQ9")
	)
	(segment
		(start 125.005084 -42.670222)
		(end 124.852684 -42.822622)
		(width 0.1524)
		(layer "In4.Cu")
		(net "M_A_DQ9")
	)
	(segment
		(start 133.539484 -42.670222)
		(end 133.387084 -42.822622)
		(width 0.1524)
		(layer "In4.Cu")
		(net "M_A_DQ9")
	)
	(segment
		(start 176.464976 -53.117242)
		(end 173.183042 -53.117242)
		(width 0.1524)
		(layer "In4.Cu")
		(net "M_A_DQ9")
	)
	(segment
		(start 136.587484 -42.545)
		(end 136.435084 -42.3926)
		(width 0.1524)
		(layer "In4.Cu")
		(net "M_A_DQ9")
	)
	(segment
		(start 132.472684 -42.3926)
		(end 132.320284 -42.545)
		(width 0.1524)
		(layer "In4.Cu")
		(net "M_A_DQ9")
	)
	(segment
		(start 135.368284 -42.670222)
		(end 135.368284 -42.545)
		(width 0.1524)
		(layer "In4.Cu")
		(net "M_A_DQ9")
	)
	(segment
		(start 112.3188 -41.6052)
		(end 111.7346 -42.1894)
		(width 0.1524)
		(layer "In4.Cu")
		(net "M_A_DQ9")
	)
	(segment
		(start 127.443484 -42.670222)
		(end 127.291084 -42.822622)
		(width 0.1524)
		(layer "In4.Cu")
		(net "M_A_DQ9")
	)
	(segment
		(start 136.739884 -42.822622)
		(end 136.587484 -42.670222)
		(width 0.1524)
		(layer "In4.Cu")
		(net "M_A_DQ9")
	)
	(segment
		(start 129.881884 -42.670222)
		(end 129.729484 -42.822622)
		(width 0.1524)
		(layer "In4.Cu")
		(net "M_A_DQ9")
	)
	(segment
		(start 183.2864 -64.7192)
		(end 183.6674 -64.3382)
		(width 0.1524)
		(layer "In4.Cu")
		(net "M_A_DQ9")
	)
	(segment
		(start 134.758684 -42.545)
		(end 134.758684 -42.670222)
		(width 0.1524)
		(layer "In4.Cu")
		(net "M_A_DQ9")
	)
	(segment
		(start 126.376684 -42.3926)
		(end 126.224284 -42.545)
		(width 0.1524)
		(layer "In4.Cu")
		(net "M_A_DQ9")
	)
	(segment
		(start 109.13872 -42.484294)
		(end 109.354366 -42.69994)
		(width 0.1016)
		(layer "In4.Cu")
		(net "M_A_DQ9")
	)
	(segment
		(start 132.167884 -42.822622)
		(end 131.863084 -42.822622)
		(width 0.1524)
		(layer "In4.Cu")
		(net "M_A_DQ9")
	)
	(segment
		(start 132.320284 -42.670222)
		(end 132.167884 -42.822622)
		(width 0.1524)
		(layer "In4.Cu")
		(net "M_A_DQ9")
	)
	(segment
		(start 123.176284 -42.670222)
		(end 123.176284 -42.545)
		(width 0.1524)
		(layer "In4.Cu")
		(net "M_A_DQ9")
	)
	(segment
		(start 137.806684 -42.545)
		(end 137.654284 -42.3926)
		(width 0.1524)
		(layer "In4.Cu")
		(net "M_A_DQ9")
	)
	(segment
		(start 135.368284 -42.545)
		(end 135.215884 -42.3926)
		(width 0.1524)
		(layer "In4.Cu")
		(net "M_A_DQ9")
	)
	(segment
		(start 123.938284 -42.3926)
		(end 123.785884 -42.545)
		(width 0.1524)
		(layer "In4.Cu")
		(net "M_A_DQ9")
	)
	(segment
		(start 154.0002 -42.3926)
		(end 138.568684 -42.3926)
		(width 0.1524)
		(layer "In4.Cu")
		(net "M_A_DQ9")
	)
	(segment
		(start 137.197084 -42.545)
		(end 137.197084 -42.670222)
		(width 0.1524)
		(layer "In4.Cu")
		(net "M_A_DQ9")
	)
	(segment
		(start 135.520684 -42.822622)
		(end 135.368284 -42.670222)
		(width 0.1524)
		(layer "In4.Cu")
		(net "M_A_DQ9")
	)
	(segment
		(start 127.443484 -42.545)
		(end 127.443484 -42.670222)
		(width 0.1524)
		(layer "In4.Cu")
		(net "M_A_DQ9")
	)
	(segment
		(start 138.416284 -42.545)
		(end 138.416284 -42.670222)
		(width 0.1524)
		(layer "In4.Cu")
		(net "M_A_DQ9")
	)
	(segment
		(start 111.7346 -42.1894)
		(end 111.506 -42.1894)
		(width 0.1524)
		(layer "In4.Cu")
		(net "M_A_DQ9")
	)
	(segment
		(start 131.710684 -42.545)
		(end 131.558284 -42.3926)
		(width 0.1524)
		(layer "In4.Cu")
		(net "M_A_DQ9")
	)
	(segment
		(start 131.558284 -42.3926)
		(end 131.253484 -42.3926)
		(width 0.1524)
		(layer "In4.Cu")
		(net "M_A_DQ9")
	)
	(segment
		(start 138.263884 -42.822622)
		(end 137.959084 -42.822622)
		(width 0.1524)
		(layer "In4.Cu")
		(net "M_A_DQ9")
	)
	(segment
		(start 126.224284 -42.545)
		(end 126.224284 -42.670222)
		(width 0.1524)
		(layer "In4.Cu")
		(net "M_A_DQ9")
	)
	(segment
		(start 138.568684 -42.3926)
		(end 138.416284 -42.545)
		(width 0.1524)
		(layer "In4.Cu")
		(net "M_A_DQ9")
	)
	(segment
		(start 124.395484 -42.670222)
		(end 124.395484 -42.545)
		(width 0.1524)
		(layer "In4.Cu")
		(net "M_A_DQ9")
	)
	(segment
		(start 109.13872 -42.4434)
		(end 109.13872 -42.484294)
		(width 0.1016)
		(layer "In4.Cu")
		(net "M_A_DQ9")
	)
	(segment
		(start 135.215884 -42.3926)
		(end 134.911084 -42.3926)
		(width 0.1524)
		(layer "In4.Cu")
		(net "M_A_DQ9")
	)
	(segment
		(start 131.710684 -42.670222)
		(end 131.710684 -42.545)
		(width 0.1524)
		(layer "In4.Cu")
		(net "M_A_DQ9")
	)
	(segment
		(start 130.491484 -42.670222)
		(end 130.491484 -42.545)
		(width 0.1524)
		(layer "In4.Cu")
		(net "M_A_DQ9")
	)
	(segment
		(start 180.9496 -57.601866)
		(end 176.464976 -53.117242)
		(width 0.1524)
		(layer "In4.Cu")
		(net "M_A_DQ9")
	)
	(segment
		(start 130.491484 -42.545)
		(end 130.339084 -42.3926)
		(width 0.1524)
		(layer "In4.Cu")
		(net "M_A_DQ9")
	)
	(segment
		(start 132.929884 -42.670222)
		(end 132.929884 -42.545)
		(width 0.1524)
		(layer "In4.Cu")
		(net "M_A_DQ9")
	)
	(segment
		(start 107.81792 -42.57548)
		(end 107.81792 -42.377106)
		(width 0.1016)
		(layer "In4.Cu")
		(net "M_A_DQ9")
	)
	(segment
		(start 128.662684 -42.670222)
		(end 128.510284 -42.822622)
		(width 0.1524)
		(layer "In4.Cu")
		(net "M_A_DQ9")
	)
	(segment
		(start 135.977884 -42.670222)
		(end 135.825484 -42.822622)
		(width 0.1524)
		(layer "In4.Cu")
		(net "M_A_DQ9")
	)
	(segment
		(start 133.082284 -42.822622)
		(end 132.929884 -42.670222)
		(width 0.1524)
		(layer "In4.Cu")
		(net "M_A_DQ9")
	)
	(segment
		(start 138.416284 -42.670222)
		(end 138.263884 -42.822622)
		(width 0.1524)
		(layer "In4.Cu")
		(net "M_A_DQ9")
	)
	(segment
		(start 183.4134 -62.82436)
		(end 183.4134 -61.491114)
		(width 0.1524)
		(layer "In4.Cu")
		(net "M_A_DQ9")
	)
	(segment
		(start 107.467654 -42.925746)
		(end 107.81792 -42.57548)
		(width 0.1016)
		(layer "In4.Cu")
		(net "M_A_DQ9")
	)
	(segment
		(start 132.320284 -42.545)
		(end 132.320284 -42.670222)
		(width 0.1524)
		(layer "In4.Cu")
		(net "M_A_DQ9")
	)
	(segment
		(start 173.183042 -53.117242)
		(end 165.5064 -45.4406)
		(width 0.1524)
		(layer "In4.Cu")
		(net "M_A_DQ9")
	)
	(segment
		(start 109.354366 -42.69994)
		(end 109.725206 -42.69994)
		(width 0.1016)
		(layer "In4.Cu")
		(net "M_A_DQ9")
	)
	(segment
		(start 156.166312 -42.9006)
		(end 154.0002 -42.3926)
		(width 0.1524)
		(layer "In4.Cu")
		(net "M_A_DQ9")
	)
	(segment
		(start 129.119884 -42.3926)
		(end 128.815084 -42.3926)
		(width 0.1524)
		(layer "In4.Cu")
		(net "M_A_DQ9")
	)
	(segment
		(start 132.929884 -42.545)
		(end 132.777484 -42.3926)
		(width 0.1524)
		(layer "In4.Cu")
		(net "M_A_DQ9")
	)
	(segment
		(start 128.053084 -42.545)
		(end 127.900684 -42.3926)
		(width 0.1524)
		(layer "In4.Cu")
		(net "M_A_DQ9")
	)
	(segment
		(start 136.435084 -42.3926)
		(end 136.130284 -42.3926)
		(width 0.1524)
		(layer "In4.Cu")
		(net "M_A_DQ9")
	)
	(segment
		(start 106.88066 -43.6499)
		(end 106.88066 -43.15714)
		(width 0.1016)
		(layer "In4.Cu")
		(net "M_A_DQ9")
	)
	(segment
		(start 129.272284 -42.545)
		(end 129.119884 -42.3926)
		(width 0.1524)
		(layer "In4.Cu")
		(net "M_A_DQ9")
	)
	(segment
		(start 137.044684 -42.822622)
		(end 136.739884 -42.822622)
		(width 0.1524)
		(layer "In4.Cu")
		(net "M_A_DQ9")
	)
	(segment
		(start 137.654284 -42.3926)
		(end 137.349484 -42.3926)
		(width 0.1524)
		(layer "In4.Cu")
		(net "M_A_DQ9")
	)
	(segment
		(start 134.301484 -42.822622)
		(end 134.149084 -42.670222)
		(width 0.1524)
		(layer "In4.Cu")
		(net "M_A_DQ9")
	)
	(segment
		(start 129.424684 -42.822622)
		(end 129.272284 -42.670222)
		(width 0.1524)
		(layer "In4.Cu")
		(net "M_A_DQ9")
	)
	(segment
		(start 129.272284 -42.670222)
		(end 129.272284 -42.545)
		(width 0.1524)
		(layer "In4.Cu")
		(net "M_A_DQ9")
	)
	(segment
		(start 123.785884 -42.545)
		(end 123.785884 -42.670222)
		(width 0.1524)
		(layer "In4.Cu")
		(net "M_A_DQ9")
	)
	(segment
		(start 124.852684 -42.822622)
		(end 124.547884 -42.822622)
		(width 0.1524)
		(layer "In4.Cu")
		(net "M_A_DQ9")
	)
	(segment
		(start 183.261 -64.77)
		(end 183.2864 -64.7446)
		(width 0.1524)
		(layer "In4.Cu")
		(net "M_A_DQ9")
	)
	(segment
		(start 183.2864 -64.7446)
		(end 183.2864 -64.7192)
		(width 0.1524)
		(layer "In4.Cu")
		(net "M_A_DQ9")
	)
	(segment
		(start 128.662684 -42.545)
		(end 128.662684 -42.670222)
		(width 0.1524)
		(layer "In4.Cu")
		(net "M_A_DQ9")
	)
	(segment
		(start 180.9496 -59.027314)
		(end 180.9496 -57.601866)
		(width 0.1524)
		(layer "In4.Cu")
		(net "M_A_DQ9")
	)
	(segment
		(start 135.977884 -42.545)
		(end 135.977884 -42.670222)
		(width 0.1524)
		(layer "In4.Cu")
		(net "M_A_DQ9")
	)
	(segment
		(start 127.291084 -42.822622)
		(end 126.986284 -42.822622)
		(width 0.1524)
		(layer "In4.Cu")
		(net "M_A_DQ9")
	)
	(segment
		(start 126.833884 -42.545)
		(end 126.681484 -42.3926)
		(width 0.1524)
		(layer "In4.Cu")
		(net "M_A_DQ9")
	)
	(segment
		(start 135.825484 -42.822622)
		(end 135.520684 -42.822622)
		(width 0.1524)
		(layer "In4.Cu")
		(net "M_A_DQ9")
	)
	(segment
		(start 134.149084 -42.670222)
		(end 134.149084 -42.545)
		(width 0.1524)
		(layer "In4.Cu")
		(net "M_A_DQ9")
	)
	(segment
		(start 125.157484 -42.3926)
		(end 125.005084 -42.545)
		(width 0.1524)
		(layer "In4.Cu")
		(net "M_A_DQ9")
	)
	(segment
		(start 107.81792 -42.377106)
		(end 108.051346 -42.14368)
		(width 0.1016)
		(layer "In4.Cu")
		(net "M_A_DQ9")
	)
	(segment
		(start 137.349484 -42.3926)
		(end 137.197084 -42.545)
		(width 0.1524)
		(layer "In4.Cu")
		(net "M_A_DQ9")
	)
	(segment
		(start 183.6674 -63.07836)
		(end 183.4134 -62.82436)
		(width 0.1524)
		(layer "In4.Cu")
		(net "M_A_DQ9")
	)
	(segment
		(start 130.643884 -42.822622)
		(end 130.491484 -42.670222)
		(width 0.1524)
		(layer "In4.Cu")
		(net "M_A_DQ9")
	)
	(segment
		(start 118.9482 -42.3926)
		(end 118.1608 -41.6052)
		(width 0.1524)
		(layer "In4.Cu")
		(net "M_A_DQ9")
	)
	(segment
		(start 133.387084 -42.822622)
		(end 133.082284 -42.822622)
		(width 0.1524)
		(layer "In4.Cu")
		(net "M_A_DQ9")
	)
	(segment
		(start 133.539484 -42.545)
		(end 133.539484 -42.670222)
		(width 0.1524)
		(layer "In4.Cu")
		(net "M_A_DQ9")
	)
	(segment
		(start 108.051346 -42.14368)
		(end 108.839 -42.14368)
		(width 0.1016)
		(layer "In4.Cu")
		(net "M_A_DQ9")
	)
	(segment
		(start 125.462284 -42.3926)
		(end 125.157484 -42.3926)
		(width 0.1524)
		(layer "In4.Cu")
		(net "M_A_DQ9")
	)
	(segment
		(start 131.101084 -42.545)
		(end 131.101084 -42.670222)
		(width 0.1524)
		(layer "In4.Cu")
		(net "M_A_DQ9")
	)
	(segment
		(start 126.833884 -42.670222)
		(end 126.833884 -42.545)
		(width 0.1524)
		(layer "In4.Cu")
		(net "M_A_DQ9")
	)
	(segment
		(start 134.606284 -42.822622)
		(end 134.301484 -42.822622)
		(width 0.1524)
		(layer "In4.Cu")
		(net "M_A_DQ9")
	)
	(segment
		(start 124.243084 -42.3926)
		(end 123.938284 -42.3926)
		(width 0.1524)
		(layer "In4.Cu")
		(net "M_A_DQ9")
	)
	(segment
		(start 123.023884 -42.3926)
		(end 118.9482 -42.3926)
		(width 0.1524)
		(layer "In4.Cu")
		(net "M_A_DQ9")
	)
	(segment
		(start 123.176284 -42.545)
		(end 123.023884 -42.3926)
		(width 0.1524)
		(layer "In4.Cu")
		(net "M_A_DQ9")
	)
	(segment
		(start 125.614684 -42.670222)
		(end 125.614684 -42.545)
		(width 0.1524)
		(layer "In4.Cu")
		(net "M_A_DQ9")
	)
	(segment
		(start 128.510284 -42.822622)
		(end 128.205484 -42.822622)
		(width 0.1524)
		(layer "In4.Cu")
		(net "M_A_DQ9")
	)
	(segment
		(start 133.691884 -42.3926)
		(end 133.539484 -42.545)
		(width 0.1524)
		(layer "In4.Cu")
		(net "M_A_DQ9")
	)
	(segment
		(start 125.767084 -42.822622)
		(end 125.614684 -42.670222)
		(width 0.1524)
		(layer "In4.Cu")
		(net "M_A_DQ9")
	)
	(segment
		(start 132.777484 -42.3926)
		(end 132.472684 -42.3926)
		(width 0.1524)
		(layer "In4.Cu")
		(net "M_A_DQ9")
	)
	(segment
		(start 106.88066 -43.15714)
		(end 107.112054 -42.925746)
		(width 0.1016)
		(layer "In4.Cu")
		(net "M_A_DQ9")
	)
	(segment
		(start 131.253484 -42.3926)
		(end 131.101084 -42.545)
		(width 0.1524)
		(layer "In4.Cu")
		(net "M_A_DQ9")
	)
	(segment
		(start 125.005084 -42.545)
		(end 125.005084 -42.670222)
		(width 0.1524)
		(layer "In4.Cu")
		(net "M_A_DQ9")
	)
	(segment
		(start 134.911084 -42.3926)
		(end 134.758684 -42.545)
		(width 0.1524)
		(layer "In4.Cu")
		(net "M_A_DQ9")
	)
	(segment
		(start 127.595884 -42.3926)
		(end 127.443484 -42.545)
		(width 0.1524)
		(layer "In4.Cu")
		(net "M_A_DQ9")
	)
	(segment
		(start 123.328684 -42.822622)
		(end 123.176284 -42.670222)
		(width 0.1524)
		(layer "In4.Cu")
		(net "M_A_DQ9")
	)
	(segment
		(start 126.071884 -42.822622)
		(end 125.767084 -42.822622)
		(width 0.1524)
		(layer "In4.Cu")
		(net "M_A_DQ9")
	)
	(segment
		(start 183.6674 -64.3382)
		(end 183.6674 -63.07836)
		(width 0.1524)
		(layer "In4.Cu")
		(net "M_A_DQ9")
	)
	(segment
		(start 129.881884 -42.545)
		(end 129.881884 -42.670222)
		(width 0.1524)
		(layer "In4.Cu")
		(net "M_A_DQ9")
	)
	(segment
		(start 130.034284 -42.3926)
		(end 129.881884 -42.545)
		(width 0.1524)
		(layer "In4.Cu")
		(net "M_A_DQ9")
	)
	(segment
		(start 137.197084 -42.670222)
		(end 137.044684 -42.822622)
		(width 0.1524)
		(layer "In4.Cu")
		(net "M_A_DQ9")
	)
	(segment
		(start 125.614684 -42.545)
		(end 125.462284 -42.3926)
		(width 0.1524)
		(layer "In4.Cu")
		(net "M_A_DQ9")
	)
	(segment
		(start 133.996684 -42.3926)
		(end 133.691884 -42.3926)
		(width 0.1524)
		(layer "In4.Cu")
		(net "M_A_DQ9")
	)
	(segment
		(start 126.986284 -42.822622)
		(end 126.833884 -42.670222)
		(width 0.1524)
		(layer "In4.Cu")
		(net "M_A_DQ9")
	)
	(segment
		(start 130.948684 -42.822622)
		(end 130.643884 -42.822622)
		(width 0.1524)
		(layer "In4.Cu")
		(net "M_A_DQ9")
	)
	(segment
		(start 136.130284 -42.3926)
		(end 135.977884 -42.545)
		(width 0.1524)
		(layer "In4.Cu")
		(net "M_A_DQ9")
	)
	(segment
		(start 131.101084 -42.670222)
		(end 130.948684 -42.822622)
		(width 0.1524)
		(layer "In4.Cu")
		(net "M_A_DQ9")
	)
	(segment
		(start 128.815084 -42.3926)
		(end 128.662684 -42.545)
		(width 0.1524)
		(layer "In4.Cu")
		(net "M_A_DQ9")
	)
	(segment
		(start 123.785884 -42.670222)
		(end 123.633484 -42.822622)
		(width 0.1524)
		(layer "In4.Cu")
		(net "M_A_DQ9")
	)
	(segment
		(start 134.758684 -42.670222)
		(end 134.606284 -42.822622)
		(width 0.1524)
		(layer "In4.Cu")
		(net "M_A_DQ9")
	)
	(segment
		(start 136.587484 -42.670222)
		(end 136.587484 -42.545)
		(width 0.1524)
		(layer "In4.Cu")
		(net "M_A_DQ9")
	)
	(segment
		(start 118.1608 -41.6052)
		(end 112.3188 -41.6052)
		(width 0.1524)
		(layer "In4.Cu")
		(net "M_A_DQ9")
	)
	(segment
		(start 137.959084 -42.822622)
		(end 137.806684 -42.670222)
		(width 0.1524)
		(layer "In4.Cu")
		(net "M_A_DQ9")
	)
	(segment
		(start 126.224284 -42.670222)
		(end 126.071884 -42.822622)
		(width 0.1524)
		(layer "In4.Cu")
		(net "M_A_DQ9")
	)
	(segment
		(start 107.112054 -42.925746)
		(end 107.467654 -42.925746)
		(width 0.1016)
		(layer "In4.Cu")
		(net "M_A_DQ9")
	)
	(segment
		(start 108.839 -42.14368)
		(end 109.13872 -42.4434)
		(width 0.1016)
		(layer "In4.Cu")
		(net "M_A_DQ9")
	)
	(segment
		(start 129.729484 -42.822622)
		(end 129.424684 -42.822622)
		(width 0.1524)
		(layer "In4.Cu")
		(net "M_A_DQ9")
	)
	(segment
		(start 123.633484 -42.822622)
		(end 123.328684 -42.822622)
		(width 0.1524)
		(layer "In4.Cu")
		(net "M_A_DQ9")
	)
	(segment
		(start 183.4134 -61.491114)
		(end 180.9496 -59.027314)
		(width 0.1524)
		(layer "In4.Cu")
		(net "M_A_DQ9")
	)
	(segment
		(start 106.541062 -43.989498)
		(end 106.88066 -43.6499)
		(width 0.1016)
		(layer "In4.Cu")
		(net "M_A_DQ9")
	)
	(segment
		(start 124.395484 -42.545)
		(end 124.243084 -42.3926)
		(width 0.1524)
		(layer "In4.Cu")
		(net "M_A_DQ9")
	)
	(segment
		(start 110.236 -42.1894)
		(end 111.506 -42.1894)
		(width 0.1016)
		(layer "In4.Cu")
		(net "M_A_DQ9")
	)
	(segment
		(start 130.339084 -42.3926)
		(end 130.034284 -42.3926)
		(width 0.1524)
		(layer "In4.Cu")
		(net "M_A_DQ9")
	)
	(segment
		(start 137.806684 -42.670222)
		(end 137.806684 -42.545)
		(width 0.1524)
		(layer "In4.Cu")
		(net "M_A_DQ9")
	)
	(segment
		(start 128.053084 -42.670222)
		(end 128.053084 -42.545)
		(width 0.1524)
		(layer "In4.Cu")
		(net "M_A_DQ9")
	)
	(segment
		(start 127.900684 -42.3926)
		(end 127.595884 -42.3926)
		(width 0.1524)
		(layer "In4.Cu")
		(net "M_A_DQ9")
	)
	(segment
		(start 128.205484 -42.822622)
		(end 128.053084 -42.670222)
		(width 0.1524)
		(layer "In4.Cu")
		(net "M_A_DQ9")
	)
	(segment
		(start 165.5064 -45.4406)
		(end 156.166312 -42.9006)
		(width 0.1524)
		(layer "In4.Cu")
		(net "M_A_DQ9")
	)
	(segment
		(start 124.547884 -42.822622)
		(end 124.395484 -42.670222)
		(width 0.1524)
		(layer "In4.Cu")
		(net "M_A_DQ9")
	)
	(segment
		(start 109.725206 -42.69994)
		(end 109.752384 -42.673016)
		(width 0.1016)
		(layer "In4.Cu")
		(net "M_A_DQ9")
	)
	(segment
		(start 97.282 -29.674566)
		(end 97.605088 -29.997654)
		(width 0.1016)
		(layer "F.Cu")
		(net "M_B_DQ29")
	)
	(segment
		(start 97.0026 -28.702)
		(end 97.282 -28.9814)
		(width 0.1016)
		(layer "F.Cu")
		(net "M_B_DQ29")
	)
	(segment
		(start 97.282 -28.9814)
		(end 97.282 -29.674566)
		(width 0.1016)
		(layer "F.Cu")
		(net "M_B_DQ29")
	)
	(segment
		(start 144.9578 -3.379978)
		(end 145.1864 -3.608578)
		(width 0.1778)
		(layer "F.Cu")
		(net "M_B_DQ29")
	)
	(segment
		(start 145.149824 -1.68402)
		(end 145.149824 -2.679954)
		(width 0.1778)
		(layer "F.Cu")
		(net "M_B_DQ29")
	)
	(segment
		(start 145.149824 -2.679954)
		(end 144.9578 -2.871978)
		(width 0.1778)
		(layer "F.Cu")
		(net "M_B_DQ29")
	)
	(segment
		(start 144.9578 -2.871978)
		(end 144.9578 -3.379978)
		(width 0.1778)
		(layer "F.Cu")
		(net "M_B_DQ29")
	)
	(via
		(at 97.0026 -28.702)
		(size 0.4318)
		(drill 0.2032)
		(layers "F.Cu" "B.Cu")
		(net "M_B_DQ29")
	)
	(via
		(at 145.1864 -3.608578)
		(size 0.4318)
		(drill 0.2032)
		(layers "F.Cu" "B.Cu")
		(net "M_B_DQ29")
	)
	(segment
		(start 144.84985 -1.690624)
		(end 144.84985 -3.272028)
		(width 0.1778)
		(layer "B.Cu")
		(net "M_B_DQ29")
	)
	(segment
		(start 144.84985 -3.272028)
		(end 145.1864 -3.608578)
		(width 0.1778)
		(layer "B.Cu")
		(net "M_B_DQ29")
	)
	(segment
		(start 97.632012 -27.640788)
		(end 97.632012 -28.072588)
		(width 0.1016)
		(layer "In4.Cu")
		(net "M_B_DQ29")
	)
	(segment
		(start 103.9368 -21.5646)
		(end 103.9368 -23.0378)
		(width 0.1524)
		(layer "In4.Cu")
		(net "M_B_DQ29")
	)
	(segment
		(start 121.2342 -17.7546)
		(end 121.0818 -17.6022)
		(width 0.1524)
		(layer "In4.Cu")
		(net "M_B_DQ29")
	)
	(segment
		(start 138.0998 -18.2626)
		(end 138.0998 -17.6784)
		(width 0.1524)
		(layer "In4.Cu")
		(net "M_B_DQ29")
	)
	(segment
		(start 98.8314 -26.4414)
		(end 97.632012 -27.640788)
		(width 0.1016)
		(layer "In4.Cu")
		(net "M_B_DQ29")
	)
	(segment
		(start 145.1864 -3.608578)
		(end 144.99717 -3.797808)
		(width 0.1524)
		(layer "In4.Cu")
		(net "M_B_DQ29")
	)
	(segment
		(start 138.6332 -18.796)
		(end 138.0998 -18.2626)
		(width 0.1524)
		(layer "In4.Cu")
		(net "M_B_DQ29")
	)
	(segment
		(start 121.2342 -18.6436)
		(end 121.2342 -17.7546)
		(width 0.1524)
		(layer "In4.Cu")
		(net "M_B_DQ29")
	)
	(segment
		(start 144.145254 -18.129758)
		(end 143.479012 -18.796)
		(width 0.1524)
		(layer "In4.Cu")
		(net "M_B_DQ29")
	)
	(segment
		(start 114.04219 -18.796)
		(end 111.57839 -21.2598)
		(width 0.1524)
		(layer "In4.Cu")
		(net "M_B_DQ29")
	)
	(segment
		(start 144.99717 -6.464808)
		(end 144.30248 -7.159498)
		(width 0.1524)
		(layer "In4.Cu")
		(net "M_B_DQ29")
	)
	(segment
		(start 121.9708 -17.526)
		(end 121.8184 -17.6784)
		(width 0.1524)
		(layer "In4.Cu")
		(net "M_B_DQ29")
	)
	(segment
		(start 137.9474 -17.526)
		(end 121.9708 -17.526)
		(width 0.1524)
		(layer "In4.Cu")
		(net "M_B_DQ29")
	)
	(segment
		(start 121.666 -18.796)
		(end 121.3866 -18.796)
		(width 0.1524)
		(layer "In4.Cu")
		(net "M_B_DQ29")
	)
	(segment
		(start 103.9368 -23.0378)
		(end 103.9368 -24.3078)
		(width 0.1016)
		(layer "In4.Cu")
		(net "M_B_DQ29")
	)
	(segment
		(start 120.6246 -17.7546)
		(end 120.6246 -18.6436)
		(width 0.1524)
		(layer "In4.Cu")
		(net "M_B_DQ29")
	)
	(segment
		(start 104.2416 -21.2598)
		(end 103.9368 -21.5646)
		(width 0.1524)
		(layer "In4.Cu")
		(net "M_B_DQ29")
	)
	(segment
		(start 143.479012 -18.796)
		(end 138.6332 -18.796)
		(width 0.1524)
		(layer "In4.Cu")
		(net "M_B_DQ29")
	)
	(segment
		(start 103.9368 -24.3078)
		(end 102.3874 -25.8572)
		(width 0.1016)
		(layer "In4.Cu")
		(net "M_B_DQ29")
	)
	(segment
		(start 120.4722 -18.796)
		(end 114.04219 -18.796)
		(width 0.1524)
		(layer "In4.Cu")
		(net "M_B_DQ29")
	)
	(segment
		(start 120.6246 -18.6436)
		(end 120.4722 -18.796)
		(width 0.1524)
		(layer "In4.Cu")
		(net "M_B_DQ29")
	)
	(segment
		(start 111.57839 -21.2598)
		(end 104.2416 -21.2598)
		(width 0.1524)
		(layer "In4.Cu")
		(net "M_B_DQ29")
	)
	(segment
		(start 144.99717 -3.797808)
		(end 144.99717 -6.464808)
		(width 0.1524)
		(layer "In4.Cu")
		(net "M_B_DQ29")
	)
	(segment
		(start 144.30248 -10.78484)
		(end 144.145254 -10.942066)
		(width 0.1524)
		(layer "In4.Cu")
		(net "M_B_DQ29")
	)
	(segment
		(start 100.297996 -25.8572)
		(end 99.713796 -26.4414)
		(width 0.1016)
		(layer "In4.Cu")
		(net "M_B_DQ29")
	)
	(segment
		(start 121.3866 -18.796)
		(end 121.2342 -18.6436)
		(width 0.1524)
		(layer "In4.Cu")
		(net "M_B_DQ29")
	)
	(segment
		(start 138.0998 -17.6784)
		(end 137.9474 -17.526)
		(width 0.1524)
		(layer "In4.Cu")
		(net "M_B_DQ29")
	)
	(segment
		(start 99.713796 -26.4414)
		(end 98.8314 -26.4414)
		(width 0.1016)
		(layer "In4.Cu")
		(net "M_B_DQ29")
	)
	(segment
		(start 121.8184 -18.6436)
		(end 121.666 -18.796)
		(width 0.1524)
		(layer "In4.Cu")
		(net "M_B_DQ29")
	)
	(segment
		(start 144.30248 -7.159498)
		(end 144.30248 -10.78484)
		(width 0.1524)
		(layer "In4.Cu")
		(net "M_B_DQ29")
	)
	(segment
		(start 97.632012 -28.072588)
		(end 97.0026 -28.702)
		(width 0.1016)
		(layer "In4.Cu")
		(net "M_B_DQ29")
	)
	(segment
		(start 144.145254 -10.942066)
		(end 144.145254 -18.129758)
		(width 0.1524)
		(layer "In4.Cu")
		(net "M_B_DQ29")
	)
	(segment
		(start 102.3874 -25.8572)
		(end 100.297996 -25.8572)
		(width 0.1016)
		(layer "In4.Cu")
		(net "M_B_DQ29")
	)
	(segment
		(start 121.0818 -17.6022)
		(end 120.777 -17.6022)
		(width 0.1524)
		(layer "In4.Cu")
		(net "M_B_DQ29")
	)
	(segment
		(start 121.8184 -17.6784)
		(end 121.8184 -18.6436)
		(width 0.1524)
		(layer "In4.Cu")
		(net "M_B_DQ29")
	)
	(segment
		(start 120.777 -17.6022)
		(end 120.6246 -17.7546)
		(width 0.1524)
		(layer "In4.Cu")
		(net "M_B_DQ29")
	)
	(segment
		(start 111.148368 -49.517554)
		(end 111.148368 -49.802796)
		(width 0.1016)
		(layer "F.Cu")
		(net "M_A_CKE3")
	)
	(segment
		(start 111.148368 -49.802796)
		(end 111.440468 -50.094896)
		(width 0.1016)
		(layer "F.Cu")
		(net "M_A_CKE3")
	)
	(segment
		(start 161.349944 -70.806564)
		(end 161.349944 -69.126608)
		(width 0.1778)
		(layer "F.Cu")
		(net "M_A_CKE3")
	)
	(segment
		(start 161.349944 -69.126608)
		(end 161.871152 -68.6054)
		(width 0.1778)
		(layer "F.Cu")
		(net "M_A_CKE3")
	)
	(via
		(at 161.871152 -68.6054)
		(size 0.4318)
		(drill 0.2032)
		(layers "F.Cu" "B.Cu")
		(net "M_A_CKE3")
	)
	(via
		(at 111.440468 -50.094896)
		(size 0.4318)
		(drill 0.2032)
		(layers "F.Cu" "B.Cu")
		(net "M_A_CKE3")
	)
	(segment
		(start 159.7152 -61.57341)
		(end 159.3342 -61.57341)
		(width 0.1524)
		(layer "In7.Cu")
		(net "M_A_CKE3")
	)
	(segment
		(start 159.1818 -60.20181)
		(end 159.1818 -59.89701)
		(width 0.1524)
		(layer "In7.Cu")
		(net "M_A_CKE3")
	)
	(segment
		(start 159.8676 -63.24981)
		(end 159.8676 -62.94501)
		(width 0.1524)
		(layer "In7.Cu")
		(net "M_A_CKE3")
	)
	(segment
		(start 159.3342 -60.96381)
		(end 159.7152 -60.96381)
		(width 0.1524)
		(layer "In7.Cu")
		(net "M_A_CKE3")
	)
	(segment
		(start 159.8676 -59.28741)
		(end 159.7152 -59.13501)
		(width 0.1524)
		(layer "In7.Cu")
		(net "M_A_CKE3")
	)
	(segment
		(start 162.4076 -67.8434)
		(end 163.068 -67.183)
		(width 0.1524)
		(layer "In7.Cu")
		(net "M_A_CKE3")
	)
	(segment
		(start 157.983936 -56.341772)
		(end 157.077664 -55.4355)
		(width 0.1524)
		(layer "In7.Cu")
		(net "M_A_CKE3")
	)
	(segment
		(start 116.967 -50.4952)
		(end 111.840772 -50.4952)
		(width 0.1524)
		(layer "In7.Cu")
		(net "M_A_CKE3")
	)
	(segment
		(start 153.971244 -52.378102)
		(end 153.70048 -52.378102)
		(width 0.1524)
		(layer "In7.Cu")
		(net "M_A_CKE3")
	)
	(segment
		(start 159.3342 -62.18301)
		(end 159.7152 -62.18301)
		(width 0.1524)
		(layer "In7.Cu")
		(net "M_A_CKE3")
	)
	(segment
		(start 159.8676 -61.72581)
		(end 159.7152 -61.57341)
		(width 0.1524)
		(layer "In7.Cu")
		(net "M_A_CKE3")
	)
	(segment
		(start 162.56 -65.5574)
		(end 160.5534 -65.5574)
		(width 0.1524)
		(layer "In7.Cu")
		(net "M_A_CKE3")
	)
	(segment
		(start 159.8676 -60.81141)
		(end 159.8676 -60.50661)
		(width 0.1524)
		(layer "In7.Cu")
		(net "M_A_CKE3")
	)
	(segment
		(start 151.935942 -52.145184)
		(end 149.416008 -49.62525)
		(width 0.1524)
		(layer "In7.Cu")
		(net "M_A_CKE3")
	)
	(segment
		(start 159.1818 -62.64021)
		(end 159.1818 -62.33541)
		(width 0.1524)
		(layer "In7.Cu")
		(net "M_A_CKE3")
	)
	(segment
		(start 143.962374 -49.62525)
		(end 143.428974 -49.09185)
		(width 0.1524)
		(layer "In7.Cu")
		(net "M_A_CKE3")
	)
	(segment
		(start 159.1818 -61.11621)
		(end 159.3342 -60.96381)
		(width 0.1524)
		(layer "In7.Cu")
		(net "M_A_CKE3")
	)
	(segment
		(start 159.8676 -64.16421)
		(end 159.7152 -64.01181)
		(width 0.1524)
		(layer "In7.Cu")
		(net "M_A_CKE3")
	)
	(segment
		(start 161.871152 -68.6054)
		(end 161.871152 -68.168012)
		(width 0.1524)
		(layer "In7.Cu")
		(net "M_A_CKE3")
	)
	(segment
		(start 159.8676 -64.8716)
		(end 159.8676 -64.16421)
		(width 0.1524)
		(layer "In7.Cu")
		(net "M_A_CKE3")
	)
	(segment
		(start 159.8676 -60.50661)
		(end 159.7152 -60.35421)
		(width 0.1524)
		(layer "In7.Cu")
		(net "M_A_CKE3")
	)
	(segment
		(start 159.7152 -63.40221)
		(end 159.8676 -63.24981)
		(width 0.1524)
		(layer "In7.Cu")
		(net "M_A_CKE3")
	)
	(segment
		(start 159.7152 -59.13501)
		(end 159.3342 -59.13501)
		(width 0.1524)
		(layer "In7.Cu")
		(net "M_A_CKE3")
	)
	(segment
		(start 159.3342 -61.57341)
		(end 159.1818 -61.42101)
		(width 0.1524)
		(layer "In7.Cu")
		(net "M_A_CKE3")
	)
	(segment
		(start 159.8676 -62.03061)
		(end 159.8676 -61.72581)
		(width 0.1524)
		(layer "In7.Cu")
		(net "M_A_CKE3")
	)
	(segment
		(start 159.1818 -58.98261)
		(end 159.1818 -57.859422)
		(width 0.1524)
		(layer "In7.Cu")
		(net "M_A_CKE3")
	)
	(segment
		(start 159.3342 -59.74461)
		(end 159.7152 -59.74461)
		(width 0.1524)
		(layer "In7.Cu")
		(net "M_A_CKE3")
	)
	(segment
		(start 159.1818 -62.33541)
		(end 159.3342 -62.18301)
		(width 0.1524)
		(layer "In7.Cu")
		(net "M_A_CKE3")
	)
	(segment
		(start 153.467562 -52.145184)
		(end 151.935942 -52.145184)
		(width 0.1524)
		(layer "In7.Cu")
		(net "M_A_CKE3")
	)
	(segment
		(start 159.3342 -62.79261)
		(end 159.1818 -62.64021)
		(width 0.1524)
		(layer "In7.Cu")
		(net "M_A_CKE3")
	)
	(segment
		(start 155.630118 -54.30774)
		(end 154.926538 -53.60416)
		(width 0.1524)
		(layer "In7.Cu")
		(net "M_A_CKE3")
	)
	(segment
		(start 159.1818 -63.85941)
		(end 159.1818 -63.55461)
		(width 0.1524)
		(layer "In7.Cu")
		(net "M_A_CKE3")
	)
	(segment
		(start 143.428974 -49.09185)
		(end 118.37035 -49.09185)
		(width 0.1524)
		(layer "In7.Cu")
		(net "M_A_CKE3")
	)
	(segment
		(start 160.5534 -65.5574)
		(end 159.8676 -64.8716)
		(width 0.1524)
		(layer "In7.Cu")
		(net "M_A_CKE3")
	)
	(segment
		(start 155.94965 -54.30774)
		(end 155.630118 -54.30774)
		(width 0.1524)
		(layer "In7.Cu")
		(net "M_A_CKE3")
	)
	(segment
		(start 149.416008 -49.62525)
		(end 143.962374 -49.62525)
		(width 0.1524)
		(layer "In7.Cu")
		(net "M_A_CKE3")
	)
	(segment
		(start 163.068 -67.183)
		(end 163.068 -66.0654)
		(width 0.1524)
		(layer "In7.Cu")
		(net "M_A_CKE3")
	)
	(segment
		(start 159.8676 -59.59221)
		(end 159.8676 -59.28741)
		(width 0.1524)
		(layer "In7.Cu")
		(net "M_A_CKE3")
	)
	(segment
		(start 159.3342 -64.01181)
		(end 159.1818 -63.85941)
		(width 0.1524)
		(layer "In7.Cu")
		(net "M_A_CKE3")
	)
	(segment
		(start 159.8676 -62.94501)
		(end 159.7152 -62.79261)
		(width 0.1524)
		(layer "In7.Cu")
		(net "M_A_CKE3")
	)
	(segment
		(start 162.195764 -67.8434)
		(end 162.4076 -67.8434)
		(width 0.1524)
		(layer "In7.Cu")
		(net "M_A_CKE3")
	)
	(segment
		(start 159.3342 -63.40221)
		(end 159.7152 -63.40221)
		(width 0.1524)
		(layer "In7.Cu")
		(net "M_A_CKE3")
	)
	(segment
		(start 159.7152 -60.96381)
		(end 159.8676 -60.81141)
		(width 0.1524)
		(layer "In7.Cu")
		(net "M_A_CKE3")
	)
	(segment
		(start 163.068 -66.0654)
		(end 162.56 -65.5574)
		(width 0.1524)
		(layer "In7.Cu")
		(net "M_A_CKE3")
	)
	(segment
		(start 159.1818 -57.859422)
		(end 157.983936 -56.661558)
		(width 0.1524)
		(layer "In7.Cu")
		(net "M_A_CKE3")
	)
	(segment
		(start 111.840772 -50.4952)
		(end 111.440468 -50.094896)
		(width 0.1524)
		(layer "In7.Cu")
		(net "M_A_CKE3")
	)
	(segment
		(start 159.7152 -64.01181)
		(end 159.3342 -64.01181)
		(width 0.1524)
		(layer "In7.Cu")
		(net "M_A_CKE3")
	)
	(segment
		(start 157.077664 -55.4355)
		(end 157.07741 -55.4355)
		(width 0.1524)
		(layer "In7.Cu")
		(net "M_A_CKE3")
	)
	(segment
		(start 161.871152 -68.168012)
		(end 162.195764 -67.8434)
		(width 0.1524)
		(layer "In7.Cu")
		(net "M_A_CKE3")
	)
	(segment
		(start 159.7152 -60.35421)
		(end 159.3342 -60.35421)
		(width 0.1524)
		(layer "In7.Cu")
		(net "M_A_CKE3")
	)
	(segment
		(start 157.07741 -55.4355)
		(end 155.94965 -54.30774)
		(width 0.1524)
		(layer "In7.Cu")
		(net "M_A_CKE3")
	)
	(segment
		(start 154.926538 -53.333396)
		(end 153.971244 -52.378102)
		(width 0.1524)
		(layer "In7.Cu")
		(net "M_A_CKE3")
	)
	(segment
		(start 159.7152 -62.79261)
		(end 159.3342 -62.79261)
		(width 0.1524)
		(layer "In7.Cu")
		(net "M_A_CKE3")
	)
	(segment
		(start 154.926538 -53.60416)
		(end 154.926538 -53.333396)
		(width 0.1524)
		(layer "In7.Cu")
		(net "M_A_CKE3")
	)
	(segment
		(start 159.1818 -59.89701)
		(end 159.3342 -59.74461)
		(width 0.1524)
		(layer "In7.Cu")
		(net "M_A_CKE3")
	)
	(segment
		(start 159.7152 -62.18301)
		(end 159.8676 -62.03061)
		(width 0.1524)
		(layer "In7.Cu")
		(net "M_A_CKE3")
	)
	(segment
		(start 159.1818 -61.42101)
		(end 159.1818 -61.11621)
		(width 0.1524)
		(layer "In7.Cu")
		(net "M_A_CKE3")
	)
	(segment
		(start 153.70048 -52.378102)
		(end 153.467562 -52.145184)
		(width 0.1524)
		(layer "In7.Cu")
		(net "M_A_CKE3")
	)
	(segment
		(start 159.3342 -59.13501)
		(end 159.1818 -58.98261)
		(width 0.1524)
		(layer "In7.Cu")
		(net "M_A_CKE3")
	)
	(segment
		(start 157.983936 -56.661558)
		(end 157.983936 -56.341772)
		(width 0.1524)
		(layer "In7.Cu")
		(net "M_A_CKE3")
	)
	(segment
		(start 118.37035 -49.09185)
		(end 116.967 -50.4952)
		(width 0.1524)
		(layer "In7.Cu")
		(net "M_A_CKE3")
	)
	(segment
		(start 159.3342 -60.35421)
		(end 159.1818 -60.20181)
		(width 0.1524)
		(layer "In7.Cu")
		(net "M_A_CKE3")
	)
	(segment
		(start 159.7152 -59.74461)
		(end 159.8676 -59.59221)
		(width 0.1524)
		(layer "In7.Cu")
		(net "M_A_CKE3")
	)
	(segment
		(start 159.1818 -63.55461)
		(end 159.3342 -63.40221)
		(width 0.1524)
		(layer "In7.Cu")
		(net "M_A_CKE3")
	)
	(segment
		(start 99.911154 -29.17444)
		(end 99.911154 -29.237178)
		(width 0.1016)
		(layer "F.Cu")
		(net "M_B_MA14")
	)
	(segment
		(start 157.387036 -7.35711)
		(end 157.232858 -7.35711)
		(width 0.2413)
		(layer "F.Cu")
		(net "M_B_MA14")
	)
	(segment
		(start 99.591368 -28.854654)
		(end 99.911154 -29.17444)
		(width 0.1016)
		(layer "F.Cu")
		(net "M_B_MA14")
	)
	(segment
		(start 157.232858 -7.35711)
		(end 156.529278 -6.65353)
		(width 0.2413)
		(layer "F.Cu")
		(net "M_B_MA14")
	)
	(segment
		(start 156.529278 -6.402324)
		(end 156.440378 -6.313424)
		(width 0.2413)
		(layer "F.Cu")
		(net "M_B_MA14")
	)
	(segment
		(start 157.67685 -8.653018)
		(end 157.67685 -7.646924)
		(width 0.2413)
		(layer "F.Cu")
		(net "M_B_MA14")
	)
	(segment
		(start 157.450028 -9.897364)
		(end 157.450028 -8.87984)
		(width 0.2413)
		(layer "F.Cu")
		(net "M_B_MA14")
	)
	(segment
		(start 156.529278 -6.65353)
		(end 156.529278 -6.402324)
		(width 0.2413)
		(layer "F.Cu")
		(net "M_B_MA14")
	)
	(segment
		(start 157.67685 -7.646924)
		(end 157.387036 -7.35711)
		(width 0.2413)
		(layer "F.Cu")
		(net "M_B_MA14")
	)
	(segment
		(start 157.450028 -8.87984)
		(end 157.67685 -8.653018)
		(width 0.2413)
		(layer "F.Cu")
		(net "M_B_MA14")
	)
	(via
		(at 156.440378 -6.313424)
		(size 0.4318)
		(drill 0.2032)
		(layers "F.Cu" "B.Cu")
		(net "M_B_MA14")
	)
	(via
		(at 99.911154 -29.237178)
		(size 0.4318)
		(drill 0.2032)
		(layers "F.Cu" "B.Cu")
		(net "M_B_MA14")
	)
	(segment
		(start 157.450028 -1.690624)
		(end 157.450028 -4.30149)
		(width 0.2413)
		(layer "B.Cu")
		(net "M_B_MA14")
	)
	(segment
		(start 156.916628 -5.926582)
		(end 156.529786 -6.313424)
		(width 0.2413)
		(layer "B.Cu")
		(net "M_B_MA14")
	)
	(segment
		(start 157.450028 -4.30149)
		(end 156.916628 -4.83489)
		(width 0.2413)
		(layer "B.Cu")
		(net "M_B_MA14")
	)
	(segment
		(start 156.529786 -6.313424)
		(end 156.440378 -6.313424)
		(width 0.2413)
		(layer "B.Cu")
		(net "M_B_MA14")
	)
	(segment
		(start 156.916628 -4.83489)
		(end 156.916628 -5.926582)
		(width 0.2413)
		(layer "B.Cu")
		(net "M_B_MA14")
	)
	(segment
		(start 153.40584 -7.301738)
		(end 153.40584 -9.91616)
		(width 0.1905)
		(layer "In7.Cu")
		(net "M_B_MA14")
	)
	(segment
		(start 114.42827 -15.68704)
		(end 109.66831 -20.447)
		(width 0.1905)
		(layer "In7.Cu")
		(net "M_B_MA14")
	)
	(segment
		(start 100.4824 -25.9334)
		(end 99.6188 -26.797)
		(width 0.1016)
		(layer "In7.Cu")
		(net "M_B_MA14")
	)
	(segment
		(start 146.05 -12.7)
		(end 136.3853 -12.7)
		(width 0.1905)
		(layer "In7.Cu")
		(net "M_B_MA14")
	)
	(segment
		(start 156.300932 -6.173978)
		(end 154.5336 -6.173978)
		(width 0.1905)
		(layer "In7.Cu")
		(net "M_B_MA14")
	)
	(segment
		(start 109.66831 -20.447)
		(end 101.9048 -20.447)
		(width 0.1905)
		(layer "In7.Cu")
		(net "M_B_MA14")
	)
	(segment
		(start 146.2532 -15.125446)
		(end 146.2532 -12.9032)
		(width 0.1905)
		(layer "In7.Cu")
		(net "M_B_MA14")
	)
	(segment
		(start 156.440378 -6.313424)
		(end 156.300932 -6.173978)
		(width 0.1905)
		(layer "In7.Cu")
		(net "M_B_MA14")
	)
	(segment
		(start 99.6188 -26.797)
		(end 99.6188 -28.944824)
		(width 0.1016)
		(layer "In7.Cu")
		(net "M_B_MA14")
	)
	(segment
		(start 153.40584 -9.91616)
		(end 147.993354 -15.328646)
		(width 0.1905)
		(layer "In7.Cu")
		(net "M_B_MA14")
	)
	(segment
		(start 114.42827 -15.686786)
		(end 114.42827 -15.68704)
		(width 0.1905)
		(layer "In7.Cu")
		(net "M_B_MA14")
	)
	(segment
		(start 147.993354 -15.328646)
		(end 146.4564 -15.328646)
		(width 0.1905)
		(layer "In7.Cu")
		(net "M_B_MA14")
	)
	(segment
		(start 136.3853 -12.7)
		(end 136.1821 -12.9032)
		(width 0.1905)
		(layer "In7.Cu")
		(net "M_B_MA14")
	)
	(segment
		(start 136.0297 -15.32255)
		(end 114.792506 -15.32255)
		(width 0.1905)
		(layer "In7.Cu")
		(net "M_B_MA14")
	)
	(segment
		(start 136.1821 -15.17015)
		(end 136.0297 -15.32255)
		(width 0.1905)
		(layer "In7.Cu")
		(net "M_B_MA14")
	)
	(segment
		(start 154.5336 -6.173978)
		(end 153.40584 -7.301738)
		(width 0.1905)
		(layer "In7.Cu")
		(net "M_B_MA14")
	)
	(segment
		(start 100.4824 -21.8694)
		(end 100.4824 -25.9334)
		(width 0.1016)
		(layer "In7.Cu")
		(net "M_B_MA14")
	)
	(segment
		(start 136.1821 -12.9032)
		(end 136.1821 -15.17015)
		(width 0.1905)
		(layer "In7.Cu")
		(net "M_B_MA14")
	)
	(segment
		(start 99.6188 -28.944824)
		(end 99.911154 -29.237178)
		(width 0.1016)
		(layer "In7.Cu")
		(net "M_B_MA14")
	)
	(segment
		(start 101.9048 -20.447)
		(end 100.4824 -21.8694)
		(width 0.1016)
		(layer "In7.Cu")
		(net "M_B_MA14")
	)
	(segment
		(start 146.2532 -12.9032)
		(end 146.05 -12.7)
		(width 0.1905)
		(layer "In7.Cu")
		(net "M_B_MA14")
	)
	(segment
		(start 146.4564 -15.328646)
		(end 146.2532 -15.125446)
		(width 0.1905)
		(layer "In7.Cu")
		(net "M_B_MA14")
	)
	(segment
		(start 114.792506 -15.32255)
		(end 114.42827 -15.686786)
		(width 0.1905)
		(layer "In7.Cu")
		(net "M_B_MA14")
	)
	(segment
		(start 119.2784 -46.609)
		(end 114.282982 -46.609)
		(width 0.1016)
		(layer "F.Cu")
		(net "M_A_DQ27")
	)
	(segment
		(start 114.282982 -46.609)
		(end 111.430816 -43.756834)
		(width 0.1016)
		(layer "F.Cu")
		(net "M_A_DQ27")
	)
	(segment
		(start 170.049952 -62.59322)
		(end 170.049952 -63.319152)
		(width 0.1778)
		(layer "F.Cu")
		(net "M_A_DQ27")
	)
	(segment
		(start 170.049952 -63.319152)
		(end 170.59402 -63.86322)
		(width 0.1778)
		(layer "F.Cu")
		(net "M_A_DQ27")
	)
	(segment
		(start 170.59402 -64.33058)
		(end 170.2308 -64.6938)
		(width 0.1778)
		(layer "F.Cu")
		(net "M_A_DQ27")
	)
	(segment
		(start 111.430816 -43.756834)
		(end 111.153448 -43.756834)
		(width 0.1016)
		(layer "F.Cu")
		(net "M_A_DQ27")
	)
	(segment
		(start 170.59402 -63.86322)
		(end 170.59402 -64.33058)
		(width 0.1778)
		(layer "F.Cu")
		(net "M_A_DQ27")
	)
	(segment
		(start 119.7102 -46.1772)
		(end 119.2784 -46.609)
		(width 0.1016)
		(layer "F.Cu")
		(net "M_A_DQ27")
	)
	(via
		(at 119.7102 -46.1772)
		(size 0.4318)
		(drill 0.2032)
		(layers "F.Cu" "B.Cu")
		(net "M_A_DQ27")
	)
	(via
		(at 170.2308 -64.6938)
		(size 0.4318)
		(drill 0.2032)
		(layers "F.Cu" "B.Cu")
		(net "M_A_DQ27")
	)
	(segment
		(start 170.950128 -63.397892)
		(end 170.59402 -63.754)
		(width 0.1778)
		(layer "B.Cu")
		(net "M_A_DQ27")
	)
	(segment
		(start 170.59402 -63.754)
		(end 170.59402 -64.33058)
		(width 0.1778)
		(layer "B.Cu")
		(net "M_A_DQ27")
	)
	(segment
		(start 170.59402 -64.33058)
		(end 170.2308 -64.6938)
		(width 0.1778)
		(layer "B.Cu")
		(net "M_A_DQ27")
	)
	(segment
		(start 170.950128 -62.599824)
		(end 170.950128 -63.397892)
		(width 0.1778)
		(layer "B.Cu")
		(net "M_A_DQ27")
	)
	(segment
		(start 164.679122 -54.098952)
		(end 164.679122 -54.314344)
		(width 0.1524)
		(layer "In2.Cu")
		(net "M_A_DQ27")
	)
	(segment
		(start 169.150284 -58.570114)
		(end 169.366184 -58.786014)
		(width 0.1524)
		(layer "In2.Cu")
		(net "M_A_DQ27")
	)
	(segment
		(start 123.983242 -46.3804)
		(end 123.983242 -46.1772)
		(width 0.1524)
		(layer "In2.Cu")
		(net "M_A_DQ27")
	)
	(segment
		(start 166.18839 -55.60822)
		(end 166.778432 -56.198262)
		(width 0.1524)
		(layer "In2.Cu")
		(net "M_A_DQ27")
	)
	(segment
		(start 157.226 -50.4698)
		(end 158.2801 -50.4698)
		(width 0.1524)
		(layer "In2.Cu")
		(net "M_A_DQ27")
	)
	(segment
		(start 164.679122 -54.314344)
		(end 164.532056 -54.461664)
		(width 0.1524)
		(layer "In2.Cu")
		(net "M_A_DQ27")
	)
	(segment
		(start 151.3586 -46.5074)
		(end 151.3586 -47.0662)
		(width 0.1524)
		(layer "In2.Cu")
		(net "M_A_DQ27")
	)
	(segment
		(start 164.463222 -53.883052)
		(end 164.679122 -54.098952)
		(width 0.1524)
		(layer "In2.Cu")
		(net "M_A_DQ27")
	)
	(segment
		(start 167.05326 -57.00141)
		(end 167.209724 -56.844946)
		(width 0.1524)
		(layer "In2.Cu")
		(net "M_A_DQ27")
	)
	(segment
		(start 162.953954 -52.589176)
		(end 162.806888 -52.736496)
		(width 0.1524)
		(layer "In2.Cu")
		(net "M_A_DQ27")
	)
	(segment
		(start 167.425116 -56.844946)
		(end 167.641016 -57.060846)
		(width 0.1524)
		(layer "In2.Cu")
		(net "M_A_DQ27")
	)
	(segment
		(start 125.050042 -46.5328)
		(end 125.202442 -46.3804)
		(width 0.1524)
		(layer "In2.Cu")
		(net "M_A_DQ27")
	)
	(segment
		(start 152.821386 -49.218342)
		(end 153.844244 -50.2412)
		(width 0.1524)
		(layer "In2.Cu")
		(net "M_A_DQ27")
	)
	(segment
		(start 157.0736 -50.3174)
		(end 157.226 -50.4698)
		(width 0.1524)
		(layer "In2.Cu")
		(net "M_A_DQ27")
	)
	(segment
		(start 168.778428 -58.726578)
		(end 168.934892 -58.570114)
		(width 0.1524)
		(layer "In2.Cu")
		(net "M_A_DQ27")
	)
	(segment
		(start 168.347136 -58.295286)
		(end 168.347136 -58.510678)
		(width 0.1524)
		(layer "In2.Cu")
		(net "M_A_DQ27")
	)
	(segment
		(start 125.354842 -46.0248)
		(end 150.876 -46.0248)
		(width 0.1524)
		(layer "In2.Cu")
		(net "M_A_DQ27")
	)
	(segment
		(start 122.306842 -46.5328)
		(end 122.611642 -46.5328)
		(width 0.1524)
		(layer "In2.Cu")
		(net "M_A_DQ27")
	)
	(segment
		(start 156.0576 -49.5808)
		(end 156.9212 -49.5808)
		(width 0.1524)
		(layer "In2.Cu")
		(net "M_A_DQ27")
	)
	(segment
		(start 152.952704 -48.871632)
		(end 152.821386 -49.00295)
		(width 0.1524)
		(layer "In2.Cu")
		(net "M_A_DQ27")
	)
	(segment
		(start 165.39464 -55.53964)
		(end 165.61054 -55.75554)
		(width 0.1524)
		(layer "In2.Cu")
		(net "M_A_DQ27")
	)
	(segment
		(start 165.825678 -55.75554)
		(end 165.972998 -55.60822)
		(width 0.1524)
		(layer "In2.Cu")
		(net "M_A_DQ27")
	)
	(segment
		(start 152.160224 -48.586136)
		(end 152.375616 -48.586136)
		(width 0.1524)
		(layer "In2.Cu")
		(net "M_A_DQ27")
	)
	(segment
		(start 165.39464 -55.324248)
		(end 165.39464 -55.53964)
		(width 0.1524)
		(layer "In2.Cu")
		(net "M_A_DQ27")
	)
	(segment
		(start 168.934892 -58.570114)
		(end 169.150284 -58.570114)
		(width 0.1524)
		(layer "In2.Cu")
		(net "M_A_DQ27")
	)
	(segment
		(start 167.484552 -57.648094)
		(end 167.700452 -57.863994)
		(width 0.1524)
		(layer "In2.Cu")
		(net "M_A_DQ27")
	)
	(segment
		(start 151.944324 -48.370236)
		(end 152.160224 -48.586136)
		(width 0.1524)
		(layer "In2.Cu")
		(net "M_A_DQ27")
	)
	(segment
		(start 122.002042 -46.0248)
		(end 122.154442 -46.1772)
		(width 0.1524)
		(layer "In2.Cu")
		(net "M_A_DQ27")
	)
	(segment
		(start 157.0736 -49.7332)
		(end 157.0736 -50.3174)
		(width 0.1524)
		(layer "In2.Cu")
		(net "M_A_DQ27")
	)
	(segment
		(start 123.983242 -46.1772)
		(end 124.135642 -46.0248)
		(width 0.1524)
		(layer "In2.Cu")
		(net "M_A_DQ27")
	)
	(segment
		(start 162.806888 -52.951888)
		(end 163.022788 -53.167788)
		(width 0.1524)
		(layer "In2.Cu")
		(net "M_A_DQ27")
	)
	(segment
		(start 152.736804 -48.44034)
		(end 152.952704 -48.65624)
		(width 0.1524)
		(layer "In2.Cu")
		(net "M_A_DQ27")
	)
	(segment
		(start 150.876 -46.0248)
		(end 151.3586 -46.5074)
		(width 0.1524)
		(layer "In2.Cu")
		(net "M_A_DQ27")
	)
	(segment
		(start 124.135642 -46.0248)
		(end 124.440442 -46.0248)
		(width 0.1524)
		(layer "In2.Cu")
		(net "M_A_DQ27")
	)
	(segment
		(start 160.1978 -50.9778)
		(end 160.0454 -51.1302)
		(width 0.1524)
		(layer "In2.Cu")
		(net "M_A_DQ27")
	)
	(segment
		(start 168.5036 -58.138822)
		(end 168.347136 -58.295286)
		(width 0.1524)
		(layer "In2.Cu")
		(net "M_A_DQ27")
	)
	(segment
		(start 166.837868 -57.00141)
		(end 167.05326 -57.00141)
		(width 0.1524)
		(layer "In2.Cu")
		(net "M_A_DQ27")
	)
	(segment
		(start 123.830842 -46.5328)
		(end 123.983242 -46.3804)
		(width 0.1524)
		(layer "In2.Cu")
		(net "M_A_DQ27")
	)
	(segment
		(start 169.8244 -62.2808)
		(end 170.58132 -63.03772)
		(width 0.1524)
		(layer "In2.Cu")
		(net "M_A_DQ27")
	)
	(segment
		(start 124.592842 -46.1772)
		(end 124.592842 -46.3804)
		(width 0.1524)
		(layer "In2.Cu")
		(net "M_A_DQ27")
	)
	(segment
		(start 123.526042 -46.5328)
		(end 123.830842 -46.5328)
		(width 0.1524)
		(layer "In2.Cu")
		(net "M_A_DQ27")
	)
	(segment
		(start 163.237926 -53.167788)
		(end 163.385246 -53.020468)
		(width 0.1524)
		(layer "In2.Cu")
		(net "M_A_DQ27")
	)
	(segment
		(start 152.952704 -48.65624)
		(end 152.952704 -48.871632)
		(width 0.1524)
		(layer "In2.Cu")
		(net "M_A_DQ27")
	)
	(segment
		(start 158.5849 -49.8094)
		(end 162.1282 -49.8094)
		(width 0.1524)
		(layer "In2.Cu")
		(net "M_A_DQ27")
	)
	(segment
		(start 151.944324 -48.154844)
		(end 151.944324 -48.370236)
		(width 0.1524)
		(layer "In2.Cu")
		(net "M_A_DQ27")
	)
	(segment
		(start 160.0454 -51.1302)
		(end 160.0454 -51.549808)
		(width 0.1524)
		(layer "In2.Cu")
		(net "M_A_DQ27")
	)
	(segment
		(start 165.110414 -54.745636)
		(end 165.325806 -54.745636)
		(width 0.1524)
		(layer "In2.Cu")
		(net "M_A_DQ27")
	)
	(segment
		(start 165.325806 -54.745636)
		(end 165.541706 -54.961536)
		(width 0.1524)
		(layer "In2.Cu")
		(net "M_A_DQ27")
	)
	(segment
		(start 124.745242 -46.5328)
		(end 125.050042 -46.5328)
		(width 0.1524)
		(layer "In2.Cu")
		(net "M_A_DQ27")
	)
	(segment
		(start 166.621968 -56.570118)
		(end 166.621968 -56.78551)
		(width 0.1524)
		(layer "In2.Cu")
		(net "M_A_DQ27")
	)
	(segment
		(start 151.3586 -47.0662)
		(end 152.088088 -47.795688)
		(width 0.1524)
		(layer "In2.Cu")
		(net "M_A_DQ27")
	)
	(segment
		(start 162.953954 -52.373784)
		(end 162.953954 -52.589176)
		(width 0.1524)
		(layer "In2.Cu")
		(net "M_A_DQ27")
	)
	(segment
		(start 121.5644 -46.1772)
		(end 119.7102 -46.1772)
		(width 0.1016)
		(layer "In2.Cu")
		(net "M_A_DQ27")
	)
	(segment
		(start 169.20972 -59.15787)
		(end 169.20972 -59.373262)
		(width 0.1524)
		(layer "In2.Cu")
		(net "M_A_DQ27")
	)
	(segment
		(start 167.641016 -57.276238)
		(end 167.484552 -57.432702)
		(width 0.1524)
		(layer "In2.Cu")
		(net "M_A_DQ27")
	)
	(segment
		(start 164.532056 -54.461664)
		(end 164.532056 -54.677056)
		(width 0.1524)
		(layer "In2.Cu")
		(net "M_A_DQ27")
	)
	(segment
		(start 163.600638 -53.020468)
		(end 163.816538 -53.236368)
		(width 0.1524)
		(layer "In2.Cu")
		(net "M_A_DQ27")
	)
	(segment
		(start 153.844244 -50.2412)
		(end 155.3972 -50.2412)
		(width 0.1524)
		(layer "In2.Cu")
		(net "M_A_DQ27")
	)
	(segment
		(start 158.4325 -50.3174)
		(end 158.4325 -49.9618)
		(width 0.1524)
		(layer "In2.Cu")
		(net "M_A_DQ27")
	)
	(segment
		(start 122.764042 -46.3804)
		(end 122.764042 -46.1772)
		(width 0.1524)
		(layer "In2.Cu")
		(net "M_A_DQ27")
	)
	(segment
		(start 165.541706 -54.961536)
		(end 165.541706 -55.176928)
		(width 0.1524)
		(layer "In2.Cu")
		(net "M_A_DQ27")
	)
	(segment
		(start 167.209724 -56.844946)
		(end 167.425116 -56.844946)
		(width 0.1524)
		(layer "In2.Cu")
		(net "M_A_DQ27")
	)
	(segment
		(start 166.778432 -56.413654)
		(end 166.621968 -56.570118)
		(width 0.1524)
		(layer "In2.Cu")
		(net "M_A_DQ27")
	)
	(segment
		(start 155.3972 -50.2412)
		(end 156.0576 -49.5808)
		(width 0.1524)
		(layer "In2.Cu")
		(net "M_A_DQ27")
	)
	(segment
		(start 167.641016 -57.060846)
		(end 167.641016 -57.276238)
		(width 0.1524)
		(layer "In2.Cu")
		(net "M_A_DQ27")
	)
	(segment
		(start 168.5036 -57.92343)
		(end 168.5036 -58.138822)
		(width 0.1524)
		(layer "In2.Cu")
		(net "M_A_DQ27")
	)
	(segment
		(start 122.154442 -46.1772)
		(end 122.154442 -46.3804)
		(width 0.1524)
		(layer "In2.Cu")
		(net "M_A_DQ27")
	)
	(segment
		(start 156.9212 -49.5808)
		(end 157.0736 -49.7332)
		(width 0.1524)
		(layer "In2.Cu")
		(net "M_A_DQ27")
	)
	(segment
		(start 152.521412 -48.44034)
		(end 152.736804 -48.44034)
		(width 0.1524)
		(layer "In2.Cu")
		(net "M_A_DQ27")
	)
	(segment
		(start 168.563036 -58.726578)
		(end 168.778428 -58.726578)
		(width 0.1524)
		(layer "In2.Cu")
		(net "M_A_DQ27")
	)
	(segment
		(start 164.532056 -54.677056)
		(end 164.747956 -54.892956)
		(width 0.1524)
		(layer "In2.Cu")
		(net "M_A_DQ27")
	)
	(segment
		(start 123.221242 -46.0248)
		(end 123.373642 -46.1772)
		(width 0.1524)
		(layer "In2.Cu")
		(net "M_A_DQ27")
	)
	(segment
		(start 162.1282 -50.9778)
		(end 160.1978 -50.9778)
		(width 0.1524)
		(layer "In2.Cu")
		(net "M_A_DQ27")
	)
	(segment
		(start 170.58132 -64.30518)
		(end 170.2308 -64.6557)
		(width 0.1524)
		(layer "In2.Cu")
		(net "M_A_DQ27")
	)
	(segment
		(start 168.072308 -57.70753)
		(end 168.2877 -57.70753)
		(width 0.1524)
		(layer "In2.Cu")
		(net "M_A_DQ27")
	)
	(segment
		(start 123.373642 -46.3804)
		(end 123.526042 -46.5328)
		(width 0.1524)
		(layer "In2.Cu")
		(net "M_A_DQ27")
	)
	(segment
		(start 167.915844 -57.863994)
		(end 168.072308 -57.70753)
		(width 0.1524)
		(layer "In2.Cu")
		(net "M_A_DQ27")
	)
	(segment
		(start 167.484552 -57.432702)
		(end 167.484552 -57.648094)
		(width 0.1524)
		(layer "In2.Cu")
		(net "M_A_DQ27")
	)
	(segment
		(start 168.347136 -58.510678)
		(end 168.563036 -58.726578)
		(width 0.1524)
		(layer "In2.Cu")
		(net "M_A_DQ27")
	)
	(segment
		(start 152.821386 -49.00295)
		(end 152.821386 -49.218342)
		(width 0.1524)
		(layer "In2.Cu")
		(net "M_A_DQ27")
	)
	(segment
		(start 160.1978 -51.702208)
		(end 162.282378 -51.702208)
		(width 0.1524)
		(layer "In2.Cu")
		(net "M_A_DQ27")
	)
	(segment
		(start 162.806888 -52.736496)
		(end 162.806888 -52.951888)
		(width 0.1524)
		(layer "In2.Cu")
		(net "M_A_DQ27")
	)
	(segment
		(start 124.440442 -46.0248)
		(end 124.592842 -46.1772)
		(width 0.1524)
		(layer "In2.Cu")
		(net "M_A_DQ27")
	)
	(segment
		(start 169.8244 -59.987942)
		(end 169.8244 -62.2808)
		(width 0.1524)
		(layer "In2.Cu")
		(net "M_A_DQ27")
	)
	(segment
		(start 163.669472 -53.814472)
		(end 163.885372 -54.030372)
		(width 0.1524)
		(layer "In2.Cu")
		(net "M_A_DQ27")
	)
	(segment
		(start 164.24783 -53.883052)
		(end 164.463222 -53.883052)
		(width 0.1524)
		(layer "In2.Cu")
		(net "M_A_DQ27")
	)
	(segment
		(start 160.0454 -51.549808)
		(end 160.1978 -51.702208)
		(width 0.1524)
		(layer "In2.Cu")
		(net "M_A_DQ27")
	)
	(segment
		(start 162.1282 -49.8094)
		(end 162.2806 -49.9618)
		(width 0.1524)
		(layer "In2.Cu")
		(net "M_A_DQ27")
	)
	(segment
		(start 170.2308 -64.6557)
		(end 170.2308 -64.6938)
		(width 0.1524)
		(layer "In2.Cu")
		(net "M_A_DQ27")
	)
	(segment
		(start 165.61054 -55.75554)
		(end 165.825678 -55.75554)
		(width 0.1524)
		(layer "In2.Cu")
		(net "M_A_DQ27")
	)
	(segment
		(start 152.088088 -48.01108)
		(end 151.944324 -48.154844)
		(width 0.1524)
		(layer "In2.Cu")
		(net "M_A_DQ27")
	)
	(segment
		(start 122.916442 -46.0248)
		(end 123.221242 -46.0248)
		(width 0.1524)
		(layer "In2.Cu")
		(net "M_A_DQ27")
	)
	(segment
		(start 163.669472 -53.59908)
		(end 163.669472 -53.814472)
		(width 0.1524)
		(layer "In2.Cu")
		(net "M_A_DQ27")
	)
	(segment
		(start 122.764042 -46.1772)
		(end 122.916442 -46.0248)
		(width 0.1524)
		(layer "In2.Cu")
		(net "M_A_DQ27")
	)
	(segment
		(start 164.963094 -54.892956)
		(end 165.110414 -54.745636)
		(width 0.1524)
		(layer "In2.Cu")
		(net "M_A_DQ27")
	)
	(segment
		(start 162.2806 -49.9618)
		(end 162.2806 -50.8254)
		(width 0.1524)
		(layer "In2.Cu")
		(net "M_A_DQ27")
	)
	(segment
		(start 158.4325 -49.9618)
		(end 158.5849 -49.8094)
		(width 0.1524)
		(layer "In2.Cu")
		(net "M_A_DQ27")
	)
	(segment
		(start 164.10051 -54.030372)
		(end 164.24783 -53.883052)
		(width 0.1524)
		(layer "In2.Cu")
		(net "M_A_DQ27")
	)
	(segment
		(start 166.778432 -56.198262)
		(end 166.778432 -56.413654)
		(width 0.1524)
		(layer "In2.Cu")
		(net "M_A_DQ27")
	)
	(segment
		(start 170.58132 -63.03772)
		(end 170.58132 -64.30518)
		(width 0.1524)
		(layer "In2.Cu")
		(net "M_A_DQ27")
	)
	(segment
		(start 162.2806 -50.8254)
		(end 162.1282 -50.9778)
		(width 0.1524)
		(layer "In2.Cu")
		(net "M_A_DQ27")
	)
	(segment
		(start 167.700452 -57.863994)
		(end 167.915844 -57.863994)
		(width 0.1524)
		(layer "In2.Cu")
		(net "M_A_DQ27")
	)
	(segment
		(start 121.7168 -46.0248)
		(end 121.5644 -46.1772)
		(width 0.1016)
		(layer "In2.Cu")
		(net "M_A_DQ27")
	)
	(segment
		(start 152.088088 -47.795688)
		(end 152.088088 -48.01108)
		(width 0.1524)
		(layer "In2.Cu")
		(net "M_A_DQ27")
	)
	(segment
		(start 169.366184 -59.001406)
		(end 169.20972 -59.15787)
		(width 0.1524)
		(layer "In2.Cu")
		(net "M_A_DQ27")
	)
	(segment
		(start 158.2801 -50.4698)
		(end 158.4325 -50.3174)
		(width 0.1524)
		(layer "In2.Cu")
		(net "M_A_DQ27")
	)
	(segment
		(start 163.385246 -53.020468)
		(end 163.600638 -53.020468)
		(width 0.1524)
		(layer "In2.Cu")
		(net "M_A_DQ27")
	)
	(segment
		(start 162.282378 -51.702208)
		(end 162.953954 -52.373784)
		(width 0.1524)
		(layer "In2.Cu")
		(net "M_A_DQ27")
	)
	(segment
		(start 125.202442 -46.1772)
		(end 125.354842 -46.0248)
		(width 0.1524)
		(layer "In2.Cu")
		(net "M_A_DQ27")
	)
	(segment
		(start 123.373642 -46.1772)
		(end 123.373642 -46.3804)
		(width 0.1524)
		(layer "In2.Cu")
		(net "M_A_DQ27")
	)
	(segment
		(start 125.202442 -46.3804)
		(end 125.202442 -46.1772)
		(width 0.1524)
		(layer "In2.Cu")
		(net "M_A_DQ27")
	)
	(segment
		(start 121.7168 -46.0248)
		(end 122.002042 -46.0248)
		(width 0.1524)
		(layer "In2.Cu")
		(net "M_A_DQ27")
	)
	(segment
		(start 164.747956 -54.892956)
		(end 164.963094 -54.892956)
		(width 0.1524)
		(layer "In2.Cu")
		(net "M_A_DQ27")
	)
	(segment
		(start 169.20972 -59.373262)
		(end 169.8244 -59.987942)
		(width 0.1524)
		(layer "In2.Cu")
		(net "M_A_DQ27")
	)
	(segment
		(start 165.541706 -55.176928)
		(end 165.39464 -55.324248)
		(width 0.1524)
		(layer "In2.Cu")
		(net "M_A_DQ27")
	)
	(segment
		(start 169.366184 -58.786014)
		(end 169.366184 -59.001406)
		(width 0.1524)
		(layer "In2.Cu")
		(net "M_A_DQ27")
	)
	(segment
		(start 122.611642 -46.5328)
		(end 122.764042 -46.3804)
		(width 0.1524)
		(layer "In2.Cu")
		(net "M_A_DQ27")
	)
	(segment
		(start 168.2877 -57.70753)
		(end 168.5036 -57.92343)
		(width 0.1524)
		(layer "In2.Cu")
		(net "M_A_DQ27")
	)
	(segment
		(start 122.154442 -46.3804)
		(end 122.306842 -46.5328)
		(width 0.1524)
		(layer "In2.Cu")
		(net "M_A_DQ27")
	)
	(segment
		(start 124.592842 -46.3804)
		(end 124.745242 -46.5328)
		(width 0.1524)
		(layer "In2.Cu")
		(net "M_A_DQ27")
	)
	(segment
		(start 163.885372 -54.030372)
		(end 164.10051 -54.030372)
		(width 0.1524)
		(layer "In2.Cu")
		(net "M_A_DQ27")
	)
	(segment
		(start 163.022788 -53.167788)
		(end 163.237926 -53.167788)
		(width 0.1524)
		(layer "In2.Cu")
		(net "M_A_DQ27")
	)
	(segment
		(start 163.816538 -53.236368)
		(end 163.816538 -53.45176)
		(width 0.1524)
		(layer "In2.Cu")
		(net "M_A_DQ27")
	)
	(segment
		(start 165.972998 -55.60822)
		(end 166.18839 -55.60822)
		(width 0.1524)
		(layer "In2.Cu")
		(net "M_A_DQ27")
	)
	(segment
		(start 152.375616 -48.586136)
		(end 152.521412 -48.44034)
		(width 0.1524)
		(layer "In2.Cu")
		(net "M_A_DQ27")
	)
	(segment
		(start 163.816538 -53.45176)
		(end 163.669472 -53.59908)
		(width 0.1524)
		(layer "In2.Cu")
		(net "M_A_DQ27")
	)
	(segment
		(start 166.621968 -56.78551)
		(end 166.837868 -57.00141)
		(width 0.1524)
		(layer "In2.Cu")
		(net "M_A_DQ27")
	)
	(segment
		(start 137.780776 -7.853426)
		(end 137.771378 -7.844028)
		(width 0.1778)
		(layer "F.Cu")
		(net "M_B_DQ10")
	)
	(segment
		(start 138.0998 -8.722106)
		(end 138.0998 -8.028178)
		(width 0.1778)
		(layer "F.Cu")
		(net "M_B_DQ10")
	)
	(segment
		(start 138.249914 -8.87222)
		(end 138.0998 -8.722106)
		(width 0.1778)
		(layer "F.Cu")
		(net "M_B_DQ10")
	)
	(segment
		(start 98.806 -21.717)
		(end 98.806 -24.7904)
		(width 0.1016)
		(layer "F.Cu")
		(net "M_B_DQ10")
	)
	(segment
		(start 138.0998 -8.028178)
		(end 137.925048 -7.853426)
		(width 0.1778)
		(layer "F.Cu")
		(net "M_B_DQ10")
	)
	(segment
		(start 98.3234 -21.2344)
		(end 98.806 -21.717)
		(width 0.1016)
		(layer "F.Cu")
		(net "M_B_DQ10")
	)
	(segment
		(start 98.806 -24.7904)
		(end 99.017328 -25.001728)
		(width 0.1016)
		(layer "F.Cu")
		(net "M_B_DQ10")
	)
	(segment
		(start 138.249914 -9.897364)
		(end 138.249914 -8.87222)
		(width 0.1778)
		(layer "F.Cu")
		(net "M_B_DQ10")
	)
	(segment
		(start 98.3234 -21.209)
		(end 98.3234 -21.2344)
		(width 0.1016)
		(layer "F.Cu")
		(net "M_B_DQ10")
	)
	(segment
		(start 99.017328 -25.001728)
		(end 99.017328 -25.951434)
		(width 0.1016)
		(layer "F.Cu")
		(net "M_B_DQ10")
	)
	(segment
		(start 137.925048 -7.853426)
		(end 137.780776 -7.853426)
		(width 0.1778)
		(layer "F.Cu")
		(net "M_B_DQ10")
	)
	(via
		(at 98.3234 -21.209)
		(size 0.4318)
		(drill 0.2032)
		(layers "F.Cu" "B.Cu")
		(net "M_B_DQ10")
	)
	(via
		(at 137.771378 -7.844028)
		(size 0.4318)
		(drill 0.2032)
		(layers "F.Cu" "B.Cu")
		(net "M_B_DQ10")
	)
	(segment
		(start 137.1854 -8.32739)
		(end 137.668762 -7.844028)
		(width 0.1778)
		(layer "B.Cu")
		(net "M_B_DQ10")
	)
	(segment
		(start 137.349992 -9.89076)
		(end 137.349992 -9.10717)
		(width 0.1778)
		(layer "B.Cu")
		(net "M_B_DQ10")
	)
	(segment
		(start 137.1854 -8.942578)
		(end 137.1854 -8.32739)
		(width 0.1778)
		(layer "B.Cu")
		(net "M_B_DQ10")
	)
	(segment
		(start 137.668762 -7.844028)
		(end 137.771378 -7.844028)
		(width 0.1778)
		(layer "B.Cu")
		(net "M_B_DQ10")
	)
	(segment
		(start 137.349992 -9.10717)
		(end 137.1854 -8.942578)
		(width 0.1778)
		(layer "B.Cu")
		(net "M_B_DQ10")
	)
	(segment
		(start 139.2936 -10.882884)
		(end 139.1412 -11.035284)
		(width 0.1524)
		(layer "In2.Cu")
		(net "M_B_DQ10")
	)
	(segment
		(start 100.58781 -21.0312)
		(end 98.5012 -21.0312)
		(width 0.1524)
		(layer "In2.Cu")
		(net "M_B_DQ10")
	)
	(segment
		(start 137.795 -11.187684)
		(end 137.795 -11.797284)
		(width 0.1524)
		(layer "In2.Cu")
		(net "M_B_DQ10")
	)
	(segment
		(start 98.5012 -21.0312)
		(end 98.3234 -21.209)
		(width 0.1524)
		(layer "In2.Cu")
		(net "M_B_DQ10")
	)
	(segment
		(start 139.4714 -12.711684)
		(end 139.319 -12.864084)
		(width 0.1524)
		(layer "In2.Cu")
		(net "M_B_DQ10")
	)
	(segment
		(start 139.319 -12.864084)
		(end 137.0838 -12.864084)
		(width 0.1524)
		(layer "In2.Cu")
		(net "M_B_DQ10")
	)
	(segment
		(start 137.0838 -12.864084)
		(end 136.9314 -13.016484)
		(width 0.1524)
		(layer "In2.Cu")
		(net "M_B_DQ10")
	)
	(segment
		(start 137.780776 -7.853426)
		(end 137.81405 -7.853426)
		(width 0.1524)
		(layer "In2.Cu")
		(net "M_B_DQ10")
	)
	(segment
		(start 119.126254 -17.068546)
		(end 109.697774 -17.068546)
		(width 0.1524)
		(layer "In2.Cu")
		(net "M_B_DQ10")
	)
	(segment
		(start 137.922 -8.89)
		(end 137.922 -10.1092)
		(width 0.1524)
		(layer "In2.Cu")
		(net "M_B_DQ10")
	)
	(segment
		(start 136.9314 -15.4178)
		(end 136.6774 -15.6718)
		(width 0.1524)
		(layer "In2.Cu")
		(net "M_B_DQ10")
	)
	(segment
		(start 139.1412 -10.2616)
		(end 139.2936 -10.414)
		(width 0.1524)
		(layer "In2.Cu")
		(net "M_B_DQ10")
	)
	(segment
		(start 139.2936 -10.414)
		(end 139.2936 -10.882884)
		(width 0.1524)
		(layer "In2.Cu")
		(net "M_B_DQ10")
	)
	(segment
		(start 138.0744 -8.113776)
		(end 138.0744 -8.7376)
		(width 0.1524)
		(layer "In2.Cu")
		(net "M_B_DQ10")
	)
	(segment
		(start 138.0744 -8.7376)
		(end 137.922 -8.89)
		(width 0.1524)
		(layer "In2.Cu")
		(net "M_B_DQ10")
	)
	(segment
		(start 137.771378 -7.844028)
		(end 137.780776 -7.853426)
		(width 0.1524)
		(layer "In2.Cu")
		(net "M_B_DQ10")
	)
	(segment
		(start 137.9474 -11.035284)
		(end 137.795 -11.187684)
		(width 0.1524)
		(layer "In2.Cu")
		(net "M_B_DQ10")
	)
	(segment
		(start 137.795 -11.797284)
		(end 137.9474 -11.949684)
		(width 0.1524)
		(layer "In2.Cu")
		(net "M_B_DQ10")
	)
	(segment
		(start 138.0744 -10.2616)
		(end 139.1412 -10.2616)
		(width 0.1524)
		(layer "In2.Cu")
		(net "M_B_DQ10")
	)
	(segment
		(start 136.9314 -13.016484)
		(end 136.9314 -15.4178)
		(width 0.1524)
		(layer "In2.Cu")
		(net "M_B_DQ10")
	)
	(segment
		(start 139.319 -11.949684)
		(end 139.4714 -12.102084)
		(width 0.1524)
		(layer "In2.Cu")
		(net "M_B_DQ10")
	)
	(segment
		(start 139.1412 -11.035284)
		(end 137.9474 -11.035284)
		(width 0.1524)
		(layer "In2.Cu")
		(net "M_B_DQ10")
	)
	(segment
		(start 119.5832 -16.6116)
		(end 119.126254 -17.068546)
		(width 0.1524)
		(layer "In2.Cu")
		(net "M_B_DQ10")
	)
	(segment
		(start 137.922 -10.1092)
		(end 138.0744 -10.2616)
		(width 0.1524)
		(layer "In2.Cu")
		(net "M_B_DQ10")
	)
	(segment
		(start 107.537758 -19.228562)
		(end 102.390448 -19.228562)
		(width 0.1524)
		(layer "In2.Cu")
		(net "M_B_DQ10")
	)
	(segment
		(start 119.5832 -16.166338)
		(end 119.5832 -16.6116)
		(width 0.1524)
		(layer "In2.Cu")
		(net "M_B_DQ10")
	)
	(segment
		(start 120.077738 -15.6718)
		(end 119.5832 -16.166338)
		(width 0.1524)
		(layer "In2.Cu")
		(net "M_B_DQ10")
	)
	(segment
		(start 109.697774 -17.068546)
		(end 107.537758 -19.228562)
		(width 0.1524)
		(layer "In2.Cu")
		(net "M_B_DQ10")
	)
	(segment
		(start 137.81405 -7.853426)
		(end 138.0744 -8.113776)
		(width 0.1524)
		(layer "In2.Cu")
		(net "M_B_DQ10")
	)
	(segment
		(start 102.390448 -19.228562)
		(end 100.58781 -21.0312)
		(width 0.1524)
		(layer "In2.Cu")
		(net "M_B_DQ10")
	)
	(segment
		(start 136.6774 -15.6718)
		(end 120.077738 -15.6718)
		(width 0.1524)
		(layer "In2.Cu")
		(net "M_B_DQ10")
	)
	(segment
		(start 137.9474 -11.949684)
		(end 139.319 -11.949684)
		(width 0.1524)
		(layer "In2.Cu")
		(net "M_B_DQ10")
	)
	(segment
		(start 139.4714 -12.102084)
		(end 139.4714 -12.711684)
		(width 0.1524)
		(layer "In2.Cu")
		(net "M_B_DQ10")
	)
	(segment
		(start 156.549852 -2.98323)
		(end 156.6164 -3.049778)
		(width 0.1778)
		(layer "F.Cu")
		(net "M_B_CKE2")
	)
	(segment
		(start 100.654104 -30.778958)
		(end 100.654104 -30.720792)
		(width 0.1778)
		(layer "F.Cu")
		(net "M_B_CKE2")
	)
	(segment
		(start 156.549852 -1.68402)
		(end 156.549852 -2.98323)
		(width 0.1778)
		(layer "F.Cu")
		(net "M_B_CKE2")
	)
	(segment
		(start 156.6164 -3.049778)
		(end 156.6164 -3.125978)
		(width 0.1778)
		(layer "F.Cu")
		(net "M_B_CKE2")
	)
	(segment
		(start 100.292408 -31.140654)
		(end 100.654104 -30.778958)
		(width 0.1778)
		(layer "F.Cu")
		(net "M_B_CKE2")
	)
	(via
		(at 100.654104 -30.720792)
		(size 0.4318)
		(drill 0.2032)
		(layers "F.Cu" "B.Cu")
		(net "M_B_CKE2")
	)
	(via
		(at 156.6164 -3.125978)
		(size 0.4318)
		(drill 0.2032)
		(layers "F.Cu" "B.Cu")
		(net "M_B_CKE2")
	)
	(segment
		(start 115.65763 -17.4244)
		(end 115.65763 -17.907)
		(width 0.1524)
		(layer "In9.Cu")
		(net "M_B_CKE2")
	)
	(segment
		(start 158.1658 -11.481562)
		(end 155.423362 -14.224)
		(width 0.1524)
		(layer "In9.Cu")
		(net "M_B_CKE2")
	)
	(segment
		(start 124.594366 -18.0594)
		(end 124.374656 -17.83969)
		(width 0.1524)
		(layer "In9.Cu")
		(net "M_B_CKE2")
	)
	(segment
		(start 125.367288 -18.0594)
		(end 124.594366 -18.0594)
		(width 0.1524)
		(layer "In9.Cu")
		(net "M_B_CKE2")
	)
	(segment
		(start 116.26723 -17.907)
		(end 116.26723 -17.4244)
		(width 0.1524)
		(layer "In9.Cu")
		(net "M_B_CKE2")
	)
	(segment
		(start 158.064708 -6.96214)
		(end 158.064708 -8.240268)
		(width 0.1524)
		(layer "In9.Cu")
		(net "M_B_CKE2")
	)
	(segment
		(start 156.653484 -3.188462)
		(end 157.84322 -4.378198)
		(width 0.1524)
		(layer "In9.Cu")
		(net "M_B_CKE2")
	)
	(segment
		(start 114.59083 -17.272)
		(end 114.43843 -17.4244)
		(width 0.1524)
		(layer "In9.Cu")
		(net "M_B_CKE2")
	)
	(segment
		(start 155.423362 -14.224)
		(end 139.2428 -14.224)
		(width 0.1524)
		(layer "In9.Cu")
		(net "M_B_CKE2")
	)
	(segment
		(start 120.1928 -17.8689)
		(end 120.1928 -17.4625)
		(width 0.1524)
		(layer "In9.Cu")
		(net "M_B_CKE2")
	)
	(segment
		(start 157.84322 -4.378198)
		(end 157.84322 -6.740398)
		(width 0.1524)
		(layer "In9.Cu")
		(net "M_B_CKE2")
	)
	(segment
		(start 119.4816 -17.4371)
		(end 119.4816 -17.907)
		(width 0.1524)
		(layer "In9.Cu")
		(net "M_B_CKE2")
	)
	(segment
		(start 107.8484 -24.8666)
		(end 104.03205 -28.68295)
		(width 0.1524)
		(layer "In9.Cu")
		(net "M_B_CKE2")
	)
	(segment
		(start 116.87683 -17.4244)
		(end 116.87683 -17.907)
		(width 0.1524)
		(layer "In9.Cu")
		(net "M_B_CKE2")
	)
	(segment
		(start 122.873262 -18.0594)
		(end 120.3833 -18.0594)
		(width 0.1524)
		(layer "In9.Cu")
		(net "M_B_CKE2")
	)
	(segment
		(start 119.4816 -17.907)
		(end 119.3292 -18.0594)
		(width 0.1524)
		(layer "In9.Cu")
		(net "M_B_CKE2")
	)
	(segment
		(start 115.50523 -18.0594)
		(end 115.20043 -18.0594)
		(width 0.1524)
		(layer "In9.Cu")
		(net "M_B_CKE2")
	)
	(segment
		(start 116.72443 -18.0594)
		(end 116.41963 -18.0594)
		(width 0.1524)
		(layer "In9.Cu")
		(net "M_B_CKE2")
	)
	(segment
		(start 138.7602 -14.7066)
		(end 138.7602 -17.3736)
		(width 0.1524)
		(layer "In9.Cu")
		(net "M_B_CKE2")
	)
	(segment
		(start 139.2428 -14.224)
		(end 138.7602 -14.7066)
		(width 0.1524)
		(layer "In9.Cu")
		(net "M_B_CKE2")
	)
	(segment
		(start 117.48643 -17.907)
		(end 117.48643 -17.4244)
		(width 0.1524)
		(layer "In9.Cu")
		(net "M_B_CKE2")
	)
	(segment
		(start 125.586998 -17.83969)
		(end 125.367288 -18.0594)
		(width 0.1524)
		(layer "In9.Cu")
		(net "M_B_CKE2")
	)
	(segment
		(start 120.1928 -17.4625)
		(end 120.0023 -17.272)
		(width 0.1524)
		(layer "In9.Cu")
		(net "M_B_CKE2")
	)
	(segment
		(start 116.87683 -17.907)
		(end 116.72443 -18.0594)
		(width 0.1524)
		(layer "In9.Cu")
		(net "M_B_CKE2")
	)
	(segment
		(start 115.04803 -17.907)
		(end 115.04803 -17.4244)
		(width 0.1524)
		(layer "In9.Cu")
		(net "M_B_CKE2")
	)
	(segment
		(start 101.285548 -30.089348)
		(end 100.654104 -30.720792)
		(width 0.1524)
		(layer "In9.Cu")
		(net "M_B_CKE2")
	)
	(segment
		(start 118.85803 -18.0594)
		(end 118.70563 -17.907)
		(width 0.1524)
		(layer "In9.Cu")
		(net "M_B_CKE2")
	)
	(segment
		(start 118.55323 -17.272)
		(end 118.24843 -17.272)
		(width 0.1524)
		(layer "In9.Cu")
		(net "M_B_CKE2")
	)
	(segment
		(start 117.63883 -18.0594)
		(end 117.48643 -17.907)
		(width 0.1524)
		(layer "In9.Cu")
		(net "M_B_CKE2")
	)
	(segment
		(start 114.43843 -17.4244)
		(end 114.43843 -17.907)
		(width 0.1524)
		(layer "In9.Cu")
		(net "M_B_CKE2")
	)
	(segment
		(start 117.94363 -18.0594)
		(end 117.63883 -18.0594)
		(width 0.1524)
		(layer "In9.Cu")
		(net "M_B_CKE2")
	)
	(segment
		(start 119.3292 -18.0594)
		(end 118.85803 -18.0594)
		(width 0.1524)
		(layer "In9.Cu")
		(net "M_B_CKE2")
	)
	(segment
		(start 115.81003 -17.272)
		(end 115.65763 -17.4244)
		(width 0.1524)
		(layer "In9.Cu")
		(net "M_B_CKE2")
	)
	(segment
		(start 118.24843 -17.272)
		(end 118.09603 -17.4244)
		(width 0.1524)
		(layer "In9.Cu")
		(net "M_B_CKE2")
	)
	(segment
		(start 119.6467 -17.272)
		(end 119.4816 -17.4371)
		(width 0.1524)
		(layer "In9.Cu")
		(net "M_B_CKE2")
	)
	(segment
		(start 116.41963 -18.0594)
		(end 116.26723 -17.907)
		(width 0.1524)
		(layer "In9.Cu")
		(net "M_B_CKE2")
	)
	(segment
		(start 116.11483 -17.272)
		(end 115.81003 -17.272)
		(width 0.1524)
		(layer "In9.Cu")
		(net "M_B_CKE2")
	)
	(segment
		(start 120.0023 -17.272)
		(end 119.6467 -17.272)
		(width 0.1524)
		(layer "In9.Cu")
		(net "M_B_CKE2")
	)
	(segment
		(start 107.8484 -23.70963)
		(end 107.8484 -24.8666)
		(width 0.1524)
		(layer "In9.Cu")
		(net "M_B_CKE2")
	)
	(segment
		(start 118.70563 -17.4244)
		(end 118.55323 -17.272)
		(width 0.1524)
		(layer "In9.Cu")
		(net "M_B_CKE2")
	)
	(segment
		(start 113.49863 -18.0594)
		(end 107.8484 -23.70963)
		(width 0.1524)
		(layer "In9.Cu")
		(net "M_B_CKE2")
	)
	(segment
		(start 156.653484 -3.163062)
		(end 156.653484 -3.188462)
		(width 0.1524)
		(layer "In9.Cu")
		(net "M_B_CKE2")
	)
	(segment
		(start 118.70563 -17.907)
		(end 118.70563 -17.4244)
		(width 0.1524)
		(layer "In9.Cu")
		(net "M_B_CKE2")
	)
	(segment
		(start 117.02923 -17.272)
		(end 116.87683 -17.4244)
		(width 0.1524)
		(layer "In9.Cu")
		(net "M_B_CKE2")
	)
	(segment
		(start 114.28603 -18.0594)
		(end 113.49863 -18.0594)
		(width 0.1524)
		(layer "In9.Cu")
		(net "M_B_CKE2")
	)
	(segment
		(start 158.0642 -8.240776)
		(end 158.0642 -8.747506)
		(width 0.1524)
		(layer "In9.Cu")
		(net "M_B_CKE2")
	)
	(segment
		(start 115.65763 -17.907)
		(end 115.50523 -18.0594)
		(width 0.1524)
		(layer "In9.Cu")
		(net "M_B_CKE2")
	)
	(segment
		(start 114.89563 -17.272)
		(end 114.59083 -17.272)
		(width 0.1524)
		(layer "In9.Cu")
		(net "M_B_CKE2")
	)
	(segment
		(start 138.7602 -17.3736)
		(end 138.29411 -17.83969)
		(width 0.1524)
		(layer "In9.Cu")
		(net "M_B_CKE2")
	)
	(segment
		(start 104.03205 -28.68295)
		(end 102.78745 -28.68295)
		(width 0.1524)
		(layer "In9.Cu")
		(net "M_B_CKE2")
	)
	(segment
		(start 123.092972 -17.83969)
		(end 122.873262 -18.0594)
		(width 0.1524)
		(layer "In9.Cu")
		(net "M_B_CKE2")
	)
	(segment
		(start 158.1658 -8.849106)
		(end 158.1658 -11.481562)
		(width 0.1524)
		(layer "In9.Cu")
		(net "M_B_CKE2")
	)
	(segment
		(start 114.43843 -17.907)
		(end 114.28603 -18.0594)
		(width 0.1524)
		(layer "In9.Cu")
		(net "M_B_CKE2")
	)
	(segment
		(start 116.26723 -17.4244)
		(end 116.11483 -17.272)
		(width 0.1524)
		(layer "In9.Cu")
		(net "M_B_CKE2")
	)
	(segment
		(start 120.3833 -18.0594)
		(end 120.1928 -17.8689)
		(width 0.1524)
		(layer "In9.Cu")
		(net "M_B_CKE2")
	)
	(segment
		(start 138.29411 -17.83969)
		(end 125.586998 -17.83969)
		(width 0.1524)
		(layer "In9.Cu")
		(net "M_B_CKE2")
	)
	(segment
		(start 158.0642 -8.747506)
		(end 158.1658 -8.849106)
		(width 0.1524)
		(layer "In9.Cu")
		(net "M_B_CKE2")
	)
	(segment
		(start 156.6164 -3.125978)
		(end 156.653484 -3.163062)
		(width 0.1524)
		(layer "In9.Cu")
		(net "M_B_CKE2")
	)
	(segment
		(start 118.09603 -17.4244)
		(end 118.09603 -17.907)
		(width 0.1524)
		(layer "In9.Cu")
		(net "M_B_CKE2")
	)
	(segment
		(start 115.20043 -18.0594)
		(end 115.04803 -17.907)
		(width 0.1524)
		(layer "In9.Cu")
		(net "M_B_CKE2")
	)
	(segment
		(start 157.84322 -6.740398)
		(end 158.064708 -6.96214)
		(width 0.1524)
		(layer "In9.Cu")
		(net "M_B_CKE2")
	)
	(segment
		(start 102.78745 -28.68295)
		(end 102.45725 -29.01315)
		(width 0.1524)
		(layer "In9.Cu")
		(net "M_B_CKE2")
	)
	(segment
		(start 117.48643 -17.4244)
		(end 117.33403 -17.272)
		(width 0.1524)
		(layer "In9.Cu")
		(net "M_B_CKE2")
	)
	(segment
		(start 115.04803 -17.4244)
		(end 114.89563 -17.272)
		(width 0.1524)
		(layer "In9.Cu")
		(net "M_B_CKE2")
	)
	(segment
		(start 117.33403 -17.272)
		(end 117.02923 -17.272)
		(width 0.1524)
		(layer "In9.Cu")
		(net "M_B_CKE2")
	)
	(segment
		(start 118.09603 -17.907)
		(end 117.94363 -18.0594)
		(width 0.1524)
		(layer "In9.Cu")
		(net "M_B_CKE2")
	)
	(segment
		(start 124.374656 -17.83969)
		(end 123.092972 -17.83969)
		(width 0.1524)
		(layer "In9.Cu")
		(net "M_B_CKE2")
	)
	(segment
		(start 158.064708 -8.240268)
		(end 158.0642 -8.240776)
		(width 0.1524)
		(layer "In9.Cu")
		(net "M_B_CKE2")
	)
	(arc
		(start 101.4476 -29.7688)
		(mid 101.404781 -29.948388)
		(end 101.285548 -30.089348)
		(width 0.1524)
		(layer "In9.Cu")
		(net "M_B_CKE2")
	)
	(arc
		(start 102.45725 -29.01315)
		(mid 102.217627 -29.050645)
		(end 101.975412 -29.063188)
		(width 0.1524)
		(layer "In9.Cu")
		(net "M_B_CKE2")
	)
	(arc
		(start 101.624892 -29.22016)
		(mid 101.493019 -29.480512)
		(end 101.4476 -29.7688)
		(width 0.1524)
		(layer "In9.Cu")
		(net "M_B_CKE2")
	)
	(arc
		(start 101.975412 -29.063188)
		(mid 101.794442 -29.128922)
		(end 101.624892 -29.22016)
		(width 0.1524)
		(layer "In9.Cu")
		(net "M_B_CKE2")
	)
	(segment
		(start 175.8188 -2.932938)
		(end 175.8188 -3.900678)
		(width 0.1778)
		(layer "F.Cu")
		(net "M_B_DQ45")
	)
	(segment
		(start 114.0206 -31.0388)
		(end 114.0206 -31.8262)
		(width 0.1016)
		(layer "F.Cu")
		(net "M_B_DQ45")
	)
	(segment
		(start 176.349914 -1.68402)
		(end 176.349914 -2.401824)
		(width 0.1778)
		(layer "F.Cu")
		(net "M_B_DQ45")
	)
	(segment
		(start 176.349914 -2.401824)
		(end 175.8188 -2.932938)
		(width 0.1778)
		(layer "F.Cu")
		(net "M_B_DQ45")
	)
	(segment
		(start 114.0206 -31.8262)
		(end 112.483646 -33.363154)
		(width 0.1016)
		(layer "F.Cu")
		(net "M_B_DQ45")
	)
	(segment
		(start 114.4524 -30.607)
		(end 114.0206 -31.0388)
		(width 0.1016)
		(layer "F.Cu")
		(net "M_B_DQ45")
	)
	(segment
		(start 116.7892 -30.1752)
		(end 116.3574 -30.607)
		(width 0.1016)
		(layer "F.Cu")
		(net "M_B_DQ45")
	)
	(segment
		(start 112.483646 -33.363154)
		(end 112.098328 -33.363154)
		(width 0.1016)
		(layer "F.Cu")
		(net "M_B_DQ45")
	)
	(segment
		(start 116.3574 -30.607)
		(end 114.4524 -30.607)
		(width 0.1016)
		(layer "F.Cu")
		(net "M_B_DQ45")
	)
	(via
		(at 175.8188 -3.900678)
		(size 0.4318)
		(drill 0.2032)
		(layers "F.Cu" "B.Cu")
		(net "M_B_DQ45")
	)
	(via
		(at 116.7892 -30.1752)
		(size 0.4318)
		(drill 0.2032)
		(layers "F.Cu" "B.Cu")
		(net "M_B_DQ45")
	)
	(segment
		(start 175.449992 -1.690624)
		(end 175.449992 -2.71145)
		(width 0.1778)
		(layer "B.Cu")
		(net "M_B_DQ45")
	)
	(segment
		(start 175.73244 -2.999232)
		(end 175.8188 -3.085592)
		(width 0.1778)
		(layer "B.Cu")
		(net "M_B_DQ45")
	)
	(segment
		(start 175.73244 -2.993898)
		(end 175.73244 -2.999232)
		(width 0.1778)
		(layer "B.Cu")
		(net "M_B_DQ45")
	)
	(segment
		(start 175.8188 -3.085592)
		(end 175.8188 -3.900678)
		(width 0.1778)
		(layer "B.Cu")
		(net "M_B_DQ45")
	)
	(segment
		(start 175.449992 -2.71145)
		(end 175.73244 -2.993898)
		(width 0.1778)
		(layer "B.Cu")
		(net "M_B_DQ45")
	)
	(segment
		(start 163.2712 -15.6464)
		(end 162.283648 -16.633952)
		(width 0.1524)
		(layer "In2.Cu")
		(net "M_B_DQ45")
	)
	(segment
		(start 153.575512 -25.342088)
		(end 153.36012 -25.342088)
		(width 0.1524)
		(layer "In2.Cu")
		(net "M_B_DQ45")
	)
	(segment
		(start 153.100532 -25.297892)
		(end 152.884632 -25.513792)
		(width 0.1524)
		(layer "In2.Cu")
		(net "M_B_DQ45")
	)
	(segment
		(start 152.884632 -25.513792)
		(end 152.884632 -25.729184)
		(width 0.1524)
		(layer "In2.Cu")
		(net "M_B_DQ45")
	)
	(segment
		(start 162.474656 -17.687544)
		(end 162.259264 -17.687544)
		(width 0.1524)
		(layer "In2.Cu")
		(net "M_B_DQ45")
	)
	(segment
		(start 161.39668 -18.550128)
		(end 160.989772 -18.14322)
		(width 0.1524)
		(layer "In2.Cu")
		(net "M_B_DQ45")
	)
	(segment
		(start 118.099586 -28.864814)
		(end 116.7892 -30.1752)
		(width 0.1524)
		(layer "In2.Cu")
		(net "M_B_DQ45")
	)
	(segment
		(start 172.6184 -6.935978)
		(end 172.6184 -10.230104)
		(width 0.1524)
		(layer "In2.Cu")
		(net "M_B_DQ45")
	)
	(segment
		(start 153.315924 -25.297892)
		(end 153.100532 -25.297892)
		(width 0.1524)
		(layer "In2.Cu")
		(net "M_B_DQ45")
	)
	(segment
		(start 162.283648 -16.633952)
		(end 162.283648 -16.849344)
		(width 0.1524)
		(layer "In2.Cu")
		(net "M_B_DQ45")
	)
	(segment
		(start 152.884632 -25.729184)
		(end 152.928828 -25.77338)
		(width 0.1524)
		(layer "In2.Cu")
		(net "M_B_DQ45")
	)
	(segment
		(start 160.989772 -18.14322)
		(end 160.77438 -18.14322)
		(width 0.1524)
		(layer "In2.Cu")
		(net "M_B_DQ45")
	)
	(segment
		(start 162.690556 -17.471644)
		(end 162.474656 -17.687544)
		(width 0.1524)
		(layer "In2.Cu")
		(net "M_B_DQ45")
	)
	(segment
		(start 125.355604 -26.61158)
		(end 123.10237 -28.864814)
		(width 0.1524)
		(layer "In2.Cu")
		(net "M_B_DQ45")
	)
	(segment
		(start 162.259264 -17.687544)
		(end 161.852356 -17.280636)
		(width 0.1524)
		(layer "In2.Cu")
		(net "M_B_DQ45")
	)
	(segment
		(start 154.222704 -24.479504)
		(end 154.178508 -24.435308)
		(width 0.1524)
		(layer "In2.Cu")
		(net "M_B_DQ45")
	)
	(segment
		(start 162.283648 -16.849344)
		(end 162.690556 -17.256252)
		(width 0.1524)
		(layer "In2.Cu")
		(net "M_B_DQ45")
	)
	(segment
		(start 161.636964 -17.280636)
		(end 161.421064 -17.496536)
		(width 0.1524)
		(layer "In2.Cu")
		(net "M_B_DQ45")
	)
	(segment
		(start 152.928828 -25.77338)
		(end 152.928828 -25.988772)
		(width 0.1524)
		(layer "In2.Cu")
		(net "M_B_DQ45")
	)
	(segment
		(start 153.747216 -24.8666)
		(end 153.791412 -24.910796)
		(width 0.1524)
		(layer "In2.Cu")
		(net "M_B_DQ45")
	)
	(segment
		(start 174.0154 -6.580378)
		(end 172.974 -6.580378)
		(width 0.1524)
		(layer "In2.Cu")
		(net "M_B_DQ45")
	)
	(segment
		(start 153.963116 -24.435308)
		(end 153.747216 -24.651208)
		(width 0.1524)
		(layer "In2.Cu")
		(net "M_B_DQ45")
	)
	(segment
		(start 154.6098 -23.788624)
		(end 154.6098 -24.004016)
		(width 0.1524)
		(layer "In2.Cu")
		(net "M_B_DQ45")
	)
	(segment
		(start 161.827972 -18.118836)
		(end 161.827972 -18.334228)
		(width 0.1524)
		(layer "In2.Cu")
		(net "M_B_DQ45")
	)
	(segment
		(start 160.77438 -18.14322)
		(end 155.30068 -23.61692)
		(width 0.1524)
		(layer "In2.Cu")
		(net "M_B_DQ45")
	)
	(segment
		(start 153.747216 -24.651208)
		(end 153.747216 -24.8666)
		(width 0.1524)
		(layer "In2.Cu")
		(net "M_B_DQ45")
	)
	(segment
		(start 161.421064 -17.711928)
		(end 161.827972 -18.118836)
		(width 0.1524)
		(layer "In2.Cu")
		(net "M_B_DQ45")
	)
	(segment
		(start 154.178508 -24.435308)
		(end 153.963116 -24.435308)
		(width 0.1524)
		(layer "In2.Cu")
		(net "M_B_DQ45")
	)
	(segment
		(start 155.085288 -23.61692)
		(end 155.041092 -23.572724)
		(width 0.1524)
		(layer "In2.Cu")
		(net "M_B_DQ45")
	)
	(segment
		(start 174.1678 -5.361178)
		(end 174.1678 -6.427978)
		(width 0.1524)
		(layer "In2.Cu")
		(net "M_B_DQ45")
	)
	(segment
		(start 154.653996 -24.263604)
		(end 154.438096 -24.479504)
		(width 0.1524)
		(layer "In2.Cu")
		(net "M_B_DQ45")
	)
	(segment
		(start 154.6098 -24.004016)
		(end 154.653996 -24.048212)
		(width 0.1524)
		(layer "In2.Cu")
		(net "M_B_DQ45")
	)
	(segment
		(start 174.1678 -6.427978)
		(end 174.0154 -6.580378)
		(width 0.1524)
		(layer "In2.Cu")
		(net "M_B_DQ45")
	)
	(segment
		(start 161.612072 -18.550128)
		(end 161.39668 -18.550128)
		(width 0.1524)
		(layer "In2.Cu")
		(net "M_B_DQ45")
	)
	(segment
		(start 153.791412 -25.126188)
		(end 153.575512 -25.342088)
		(width 0.1524)
		(layer "In2.Cu")
		(net "M_B_DQ45")
	)
	(segment
		(start 155.30068 -23.61692)
		(end 155.085288 -23.61692)
		(width 0.1524)
		(layer "In2.Cu")
		(net "M_B_DQ45")
	)
	(segment
		(start 161.852356 -17.280636)
		(end 161.636964 -17.280636)
		(width 0.1524)
		(layer "In2.Cu")
		(net "M_B_DQ45")
	)
	(segment
		(start 175.8188 -4.610862)
		(end 175.220884 -5.208778)
		(width 0.1524)
		(layer "In2.Cu")
		(net "M_B_DQ45")
	)
	(segment
		(start 123.10237 -28.864814)
		(end 118.099586 -28.864814)
		(width 0.1524)
		(layer "In2.Cu")
		(net "M_B_DQ45")
	)
	(segment
		(start 154.438096 -24.479504)
		(end 154.222704 -24.479504)
		(width 0.1524)
		(layer "In2.Cu")
		(net "M_B_DQ45")
	)
	(segment
		(start 161.827972 -18.334228)
		(end 161.612072 -18.550128)
		(width 0.1524)
		(layer "In2.Cu")
		(net "M_B_DQ45")
	)
	(segment
		(start 154.653996 -24.048212)
		(end 154.653996 -24.263604)
		(width 0.1524)
		(layer "In2.Cu")
		(net "M_B_DQ45")
	)
	(segment
		(start 153.36012 -25.342088)
		(end 153.315924 -25.297892)
		(width 0.1524)
		(layer "In2.Cu")
		(net "M_B_DQ45")
	)
	(segment
		(start 175.220884 -5.208778)
		(end 174.3202 -5.208778)
		(width 0.1524)
		(layer "In2.Cu")
		(net "M_B_DQ45")
	)
	(segment
		(start 152.30602 -26.61158)
		(end 125.355604 -26.61158)
		(width 0.1524)
		(layer "In2.Cu")
		(net "M_B_DQ45")
	)
	(segment
		(start 154.8257 -23.572724)
		(end 154.6098 -23.788624)
		(width 0.1524)
		(layer "In2.Cu")
		(net "M_B_DQ45")
	)
	(segment
		(start 167.202104 -15.6464)
		(end 163.2712 -15.6464)
		(width 0.1524)
		(layer "In2.Cu")
		(net "M_B_DQ45")
	)
	(segment
		(start 162.690556 -17.256252)
		(end 162.690556 -17.471644)
		(width 0.1524)
		(layer "In2.Cu")
		(net "M_B_DQ45")
	)
	(segment
		(start 155.041092 -23.572724)
		(end 154.8257 -23.572724)
		(width 0.1524)
		(layer "In2.Cu")
		(net "M_B_DQ45")
	)
	(segment
		(start 152.928828 -25.988772)
		(end 152.30602 -26.61158)
		(width 0.1524)
		(layer "In2.Cu")
		(net "M_B_DQ45")
	)
	(segment
		(start 172.6184 -10.230104)
		(end 167.202104 -15.6464)
		(width 0.1524)
		(layer "In2.Cu")
		(net "M_B_DQ45")
	)
	(segment
		(start 174.3202 -5.208778)
		(end 174.1678 -5.361178)
		(width 0.1524)
		(layer "In2.Cu")
		(net "M_B_DQ45")
	)
	(segment
		(start 172.974 -6.580378)
		(end 172.6184 -6.935978)
		(width 0.1524)
		(layer "In2.Cu")
		(net "M_B_DQ45")
	)
	(segment
		(start 175.8188 -3.900678)
		(end 175.8188 -4.610862)
		(width 0.1524)
		(layer "In2.Cu")
		(net "M_B_DQ45")
	)
	(segment
		(start 153.791412 -24.910796)
		(end 153.791412 -25.126188)
		(width 0.1524)
		(layer "In2.Cu")
		(net "M_B_DQ45")
	)
	(segment
		(start 161.421064 -17.496536)
		(end 161.421064 -17.711928)
		(width 0.1524)
		(layer "In2.Cu")
		(net "M_B_DQ45")
	)
	(via
		(at 83.947 -61.1632)
		(size 0.7112)
		(drill 0.3556)
		(layers "F.Cu" "B.Cu")
		(net "H_PROCESSOR_HOT_N_R")
	)
	(segment
		(start 85.217 -62.2046)
		(end 84.27085 -63.15075)
		(width 0.1143)
		(layer "B.Cu")
		(net "H_PROCESSOR_HOT_N_R")
	)
	(segment
		(start 84.1756 -61.1632)
		(end 85.217 -62.2046)
		(width 0.1143)
		(layer "B.Cu")
		(net "H_PROCESSOR_HOT_N_R")
	)
	(segment
		(start 84.27085 -63.15075)
		(end 84.27085 -64.02705)
		(width 0.1143)
		(layer "B.Cu")
		(net "H_PROCESSOR_HOT_N_R")
	)
	(segment
		(start 84.27085 -64.02705)
		(end 84.7598 -64.516)
		(width 0.1143)
		(layer "B.Cu")
		(net "H_PROCESSOR_HOT_N_R")
	)
	(segment
		(start 83.947 -61.1632)
		(end 84.1756 -61.1632)
		(width 0.1143)
		(layer "B.Cu")
		(net "H_PROCESSOR_HOT_N_R")
	)
	(segment
		(start 34.163 -19.1008)
		(end 34.163 -19.558)
		(width 0.1143)
		(layer "F.Cu")
		(net "XDP_DFX_PORT_R_CLK0")
	)
	(segment
		(start 32.893 -18.8468)
		(end 33.909 -18.8468)
		(width 0.1143)
		(layer "F.Cu")
		(net "XDP_DFX_PORT_R_CLK0")
	)
	(segment
		(start 35.15995 -20.55495)
		(end 36.37788 -20.55495)
		(width 0.1143)
		(layer "F.Cu")
		(net "XDP_DFX_PORT_R_CLK0")
	)
	(segment
		(start 34.163 -19.558)
		(end 35.15995 -20.55495)
		(width 0.1143)
		(layer "F.Cu")
		(net "XDP_DFX_PORT_R_CLK0")
	)
	(segment
		(start 33.909 -18.8468)
		(end 34.163 -19.1008)
		(width 0.1143)
		(layer "F.Cu")
		(net "XDP_DFX_PORT_R_CLK0")
	)
	(via
		(at 33.909 -18.8468)
		(size 0.7112)
		(drill 0.3556)
		(layers "F.Cu" "B.Cu")
		(net "XDP_DFX_PORT_R_CLK0")
	)
	(segment
		(start 173.49216 -8.139938)
		(end 173.2026 -7.850378)
		(width 0.1778)
		(layer "F.Cu")
		(net "M_B_DQ34")
	)
	(segment
		(start 173.049946 -9.897364)
		(end 173.049946 -9.151112)
		(width 0.1778)
		(layer "F.Cu")
		(net "M_B_DQ34")
	)
	(segment
		(start 108.052108 -33.010094)
		(end 108.458 -32.604202)
		(width 0.1016)
		(layer "F.Cu")
		(net "M_B_DQ34")
	)
	(segment
		(start 173.049946 -9.151112)
		(end 173.49216 -8.708898)
		(width 0.1778)
		(layer "F.Cu")
		(net "M_B_DQ34")
	)
	(segment
		(start 173.49216 -8.708898)
		(end 173.49216 -8.139938)
		(width 0.1778)
		(layer "F.Cu")
		(net "M_B_DQ34")
	)
	(segment
		(start 108.458 -32.604202)
		(end 108.458 -32.5247)
		(width 0.1016)
		(layer "F.Cu")
		(net "M_B_DQ34")
	)
	(via
		(at 108.458 -32.5247)
		(size 0.4318)
		(drill 0.2032)
		(layers "F.Cu" "B.Cu")
		(net "M_B_DQ34")
	)
	(via
		(at 173.2026 -7.850378)
		(size 0.4318)
		(drill 0.2032)
		(layers "F.Cu" "B.Cu")
		(net "M_B_DQ34")
	)
	(segment
		(start 173.55058 -8.42391)
		(end 173.55058 -8.157718)
		(width 0.1778)
		(layer "B.Cu")
		(net "M_B_DQ34")
	)
	(segment
		(start 173.949868 -9.89076)
		(end 173.949868 -8.823198)
		(width 0.1778)
		(layer "B.Cu")
		(net "M_B_DQ34")
	)
	(segment
		(start 173.24324 -7.850378)
		(end 173.2026 -7.850378)
		(width 0.1778)
		(layer "B.Cu")
		(net "M_B_DQ34")
	)
	(segment
		(start 173.55058 -8.157718)
		(end 173.24324 -7.850378)
		(width 0.1778)
		(layer "B.Cu")
		(net "M_B_DQ34")
	)
	(segment
		(start 173.949868 -8.823198)
		(end 173.55058 -8.42391)
		(width 0.1778)
		(layer "B.Cu")
		(net "M_B_DQ34")
	)
	(segment
		(start 108.331 -31.98876)
		(end 108.89996 -31.4198)
		(width 0.1016)
		(layer "In4.Cu")
		(net "M_B_DQ34")
	)
	(segment
		(start 165.073076 -20.092924)
		(end 165.073076 -20.308062)
		(width 0.1524)
		(layer "In4.Cu")
		(net "M_B_DQ34")
	)
	(segment
		(start 114.554 -28.5496)
		(end 113.9952 -29.1084)
		(width 0.1524)
		(layer "In4.Cu")
		(net "M_B_DQ34")
	)
	(segment
		(start 165.244018 -20.694396)
		(end 165.028118 -20.910296)
		(width 0.1524)
		(layer "In4.Cu")
		(net "M_B_DQ34")
	)
	(segment
		(start 142.025624 -29.09443)
		(end 142.025624 -28.702)
		(width 0.1524)
		(layer "In4.Cu")
		(net "M_B_DQ34")
	)
	(segment
		(start 142.152624 -29.22143)
		(end 142.025624 -29.09443)
		(width 0.1524)
		(layer "In4.Cu")
		(net "M_B_DQ34")
	)
	(segment
		(start 143.854424 -28.702)
		(end 143.854424 -29.09443)
		(width 0.1524)
		(layer "In4.Cu")
		(net "M_B_DQ34")
	)
	(segment
		(start 144.464024 -28.702)
		(end 144.311624 -28.5496)
		(width 0.1524)
		(layer "In4.Cu")
		(net "M_B_DQ34")
	)
	(segment
		(start 109.4994 -31.4198)
		(end 110.666784 -30.252416)
		(width 0.1016)
		(layer "In4.Cu")
		(net "M_B_DQ34")
	)
	(segment
		(start 142.787624 -28.5496)
		(end 142.635224 -28.702)
		(width 0.1524)
		(layer "In4.Cu")
		(net "M_B_DQ34")
	)
	(segment
		(start 165.67531 -20.047712)
		(end 165.504368 -19.87677)
		(width 0.1524)
		(layer "In4.Cu")
		(net "M_B_DQ34")
	)
	(segment
		(start 145.810224 -29.22143)
		(end 145.683224 -29.09443)
		(width 0.1524)
		(layer "In4.Cu")
		(net "M_B_DQ34")
	)
	(segment
		(start 146.165824 -29.22143)
		(end 145.810224 -29.22143)
		(width 0.1524)
		(layer "In4.Cu")
		(net "M_B_DQ34")
	)
	(segment
		(start 146.292824 -29.09443)
		(end 146.165824 -29.22143)
		(width 0.1524)
		(layer "In4.Cu")
		(net "M_B_DQ34")
	)
	(segment
		(start 108.89996 -31.4198)
		(end 109.4994 -31.4198)
		(width 0.1016)
		(layer "In4.Cu")
		(net "M_B_DQ34")
	)
	(segment
		(start 165.91026 -19.420078)
		(end 166.106602 -19.61642)
		(width 0.1524)
		(layer "In4.Cu")
		(net "M_B_DQ34")
	)
	(segment
		(start 147.8026 -28.5496)
		(end 147.6502 -28.702)
		(width 0.1524)
		(layer "In4.Cu")
		(net "M_B_DQ34")
	)
	(segment
		(start 166.12616 -18.98904)
		(end 165.91026 -19.20494)
		(width 0.1524)
		(layer "In4.Cu")
		(net "M_B_DQ34")
	)
	(segment
		(start 145.683224 -29.09443)
		(end 145.683224 -28.702)
		(width 0.1524)
		(layer "In4.Cu")
		(net "M_B_DQ34")
	)
	(segment
		(start 147.1422 -29.21)
		(end 146.9898 -29.0576)
		(width 0.1524)
		(layer "In4.Cu")
		(net "M_B_DQ34")
	)
	(segment
		(start 147.4978 -29.21)
		(end 147.1422 -29.21)
		(width 0.1524)
		(layer "In4.Cu")
		(net "M_B_DQ34")
	)
	(segment
		(start 144.591024 -29.22143)
		(end 144.464024 -29.09443)
		(width 0.1524)
		(layer "In4.Cu")
		(net "M_B_DQ34")
	)
	(segment
		(start 143.244824 -28.702)
		(end 143.092424 -28.5496)
		(width 0.1524)
		(layer "In4.Cu")
		(net "M_B_DQ34")
	)
	(segment
		(start 156.4386 -28.5496)
		(end 147.8026 -28.5496)
		(width 0.1524)
		(layer "In4.Cu")
		(net "M_B_DQ34")
	)
	(segment
		(start 165.890702 -20.047712)
		(end 165.67531 -20.047712)
		(width 0.1524)
		(layer "In4.Cu")
		(net "M_B_DQ34")
	)
	(segment
		(start 142.025624 -28.702)
		(end 141.873224 -28.5496)
		(width 0.1524)
		(layer "In4.Cu")
		(net "M_B_DQ34")
	)
	(segment
		(start 145.683224 -28.702)
		(end 145.530824 -28.5496)
		(width 0.1524)
		(layer "In4.Cu")
		(net "M_B_DQ34")
	)
	(segment
		(start 143.244824 -29.09443)
		(end 143.244824 -28.702)
		(width 0.1524)
		(layer "In4.Cu")
		(net "M_B_DQ34")
	)
	(segment
		(start 165.91026 -19.20494)
		(end 165.91026 -19.420078)
		(width 0.1524)
		(layer "In4.Cu")
		(net "M_B_DQ34")
	)
	(segment
		(start 142.635224 -28.702)
		(end 142.635224 -29.09443)
		(width 0.1524)
		(layer "In4.Cu")
		(net "M_B_DQ34")
	)
	(segment
		(start 166.106602 -19.831812)
		(end 165.890702 -20.047712)
		(width 0.1524)
		(layer "In4.Cu")
		(net "M_B_DQ34")
	)
	(segment
		(start 147.6502 -28.702)
		(end 147.6502 -29.0576)
		(width 0.1524)
		(layer "In4.Cu")
		(net "M_B_DQ34")
	)
	(segment
		(start 144.006824 -28.5496)
		(end 143.854424 -28.702)
		(width 0.1524)
		(layer "In4.Cu")
		(net "M_B_DQ34")
	)
	(segment
		(start 173.2026 -7.850378)
		(end 173.485048 -8.132826)
		(width 0.1524)
		(layer "In4.Cu")
		(net "M_B_DQ34")
	)
	(segment
		(start 166.106602 -19.61642)
		(end 166.106602 -19.831812)
		(width 0.1524)
		(layer "In4.Cu")
		(net "M_B_DQ34")
	)
	(segment
		(start 144.311624 -28.5496)
		(end 144.006824 -28.5496)
		(width 0.1524)
		(layer "In4.Cu")
		(net "M_B_DQ34")
	)
	(segment
		(start 145.530824 -28.5496)
		(end 145.226024 -28.5496)
		(width 0.1524)
		(layer "In4.Cu")
		(net "M_B_DQ34")
	)
	(segment
		(start 142.508224 -29.22143)
		(end 142.152624 -29.22143)
		(width 0.1524)
		(layer "In4.Cu")
		(net "M_B_DQ34")
	)
	(segment
		(start 165.28923 -19.87677)
		(end 165.073076 -20.092924)
		(width 0.1524)
		(layer "In4.Cu")
		(net "M_B_DQ34")
	)
	(segment
		(start 147.6502 -29.0576)
		(end 147.4978 -29.21)
		(width 0.1524)
		(layer "In4.Cu")
		(net "M_B_DQ34")
	)
	(segment
		(start 110.666784 -30.252416)
		(end 110.666784 -29.569918)
		(width 0.1016)
		(layer "In4.Cu")
		(net "M_B_DQ34")
	)
	(segment
		(start 146.8374 -28.5496)
		(end 146.445224 -28.5496)
		(width 0.1524)
		(layer "In4.Cu")
		(net "M_B_DQ34")
	)
	(segment
		(start 143.371824 -29.22143)
		(end 143.244824 -29.09443)
		(width 0.1524)
		(layer "In4.Cu")
		(net "M_B_DQ34")
	)
	(segment
		(start 165.028118 -20.910296)
		(end 164.812726 -20.910296)
		(width 0.1524)
		(layer "In4.Cu")
		(net "M_B_DQ34")
	)
	(segment
		(start 165.504368 -19.87677)
		(end 165.28923 -19.87677)
		(width 0.1524)
		(layer "In4.Cu")
		(net "M_B_DQ34")
	)
	(segment
		(start 164.812726 -20.910296)
		(end 164.654484 -20.752308)
		(width 0.1524)
		(layer "In4.Cu")
		(net "M_B_DQ34")
	)
	(segment
		(start 141.873224 -28.5496)
		(end 114.554 -28.5496)
		(width 0.1524)
		(layer "In4.Cu")
		(net "M_B_DQ34")
	)
	(segment
		(start 113.9952 -29.1084)
		(end 111.128302 -29.1084)
		(width 0.1524)
		(layer "In4.Cu")
		(net "M_B_DQ34")
	)
	(segment
		(start 164.235892 -20.752308)
		(end 156.4386 -28.5496)
		(width 0.1524)
		(layer "In4.Cu")
		(net "M_B_DQ34")
	)
	(segment
		(start 166.949374 -18.98904)
		(end 166.12616 -18.98904)
		(width 0.1524)
		(layer "In4.Cu")
		(net "M_B_DQ34")
	)
	(segment
		(start 145.226024 -28.5496)
		(end 145.073624 -28.702)
		(width 0.1524)
		(layer "In4.Cu")
		(net "M_B_DQ34")
	)
	(segment
		(start 143.727424 -29.22143)
		(end 143.371824 -29.22143)
		(width 0.1524)
		(layer "In4.Cu")
		(net "M_B_DQ34")
	)
	(segment
		(start 144.946624 -29.22143)
		(end 144.591024 -29.22143)
		(width 0.1524)
		(layer "In4.Cu")
		(net "M_B_DQ34")
	)
	(segment
		(start 146.445224 -28.5496)
		(end 146.292824 -28.702)
		(width 0.1524)
		(layer "In4.Cu")
		(net "M_B_DQ34")
	)
	(segment
		(start 173.485048 -12.453366)
		(end 166.949374 -18.98904)
		(width 0.1524)
		(layer "In4.Cu")
		(net "M_B_DQ34")
	)
	(segment
		(start 110.666784 -29.569918)
		(end 111.001302 -29.2354)
		(width 0.1016)
		(layer "In4.Cu")
		(net "M_B_DQ34")
	)
	(segment
		(start 165.073076 -20.308062)
		(end 165.244018 -20.479004)
		(width 0.1524)
		(layer "In4.Cu")
		(net "M_B_DQ34")
	)
	(segment
		(start 111.128302 -29.1084)
		(end 111.001302 -29.2354)
		(width 0.1524)
		(layer "In4.Cu")
		(net "M_B_DQ34")
	)
	(segment
		(start 143.854424 -29.09443)
		(end 143.727424 -29.22143)
		(width 0.1524)
		(layer "In4.Cu")
		(net "M_B_DQ34")
	)
	(segment
		(start 164.654484 -20.752308)
		(end 164.235892 -20.752308)
		(width 0.1524)
		(layer "In4.Cu")
		(net "M_B_DQ34")
	)
	(segment
		(start 146.9898 -28.702)
		(end 146.8374 -28.5496)
		(width 0.1524)
		(layer "In4.Cu")
		(net "M_B_DQ34")
	)
	(segment
		(start 108.458 -32.5247)
		(end 108.331 -32.3977)
		(width 0.1016)
		(layer "In4.Cu")
		(net "M_B_DQ34")
	)
	(segment
		(start 165.244018 -20.479004)
		(end 165.244018 -20.694396)
		(width 0.1524)
		(layer "In4.Cu")
		(net "M_B_DQ34")
	)
	(segment
		(start 142.635224 -29.09443)
		(end 142.508224 -29.22143)
		(width 0.1524)
		(layer "In4.Cu")
		(net "M_B_DQ34")
	)
	(segment
		(start 146.9898 -29.0576)
		(end 146.9898 -28.702)
		(width 0.1524)
		(layer "In4.Cu")
		(net "M_B_DQ34")
	)
	(segment
		(start 173.485048 -8.132826)
		(end 173.485048 -12.453366)
		(width 0.1524)
		(layer "In4.Cu")
		(net "M_B_DQ34")
	)
	(segment
		(start 145.073624 -29.09443)
		(end 144.946624 -29.22143)
		(width 0.1524)
		(layer "In4.Cu")
		(net "M_B_DQ34")
	)
	(segment
		(start 144.464024 -29.09443)
		(end 144.464024 -28.702)
		(width 0.1524)
		(layer "In4.Cu")
		(net "M_B_DQ34")
	)
	(segment
		(start 145.073624 -28.702)
		(end 145.073624 -29.09443)
		(width 0.1524)
		(layer "In4.Cu")
		(net "M_B_DQ34")
	)
	(segment
		(start 146.292824 -28.702)
		(end 146.292824 -29.09443)
		(width 0.1524)
		(layer "In4.Cu")
		(net "M_B_DQ34")
	)
	(segment
		(start 108.331 -32.3977)
		(end 108.331 -31.98876)
		(width 0.1016)
		(layer "In4.Cu")
		(net "M_B_DQ34")
	)
	(segment
		(start 143.092424 -28.5496)
		(end 142.787624 -28.5496)
		(width 0.1524)
		(layer "In4.Cu")
		(net "M_B_DQ34")
	)
	(segment
		(start 78.955392 -44.082462)
		(end 78.95463 -44.0817)
		(width 0.1143)
		(layer "F.Cu")
		(net "XDP_DFX_PORT_CLK0")
	)
	(segment
		(start 32.893 -17.9832)
		(end 34.020252 -17.9832)
		(width 0.1143)
		(layer "F.Cu")
		(net "XDP_DFX_PORT_CLK0")
	)
	(segment
		(start 78.8289 -44.0817)
		(end 78.514448 -43.767248)
		(width 0.1143)
		(layer "F.Cu")
		(net "XDP_DFX_PORT_CLK0")
	)
	(segment
		(start 78.95463 -44.0817)
		(end 78.8289 -44.0817)
		(width 0.1143)
		(layer "F.Cu")
		(net "XDP_DFX_PORT_CLK0")
	)
	(segment
		(start 79.5401 -44.0817)
		(end 79.26705 -44.0817)
		(width 0.1143)
		(layer "F.Cu")
		(net "XDP_DFX_PORT_CLK0")
	)
	(segment
		(start 34.833052 -18.796)
		(end 34.833052 -19.434048)
		(width 0.1143)
		(layer "F.Cu")
		(net "XDP_DFX_PORT_CLK0")
	)
	(segment
		(start 79.266288 -44.082462)
		(end 78.955392 -44.082462)
		(width 0.1143)
		(layer "F.Cu")
		(net "XDP_DFX_PORT_CLK0")
	)
	(segment
		(start 79.26705 -44.0817)
		(end 79.266288 -44.082462)
		(width 0.1143)
		(layer "F.Cu")
		(net "XDP_DFX_PORT_CLK0")
	)
	(segment
		(start 34.020252 -17.9832)
		(end 34.833052 -18.796)
		(width 0.1143)
		(layer "F.Cu")
		(net "XDP_DFX_PORT_CLK0")
	)
	(segment
		(start 79.612236 -44.009564)
		(end 79.5401 -44.0817)
		(width 0.1143)
		(layer "F.Cu")
		(net "XDP_DFX_PORT_CLK0")
	)
	(segment
		(start 80.2259 -44.009564)
		(end 79.612236 -44.009564)
		(width 0.1143)
		(layer "F.Cu")
		(net "XDP_DFX_PORT_CLK0")
	)
	(segment
		(start 80.48371 -44.267374)
		(end 80.2259 -44.009564)
		(width 0.1143)
		(layer "F.Cu")
		(net "XDP_DFX_PORT_CLK0")
	)
	(segment
		(start 78.514448 -43.767248)
		(end 78.514448 -43.67784)
		(width 0.1143)
		(layer "F.Cu")
		(net "XDP_DFX_PORT_CLK0")
	)
	(segment
		(start 81.054448 -44.267374)
		(end 80.48371 -44.267374)
		(width 0.1143)
		(layer "F.Cu")
		(net "XDP_DFX_PORT_CLK0")
	)
	(via
		(at 33.8582 -19.5834)
		(size 0.7112)
		(drill 0.3556)
		(layers "F.Cu" "B.Cu")
		(net "XDP_DFX_PORT_CLK0")
	)
	(via
		(at 78.514448 -43.67784)
		(size 0.508)
		(drill 0.254)
		(layers "F.Cu" "B.Cu")
		(net "XDP_DFX_PORT_CLK0")
	)
	(via
		(at 34.833052 -19.434048)
		(size 0.508)
		(drill 0.254)
		(layers "F.Cu" "B.Cu")
		(net "XDP_DFX_PORT_CLK0")
	)
	(segment
		(start 34.007552 -19.434048)
		(end 34.833052 -19.434048)
		(width 0.1143)
		(layer "B.Cu")
		(net "XDP_DFX_PORT_CLK0")
	)
	(segment
		(start 33.8582 -19.5834)
		(end 34.007552 -19.434048)
		(width 0.1143)
		(layer "B.Cu")
		(net "XDP_DFX_PORT_CLK0")
	)
	(segment
		(start 73.2409 -38.429946)
		(end 73.2409 -39.8907)
		(width 0.0889)
		(layer "In7.Cu")
		(net "XDP_DFX_PORT_CLK0")
	)
	(segment
		(start 34.833052 -19.434048)
		(end 35.649662 -19.434048)
		(width 0.0889)
		(layer "In7.Cu")
		(net "XDP_DFX_PORT_CLK0")
	)
	(segment
		(start 58.544206 -37.28085)
		(end 72.091804 -37.28085)
		(width 0.0889)
		(layer "In7.Cu")
		(net "XDP_DFX_PORT_CLK0")
	)
	(segment
		(start 77.762608 -42.926)
		(end 78.514448 -43.67784)
		(width 0.0889)
		(layer "In7.Cu")
		(net "XDP_DFX_PORT_CLK0")
	)
	(segment
		(start 51.053746 -36.122356)
		(end 57.385712 -36.122356)
		(width 0.0889)
		(layer "In7.Cu")
		(net "XDP_DFX_PORT_CLK0")
	)
	(segment
		(start 76.2762 -42.926)
		(end 77.762608 -42.926)
		(width 0.0889)
		(layer "In7.Cu")
		(net "XDP_DFX_PORT_CLK0")
	)
	(segment
		(start 35.649662 -19.434048)
		(end 41.39692 -25.181306)
		(width 0.0889)
		(layer "In7.Cu")
		(net "XDP_DFX_PORT_CLK0")
	)
	(segment
		(start 73.2409 -39.8907)
		(end 76.2762 -42.926)
		(width 0.0889)
		(layer "In7.Cu")
		(net "XDP_DFX_PORT_CLK0")
	)
	(segment
		(start 72.091804 -37.28085)
		(end 73.2409 -38.429946)
		(width 0.0889)
		(layer "In7.Cu")
		(net "XDP_DFX_PORT_CLK0")
	)
	(segment
		(start 46.180248 -31.877)
		(end 46.80839 -31.877)
		(width 0.0889)
		(layer "In7.Cu")
		(net "XDP_DFX_PORT_CLK0")
	)
	(segment
		(start 46.80839 -31.877)
		(end 51.053746 -36.122356)
		(width 0.0889)
		(layer "In7.Cu")
		(net "XDP_DFX_PORT_CLK0")
	)
	(segment
		(start 41.39692 -27.093672)
		(end 46.180248 -31.877)
		(width 0.0889)
		(layer "In7.Cu")
		(net "XDP_DFX_PORT_CLK0")
	)
	(segment
		(start 41.39692 -25.181306)
		(end 41.39692 -27.093672)
		(width 0.0889)
		(layer "In7.Cu")
		(net "XDP_DFX_PORT_CLK0")
	)
	(segment
		(start 57.385712 -36.122356)
		(end 58.544206 -37.28085)
		(width 0.0889)
		(layer "In7.Cu")
		(net "XDP_DFX_PORT_CLK0")
	)
	(segment
		(start 127.065532 -68.453)
		(end 124.267468 -68.453)
		(width 0.1143)
		(layer "B.Cu")
		(net "SMB_M_A0_R_DATA")
	)
	(segment
		(start 128.050036 -70.79996)
		(end 128.050036 -69.437504)
		(width 0.1143)
		(layer "B.Cu")
		(net "SMB_M_A0_R_DATA")
	)
	(segment
		(start 124.267468 -68.453)
		(end 123.530868 -69.1896)
		(width 0.1143)
		(layer "B.Cu")
		(net "SMB_M_A0_R_DATA")
	)
	(segment
		(start 123.530868 -69.1896)
		(end 121.666 -69.1896)
		(width 0.1143)
		(layer "B.Cu")
		(net "SMB_M_A0_R_DATA")
	)
	(segment
		(start 128.050036 -69.437504)
		(end 127.065532 -68.453)
		(width 0.1143)
		(layer "B.Cu")
		(net "SMB_M_A0_R_DATA")
	)
	(segment
		(start 156.722826 -7.575804)
		(end 155.964128 -6.817106)
		(width 0.2413)
		(layer "F.Cu")
		(net "M_B_MA15")
	)
	(segment
		(start 99.591368 -29.645356)
		(end 99.591368 -29.616654)
		(width 0.1016)
		(layer "F.Cu")
		(net "M_B_MA15")
	)
	(segment
		(start 155.964128 -6.817106)
		(end 155.964128 -5.510022)
		(width 0.2413)
		(layer "F.Cu")
		(net "M_B_MA15")
	)
	(segment
		(start 156.722826 -8.651494)
		(end 156.722826 -7.575804)
		(width 0.2413)
		(layer "F.Cu")
		(net "M_B_MA15")
	)
	(segment
		(start 99.892612 -29.96946)
		(end 99.892612 -29.9466)
		(width 0.1016)
		(layer "F.Cu")
		(net "M_B_MA15")
	)
	(segment
		(start 99.892612 -29.9466)
		(end 99.591368 -29.645356)
		(width 0.1016)
		(layer "F.Cu")
		(net "M_B_MA15")
	)
	(segment
		(start 99.906074 -29.982922)
		(end 99.892612 -29.96946)
		(width 0.1016)
		(layer "F.Cu")
		(net "M_B_MA15")
	)
	(segment
		(start 155.964128 -5.510022)
		(end 156.426408 -5.047742)
		(width 0.2413)
		(layer "F.Cu")
		(net "M_B_MA15")
	)
	(segment
		(start 156.849826 -9.897364)
		(end 156.849826 -8.778494)
		(width 0.2413)
		(layer "F.Cu")
		(net "M_B_MA15")
	)
	(segment
		(start 156.426408 -5.047742)
		(end 156.426408 -5.030978)
		(width 0.2413)
		(layer "F.Cu")
		(net "M_B_MA15")
	)
	(segment
		(start 156.849826 -8.778494)
		(end 156.722826 -8.651494)
		(width 0.2413)
		(layer "F.Cu")
		(net "M_B_MA15")
	)
	(via
		(at 156.426408 -5.030978)
		(size 0.4318)
		(drill 0.2032)
		(layers "F.Cu" "B.Cu")
		(net "M_B_MA15")
	)
	(via
		(at 99.906074 -29.982922)
		(size 0.4318)
		(drill 0.2032)
		(layers "F.Cu" "B.Cu")
		(net "M_B_MA15")
	)
	(segment
		(start 156.426408 -4.83997)
		(end 156.426408 -5.030978)
		(width 0.2413)
		(layer "B.Cu")
		(net "M_B_MA15")
	)
	(segment
		(start 156.849826 -1.690624)
		(end 156.849826 -2.564384)
		(width 0.2413)
		(layer "B.Cu")
		(net "M_B_MA15")
	)
	(segment
		(start 156.849826 -2.564384)
		(end 157.107128 -2.821686)
		(width 0.2413)
		(layer "B.Cu")
		(net "M_B_MA15")
	)
	(segment
		(start 157.107128 -4.15925)
		(end 156.426408 -4.83997)
		(width 0.2413)
		(layer "B.Cu")
		(net "M_B_MA15")
	)
	(segment
		(start 157.107128 -2.821686)
		(end 157.107128 -4.15925)
		(width 0.2413)
		(layer "B.Cu")
		(net "M_B_MA15")
	)
	(segment
		(start 98.554794 -27.790902)
		(end 98.552 -27.793696)
		(width 0.1016)
		(layer "In7.Cu")
		(net "M_B_MA15")
	)
	(segment
		(start 148.0312 -14.3256)
		(end 147.4216 -14.3256)
		(width 0.1905)
		(layer "In7.Cu")
		(net "M_B_MA15")
	)
	(segment
		(start 98.552 -26.162)
		(end 98.552 -27.4828)
		(width 0.1016)
		(layer "In7.Cu")
		(net "M_B_MA15")
	)
	(segment
		(start 109.093 -20.0152)
		(end 101.3968 -20.0152)
		(width 0.1905)
		(layer "In7.Cu")
		(net "M_B_MA15")
	)
	(segment
		(start 156.426408 -5.030978)
		(end 156.375608 -5.081778)
		(width 0.1905)
		(layer "In7.Cu")
		(net "M_B_MA15")
	)
	(segment
		(start 98.552 -27.4828)
		(end 98.554794 -27.485594)
		(width 0.1016)
		(layer "In7.Cu")
		(net "M_B_MA15")
	)
	(segment
		(start 147.4216 -14.3256)
		(end 147.2184 -14.1224)
		(width 0.1905)
		(layer "In7.Cu")
		(net "M_B_MA15")
	)
	(segment
		(start 100.9269 -20.4851)
		(end 99.695 -21.717)
		(width 0.1016)
		(layer "In7.Cu")
		(net "M_B_MA15")
	)
	(segment
		(start 98.554794 -27.485594)
		(end 98.554794 -27.790902)
		(width 0.1016)
		(layer "In7.Cu")
		(net "M_B_MA15")
	)
	(segment
		(start 135.4074 -14.2748)
		(end 134.98195 -14.70025)
		(width 0.1905)
		(layer "In7.Cu")
		(net "M_B_MA15")
	)
	(segment
		(start 99.782122 -29.982922)
		(end 99.906074 -29.982922)
		(width 0.1016)
		(layer "In7.Cu")
		(net "M_B_MA15")
	)
	(segment
		(start 98.552 -28.7528)
		(end 99.782122 -29.982922)
		(width 0.1016)
		(layer "In7.Cu")
		(net "M_B_MA15")
	)
	(segment
		(start 134.98195 -14.70025)
		(end 114.40795 -14.70025)
		(width 0.1905)
		(layer "In7.Cu")
		(net "M_B_MA15")
	)
	(segment
		(start 101.3968 -20.0152)
		(end 100.9269 -20.4851)
		(width 0.1905)
		(layer "In7.Cu")
		(net "M_B_MA15")
	)
	(segment
		(start 147.2184 -14.1224)
		(end 147.2184 -11.938)
		(width 0.1905)
		(layer "In7.Cu")
		(net "M_B_MA15")
	)
	(segment
		(start 156.375608 -5.081778)
		(end 155.1432 -5.081778)
		(width 0.1905)
		(layer "In7.Cu")
		(net "M_B_MA15")
	)
	(segment
		(start 152.9715 -9.3853)
		(end 148.0312 -14.3256)
		(width 0.1905)
		(layer "In7.Cu")
		(net "M_B_MA15")
	)
	(segment
		(start 147.0152 -11.7348)
		(end 135.6106 -11.7348)
		(width 0.1905)
		(layer "In7.Cu")
		(net "M_B_MA15")
	)
	(segment
		(start 99.695 -25.019)
		(end 98.552 -26.162)
		(width 0.1016)
		(layer "In7.Cu")
		(net "M_B_MA15")
	)
	(segment
		(start 114.40795 -14.70025)
		(end 109.093 -20.0152)
		(width 0.1905)
		(layer "In7.Cu")
		(net "M_B_MA15")
	)
	(segment
		(start 135.6106 -11.7348)
		(end 135.4074 -11.938)
		(width 0.1905)
		(layer "In7.Cu")
		(net "M_B_MA15")
	)
	(segment
		(start 98.552 -27.793696)
		(end 98.552 -28.7528)
		(width 0.1016)
		(layer "In7.Cu")
		(net "M_B_MA15")
	)
	(segment
		(start 155.1432 -5.081778)
		(end 152.9715 -7.253478)
		(width 0.1905)
		(layer "In7.Cu")
		(net "M_B_MA15")
	)
	(segment
		(start 152.9715 -7.253478)
		(end 152.9715 -9.3853)
		(width 0.1905)
		(layer "In7.Cu")
		(net "M_B_MA15")
	)
	(segment
		(start 135.4074 -11.938)
		(end 135.4074 -14.2748)
		(width 0.1905)
		(layer "In7.Cu")
		(net "M_B_MA15")
	)
	(segment
		(start 99.695 -21.717)
		(end 99.695 -25.019)
		(width 0.1016)
		(layer "In7.Cu")
		(net "M_B_MA15")
	)
	(segment
		(start 147.2184 -11.938)
		(end 147.0152 -11.7348)
		(width 0.1905)
		(layer "In7.Cu")
		(net "M_B_MA15")
	)
	(segment
		(start 174.879 -58.547)
		(end 175.3616 -59.0296)
		(width 0.3048)
		(layer "F.Cu")
		(net "P3V3_STBY")
	)
	(segment
		(start 109.2962 -70.5612)
		(end 109.2962 -70.612)
		(width 0.3048)
		(layer "F.Cu")
		(net "P3V3_STBY")
	)
	(segment
		(start 199.745854 -6.832854)
		(end 199.745854 -8.9408)
		(width 0.3048)
		(layer "F.Cu")
		(net "P3V3_STBY")
	)
	(segment
		(start 14.3256 -56.9722)
		(end 14.605 -56.6928)
		(width 0.3048)
		(layer "F.Cu")
		(net "P3V3_STBY")
	)
	(segment
		(start 156.4767 -27.7495)
		(end 158.209234 -27.7495)
		(width 0.3048)
		(layer "F.Cu")
		(net "P3V3_STBY")
	)
	(segment
		(start 174.879 -43.942)
		(end 175.387 -43.434)
		(width 0.508)
		(layer "F.Cu")
		(net "P3V3_STBY")
	)
	(segment
		(start 128.014984 -68.534026)
		(end 128.35001 -68.199)
		(width 0.508)
		(layer "F.Cu")
		(net "P3V3_STBY")
	)
	(segment
		(start 149.01037 -51.64963)
		(end 149.01037 -51.4223)
		(width 0.254)
		(layer "F.Cu")
		(net "P3V3_STBY")
	)
	(segment
		(start 76.279756 -57.1246)
		(end 77.3176 -57.1246)
		(width 0.3048)
		(layer "F.Cu")
		(net "P3V3_STBY")
	)
	(segment
		(start 4.445 -48.3108)
		(end 4.2926 -48.4632)
		(width 0.254)
		(layer "F.Cu")
		(net "P3V3_STBY")
	)
	(segment
		(start 101.8286 -67.9196)
		(end 101.4984 -67.5894)
		(width 0.3048)
		(layer "F.Cu")
		(net "P3V3_STBY")
	)
	(segment
		(start 154.2796 -29.546042)
		(end 154.2796 -29.562044)
		(width 0.3048)
		(layer "F.Cu")
		(net "P3V3_STBY")
	)
	(segment
		(start 144.826736 -54.39664)
		(end 144.03324 -54.39664)
		(width 0.3048)
		(layer "F.Cu")
		(net "P3V3_STBY")
	)
	(segment
		(start 176.911 -51.054)
		(end 178.2318 -52.3748)
		(width 0.508)
		(layer "F.Cu")
		(net "P3V3_STBY")
	)
	(segment
		(start 143.891 -21.5138)
		(end 143.891 -22.098)
		(width 0.3048)
		(layer "F.Cu")
		(net "P3V3_STBY")
	)
	(segment
		(start 143.7894 -22.6314)
		(end 143.764 -22.6314)
		(width 0.3048)
		(layer "F.Cu")
		(net "P3V3_STBY")
	)
	(segment
		(start 163.615624 -42.8498)
		(end 163.2966 -42.530776)
		(width 0.3048)
		(layer "F.Cu")
		(net "P3V3_STBY")
	)
	(segment
		(start 179.578 -45.974)
		(end 180.975 -47.371)
		(width 0.3048)
		(layer "F.Cu")
		(net "P3V3_STBY")
	)
	(segment
		(start 143.357092 -46.604174)
		(end 143.357092 -46.482508)
		(width 0.3048)
		(layer "F.Cu")
		(net "P3V3_STBY")
	)
	(segment
		(start 162.52825 -29.30525)
		(end 162.52825 -33.62325)
		(width 0.508)
		(layer "F.Cu")
		(net "P3V3_STBY")
	)
	(segment
		(start 158.5468 -28.829)
		(end 158.611824 -28.829)
		(width 0.3048)
		(layer "F.Cu")
		(net "P3V3_STBY")
	)
	(segment
		(start 127.7112 -33.528)
		(end 127.7112 -34.29)
		(width 0.3048)
		(layer "F.Cu")
		(net "P3V3_STBY")
	)
	(segment
		(start 130.42138 -30.85338)
		(end 129.921 -30.353)
		(width 0.3048)
		(layer "F.Cu")
		(net "P3V3_STBY")
	)
	(segment
		(start 5.331206 -52.730654)
		(end 5.003546 -52.402994)
		(width 0.254)
		(layer "F.Cu")
		(net "P3V3_STBY")
	)
	(segment
		(start 161.29 -28.067)
		(end 162.52825 -29.30525)
		(width 0.508)
		(layer "F.Cu")
		(net "P3V3_STBY")
	)
	(segment
		(start 182.43296 -48.91024)
		(end 182.118 -49.2252)
		(width 0.3048)
		(layer "F.Cu")
		(net "P3V3_STBY")
	)
	(segment
		(start 48.006 -22.2758)
		(end 47.1424 -22.2758)
		(width 0.3048)
		(layer "F.Cu")
		(net "P3V3_STBY")
	)
	(segment
		(start 28.459176 -13.462)
		(end 28.194 -13.196824)
		(width 0.3048)
		(layer "F.Cu")
		(net "P3V3_STBY")
	)
	(segment
		(start 125.222 -30.301946)
		(end 125.222 -30.5308)
		(width 0.3048)
		(layer "F.Cu")
		(net "P3V3_STBY")
	)
	(segment
		(start 175.3616 -59.0296)
		(end 176.774094 -59.0296)
		(width 0.3048)
		(layer "F.Cu")
		(net "P3V3_STBY")
	)
	(segment
		(start 148.8059 -53.9115)
		(end 148.8059 -51.8541)
		(width 0.254)
		(layer "F.Cu")
		(net "P3V3_STBY")
	)
	(segment
		(start 143.256 -46.705266)
		(end 143.357092 -46.604174)
		(width 0.3048)
		(layer "F.Cu")
		(net "P3V3_STBY")
	)
	(segment
		(start 108.66628 -63.99276)
		(end 107.75696 -63.99276)
		(width 0.3048)
		(layer "F.Cu")
		(net "P3V3_STBY")
	)
	(segment
		(start 166.1922 -55.372)
		(end 164.874194 -55.372)
		(width 0.508)
		(layer "F.Cu")
		(net "P3V3_STBY")
	)
	(segment
		(start 132.1308 -38.29431)
		(end 133.05282 -38.29431)
		(width 0.3048)
		(layer "F.Cu")
		(net "P3V3_STBY")
	)
	(segment
		(start 91.186 -13.6398)
		(end 91.0336 -13.6398)
		(width 0.3048)
		(layer "F.Cu")
		(net "P3V3_STBY")
	)
	(segment
		(start 162.52825 -33.62325)
		(end 164.719 -35.814)
		(width 0.508)
		(layer "F.Cu")
		(net "P3V3_STBY")
	)
	(segment
		(start 137.9982 -22.7965)
		(end 137.9093 -22.7076)
		(width 0.3048)
		(layer "F.Cu")
		(net "P3V3_STBY")
	)
	(segment
		(start 146.558 -21.1328)
		(end 146.558 -22.2758)
		(width 0.3048)
		(layer "F.Cu")
		(net "P3V3_STBY")
	)
	(segment
		(start 174.879 -57.5818)
		(end 174.879 -58.547)
		(width 0.3048)
		(layer "F.Cu")
		(net "P3V3_STBY")
	)
	(segment
		(start 182.0164 -33.9344)
		(end 182.372 -33.9344)
		(width 0.3048)
		(layer "F.Cu")
		(net "P3V3_STBY")
	)
	(segment
		(start 153.3652 -29.7942)
		(end 152.512268 -29.7942)
		(width 0.3048)
		(layer "F.Cu")
		(net "P3V3_STBY")
	)
	(segment
		(start 34.8488 -13.5128)
		(end 34.29 -13.5128)
		(width 0.3048)
		(layer "F.Cu")
		(net "P3V3_STBY")
	)
	(segment
		(start 133.36397 -33.79343)
		(end 134.1374 -33.02)
		(width 0.3048)
		(layer "F.Cu")
		(net "P3V3_STBY")
	)
	(segment
		(start 159.4104 -29.6926)
		(end 159.4104 -31.2674)
		(width 0.3048)
		(layer "F.Cu")
		(net "P3V3_STBY")
	)
	(segment
		(start 188.7474 -49.657)
		(end 189.103 -49.3014)
		(width 0.3048)
		(layer "F.Cu")
		(net "P3V3_STBY")
	)
	(segment
		(start 70.7517 -15.8115)
		(end 70.8152 -15.748)
		(width 0.3048)
		(layer "F.Cu")
		(net "P3V3_STBY")
	)
	(segment
		(start 174.3456 -43.942)
		(end 174.879 -43.942)
		(width 0.508)
		(layer "F.Cu")
		(net "P3V3_STBY")
	)
	(segment
		(start 177.165 -58.638694)
		(end 177.165 -57.5818)
		(width 0.3048)
		(layer "F.Cu")
		(net "P3V3_STBY")
	)
	(segment
		(start 155.702 -27.7622)
		(end 156.464 -27.7622)
		(width 0.3048)
		(layer "F.Cu")
		(net "P3V3_STBY")
	)
	(segment
		(start 76.8731 -63.71717)
		(end 76.54163 -63.71717)
		(width 0.3048)
		(layer "F.Cu")
		(net "P3V3_STBY")
	)
	(segment
		(start 167.005 -55.5498)
		(end 166.37 -55.5498)
		(width 0.508)
		(layer "F.Cu")
		(net "P3V3_STBY")
	)
	(segment
		(start 36.3728 -10.8458)
		(end 37.1602 -11.6332)
		(width 0.3048)
		(layer "F.Cu")
		(net "P3V3_STBY")
	)
	(segment
		(start 166.751 -22.6314)
		(end 164.3634 -22.6314)
		(width 0.3048)
		(layer "F.Cu")
		(net "P3V3_STBY")
	)
	(segment
		(start 59.8678 -24.3332)
		(end 60.0456 -24.1554)
		(width 0.3048)
		(layer "F.Cu")
		(net "P3V3_STBY")
	)
	(segment
		(start 163.2966 -42.530776)
		(end 163.2966 -41.636188)
		(width 0.3048)
		(layer "F.Cu")
		(net "P3V3_STBY")
	)
	(segment
		(start 168.840912 -50.656998)
		(end 169.550842 -50.656998)
		(width 0.508)
		(layer "F.Cu")
		(net "P3V3_STBY")
	)
	(segment
		(start 131.17195 -41.79443)
		(end 131.06273 -41.90365)
		(width 0.3048)
		(layer "F.Cu")
		(net "P3V3_STBY")
	)
	(segment
		(start 8.509 -49.149)
		(end 8.509 -49.8094)
		(width 0.254)
		(layer "F.Cu")
		(net "P3V3_STBY")
	)
	(segment
		(start 133.05282 -38.29431)
		(end 134.2136 -37.13353)
		(width 0.3048)
		(layer "F.Cu")
		(net "P3V3_STBY")
	)
	(segment
		(start 154.2796 -29.562044)
		(end 154.047444 -29.7942)
		(width 0.3048)
		(layer "F.Cu")
		(net "P3V3_STBY")
	)
	(segment
		(start 128.014984 -69.133974)
		(end 128.014984 -68.534026)
		(width 0.508)
		(layer "F.Cu")
		(net "P3V3_STBY")
	)
	(segment
		(start 178.2318 -57.0992)
		(end 177.7492 -57.5818)
		(width 0.508)
		(layer "F.Cu")
		(net "P3V3_STBY")
	)
	(segment
		(start 80.6704 -67.1322)
		(end 79.883 -66.3448)
		(width 0.3048)
		(layer "F.Cu")
		(net "P3V3_STBY")
	)
	(segment
		(start 161.036 -33.7058)
		(end 160.9598 -33.782)
		(width 0.3048)
		(layer "F.Cu")
		(net "P3V3_STBY")
	)
	(segment
		(start 61.331602 -14.49705)
		(end 62.646052 -15.8115)
		(width 0.3048)
		(layer "F.Cu")
		(net "P3V3_STBY")
	)
	(segment
		(start 113.284 -70.6882)
		(end 114.046 -70.6882)
		(width 0.3048)
		(layer "F.Cu")
		(net "P3V3_STBY")
	)
	(segment
		(start 63.6016 -45.075856)
		(end 62.891162 -44.365418)
		(width 0.3048)
		(layer "F.Cu")
		(net "P3V3_STBY")
	)
	(segment
		(start 202.946 -12.573)
		(end 204.224128 -13.851128)
		(width 0.3048)
		(layer "F.Cu")
		(net "P3V3_STBY")
	)
	(segment
		(start 62.891162 -44.365418)
		(end 62.889384 -44.365418)
		(width 0.3048)
		(layer "F.Cu")
		(net "P3V3_STBY")
	)
	(segment
		(start 169.550842 -50.656998)
		(end 170.550078 -51.656234)
		(width 0.508)
		(layer "F.Cu")
		(net "P3V3_STBY")
	)
	(segment
		(start 59.951874 -14.49705)
		(end 61.331602 -14.49705)
		(width 0.3048)
		(layer "F.Cu")
		(net "P3V3_STBY")
	)
	(segment
		(start 183.23052 -50.17135)
		(end 182.67807 -50.7238)
		(width 0.3048)
		(layer "F.Cu")
		(net "P3V3_STBY")
	)
	(segment
		(start 151.990552 -29.73578)
		(end 150.7236 -31.002732)
		(width 0.3048)
		(layer "F.Cu")
		(net "P3V3_STBY")
	)
	(segment
		(start 167.859202 -49.51095)
		(end 168.126156 -49.51095)
		(width 0.3048)
		(layer "F.Cu")
		(net "P3V3_STBY")
	)
	(segment
		(start 166.9796 -30.2514)
		(end 166.807896 -30.2514)
		(width 0.508)
		(layer "F.Cu")
		(net "P3V3_STBY")
	)
	(segment
		(start 142.512796 -48.038004)
		(end 142.598902 -48.038004)
		(width 0.3048)
		(layer "F.Cu")
		(net "P3V3_STBY")
	)
	(segment
		(start 26.543 -15.759684)
		(end 26.543 -19.822668)
		(width 0.3048)
		(layer "F.Cu")
		(net "P3V3_STBY")
	)
	(segment
		(start 36.6776 -49.784)
		(end 35.687 -49.784)
		(width 0.508)
		(layer "F.Cu")
		(net "P3V3_STBY")
	)
	(segment
		(start 138.879072 -19.743928)
		(end 140.4366 -21.301456)
		(width 0.3048)
		(layer "F.Cu")
		(net "P3V3_STBY")
	)
	(segment
		(start 129.921 -42.418)
		(end 129.921 -43.1038)
		(width 0.3048)
		(layer "F.Cu")
		(net "P3V3_STBY")
	)
	(segment
		(start 107.2896 -63.8048)
		(end 107.569 -63.8048)
		(width 0.3048)
		(layer "F.Cu")
		(net "P3V3_STBY")
	)
	(segment
		(start 150.7236 -31.002732)
		(end 150.7236 -32.004)
		(width 0.3048)
		(layer "F.Cu")
		(net "P3V3_STBY")
	)
	(segment
		(start 201.878946 -10.668)
		(end 202.946 -11.735054)
		(width 0.3048)
		(layer "F.Cu")
		(net "P3V3_STBY")
	)
	(segment
		(start 70.7263 -55.499)
		(end 70.7263 -55.0672)
		(width 0.3048)
		(layer "F.Cu")
		(net "P3V3_STBY")
	)
	(segment
		(start 101.0412 -67.5894)
		(end 101.0412 -66.8274)
		(width 0.3048)
		(layer "F.Cu")
		(net "P3V3_STBY")
	)
	(segment
		(start 162.6108 -41.402)
		(end 162.6108 -41.131744)
		(width 0.3048)
		(layer "F.Cu")
		(net "P3V3_STBY")
	)
	(segment
		(start 182.372 -34.7472)
		(end 182.3212 -34.798)
		(width 0.3048)
		(layer "F.Cu")
		(net "P3V3_STBY")
	)
	(segment
		(start 149.0472 -54.1528)
		(end 148.8059 -53.9115)
		(width 0.254)
		(layer "F.Cu")
		(net "P3V3_STBY")
	)
	(segment
		(start 105.918 -65.532)
		(end 105.918 -65.1764)
		(width 0.3048)
		(layer "F.Cu")
		(net "P3V3_STBY")
	)
	(segment
		(start 70.8152 -14.986)
		(end 70.8152 -15.748)
		(width 0.3048)
		(layer "F.Cu")
		(net "P3V3_STBY")
	)
	(segment
		(start 148.8059 -51.8541)
		(end 149.01037 -51.64963)
		(width 0.254)
		(layer "F.Cu")
		(net "P3V3_STBY")
	)
	(segment
		(start 13.716 -56.9722)
		(end 14.3256 -56.9722)
		(width 0.3048)
		(layer "F.Cu")
		(net "P3V3_STBY")
	)
	(segment
		(start 170.550078 -53.223922)
		(end 170.053 -53.721)
		(width 0.508)
		(layer "F.Cu")
		(net "P3V3_STBY")
	)
	(segment
		(start 143.99768 -23.9268)
		(end 143.99768 -22.83968)
		(width 0.3048)
		(layer "F.Cu")
		(net "P3V3_STBY")
	)
	(segment
		(start 190.149988 -3.764788)
		(end 190.149988 -1.68402)
		(width 0.3048)
		(layer "F.Cu")
		(net "P3V3_STBY")
	)
	(segment
		(start 41.87444 -43.363896)
		(end 41.41724 -42.906696)
		(width 0.3048)
		(layer "F.Cu")
		(net "P3V3_STBY")
	)
	(segment
		(start 167.4876 -50.345848)
		(end 167.4876 -49.882552)
		(width 0.3048)
		(layer "F.Cu")
		(net "P3V3_STBY")
	)
	(segment
		(start 41.41724 -42.906696)
		(end 41.41724 -41.99128)
		(width 0.3048)
		(layer "F.Cu")
		(net "P3V3_STBY")
	)
	(segment
		(start 142.598902 -48.038004)
		(end 143.256 -47.380906)
		(width 0.3048)
		(layer "F.Cu")
		(net "P3V3_STBY")
	)
	(segment
		(start 205.105 -21.0312)
		(end 205.105 -17.761966)
		(width 0.508)
		(layer "F.Cu")
		(net "P3V3_STBY")
	)
	(segment
		(start 158.209234 -27.7495)
		(end 158.680404 -27.27833)
		(width 0.3048)
		(layer "F.Cu")
		(net "P3V3_STBY")
	)
	(segment
		(start 59.8678 -25.146)
		(end 59.8678 -24.3332)
		(width 0.3048)
		(layer "F.Cu")
		(net "P3V3_STBY")
	)
	(segment
		(start 183.20004 -48.91024)
		(end 182.43296 -48.91024)
		(width 0.3048)
		(layer "F.Cu")
		(net "P3V3_STBY")
	)
	(segment
		(start 167.8432 -55.5498)
		(end 169.672 -53.721)
		(width 0.508)
		(layer "F.Cu")
		(net "P3V3_STBY")
	)
	(segment
		(start 189.04204 -48.91024)
		(end 189.103 -48.9712)
		(width 0.3048)
		(layer "F.Cu")
		(net "P3V3_STBY")
	)
	(segment
		(start 132.1308 -33.79343)
		(end 133.36397 -33.79343)
		(width 0.3048)
		(layer "F.Cu")
		(net "P3V3_STBY")
	)
	(segment
		(start 60.96 -23.241)
		(end 60.0456 -24.1554)
		(width 0.3048)
		(layer "F.Cu")
		(net "P3V3_STBY")
	)
	(segment
		(start 113.77676 -68.62572)
		(end 113.77676 -69.09816)
		(width 0.3048)
		(layer "F.Cu")
		(net "P3V3_STBY")
	)
	(segment
		(start 165.629844 -42.8752)
		(end 164.719 -42.8752)
		(width 0.3048)
		(layer "F.Cu")
		(net "P3V3_STBY")
	)
	(segment
		(start 137.9728 -19.177)
		(end 138.539728 -19.743928)
		(width 0.3048)
		(layer "F.Cu")
		(net "P3V3_STBY")
	)
	(segment
		(start 74.4474 -62.9158)
		(end 74.4474 -58.956956)
		(width 0.3048)
		(layer "F.Cu")
		(net "P3V3_STBY")
	)
	(segment
		(start 113.77676 -69.09816)
		(end 114.1476 -69.469)
		(width 0.3048)
		(layer "F.Cu")
		(net "P3V3_STBY")
	)
	(segment
		(start 74.4474 -58.956956)
		(end 76.279756 -57.1246)
		(width 0.3048)
		(layer "F.Cu")
		(net "P3V3_STBY")
	)
	(segment
		(start 138.99769 -46.350174)
		(end 139.281916 -46.6344)
		(width 0.3048)
		(layer "F.Cu")
		(net "P3V3_STBY")
	)
	(segment
		(start 35.687 -49.784)
		(end 35.56 -49.657)
		(width 0.508)
		(layer "F.Cu")
		(net "P3V3_STBY")
	)
	(segment
		(start 190.4746 -4.0894)
		(end 190.149988 -3.764788)
		(width 0.3048)
		(layer "F.Cu")
		(net "P3V3_STBY")
	)
	(segment
		(start 174.56404 -41.21404)
		(end 174.030894 -41.21404)
		(width 0.508)
		(layer "F.Cu")
		(net "P3V3_STBY")
	)
	(segment
		(start 142.629636 -57.750964)
		(end 142.543784 -57.750964)
		(width 0.3048)
		(layer "F.Cu")
		(net "P3V3_STBY")
	)
	(segment
		(start 29.46146 -11.05154)
		(end 31.56966 -11.05154)
		(width 0.3048)
		(layer "F.Cu")
		(net "P3V3_STBY")
	)
	(segment
		(start 146.0881 -55.03672)
		(end 145.466816 -55.03672)
		(width 0.3048)
		(layer "F.Cu")
		(net "P3V3_STBY")
	)
	(segment
		(start 26.045668 -20.32)
		(end 24.257 -20.32)
		(width 0.3048)
		(layer "F.Cu")
		(net "P3V3_STBY")
	)
	(segment
		(start 62.646052 -15.8115)
		(end 70.7517 -15.8115)
		(width 0.3048)
		(layer "F.Cu")
		(net "P3V3_STBY")
	)
	(segment
		(start 114.1476 -69.469)
		(end 114.1476 -69.5198)
		(width 0.3048)
		(layer "F.Cu")
		(net "P3V3_STBY")
	)
	(segment
		(start 168.6052 -50.7746)
		(end 168.6433 -50.7365)
		(width 0.508)
		(layer "F.Cu")
		(net "P3V3_STBY")
	)
	(segment
		(start 156.464 -27.7622)
		(end 156.464 -28.5242)
		(width 0.3048)
		(layer "F.Cu")
		(net "P3V3_STBY")
	)
	(segment
		(start 130.43535 -41.90365)
		(end 129.921 -42.418)
		(width 0.3048)
		(layer "F.Cu")
		(net "P3V3_STBY")
	)
	(segment
		(start 163.85159 -23.14321)
		(end 162.731958 -23.14321)
		(width 0.3048)
		(layer "F.Cu")
		(net "P3V3_STBY")
	)
	(segment
		(start 5.972048 -52.5526)
		(end 5.793994 -52.730654)
		(width 0.254)
		(layer "F.Cu")
		(net "P3V3_STBY")
	)
	(segment
		(start 182.3212 -35.5854)
		(end 182.3212 -34.798)
		(width 0.3048)
		(layer "F.Cu")
		(net "P3V3_STBY")
	)
	(segment
		(start 178.2318 -52.3748)
		(end 178.2318 -57.0992)
		(width 0.508)
		(layer "F.Cu")
		(net "P3V3_STBY")
	)
	(segment
		(start 75.9206 -64.3382)
		(end 75.8698 -64.3382)
		(width 0.3048)
		(layer "F.Cu")
		(net "P3V3_STBY")
	)
	(segment
		(start 177.7873 -49.3395)
		(end 178.2318 -48.895)
		(width 0.3048)
		(layer "F.Cu")
		(net "P3V3_STBY")
	)
	(segment
		(start 175.87087 -43.434)
		(end 175.387 -43.434)
		(width 0.508)
		(layer "F.Cu")
		(net "P3V3_STBY")
	)
	(segment
		(start 167.4876 -49.882552)
		(end 167.859202 -49.51095)
		(width 0.3048)
		(layer "F.Cu")
		(net "P3V3_STBY")
	)
	(segment
		(start 6.35 -52.5526)
		(end 5.972048 -52.5526)
		(width 0.254)
		(layer "F.Cu")
		(net "P3V3_STBY")
	)
	(segment
		(start 131.6228 -46.5836)
		(end 131.6228 -45.0342)
		(width 0.3048)
		(layer "F.Cu")
		(net "P3V3_STBY")
	)
	(segment
		(start 80.9244 -67.1322)
		(end 80.6704 -67.1322)
		(width 0.3048)
		(layer "F.Cu")
		(net "P3V3_STBY")
	)
	(segment
		(start 60.706 -24.8158)
		(end 60.0456 -24.1554)
		(width 0.3048)
		(layer "F.Cu")
		(net "P3V3_STBY")
	)
	(segment
		(start 141.0462 -54.3814)
		(end 141.0462 -53.6956)
		(width 0.3048)
		(layer "F.Cu")
		(net "P3V3_STBY")
	)
	(segment
		(start 190.5254 -4.0894)
		(end 190.4746 -4.0894)
		(width 0.3048)
		(layer "F.Cu")
		(net "P3V3_STBY")
	)
	(segment
		(start 5.864606 -48.999394)
		(end 5.864606 -48.471328)
		(width 0.254)
		(layer "F.Cu")
		(net "P3V3_STBY")
	)
	(segment
		(start 31.7754 -10.8458)
		(end 36.3728 -10.8458)
		(width 0.3048)
		(layer "F.Cu")
		(net "P3V3_STBY")
	)
	(segment
		(start 205.367128 -15.629128)
		(end 204.224128 -14.486128)
		(width 0.508)
		(layer "F.Cu")
		(net "P3V3_STBY")
	)
	(segment
		(start 143.99768 -22.83968)
		(end 143.7894 -22.6314)
		(width 0.3048)
		(layer "F.Cu")
		(net "P3V3_STBY")
	)
	(segment
		(start 37.1602 -12.4079)
		(end 36.283138 -13.284962)
		(width 0.3048)
		(layer "F.Cu")
		(net "P3V3_STBY")
	)
	(segment
		(start 67.698112 -26.383488)
		(end 67.698112 -32.261556)
		(width 0.3048)
		(layer "F.Cu")
		(net "P3V3_STBY")
	)
	(segment
		(start 176.911 -49.3395)
		(end 177.7873 -49.3395)
		(width 0.3048)
		(layer "F.Cu")
		(net "P3V3_STBY")
	)
	(segment
		(start 15.4178 -56.8452)
		(end 15.2654 -56.6928)
		(width 0.3048)
		(layer "F.Cu")
		(net "P3V3_STBY")
	)
	(segment
		(start 41.41724 -41.99128)
		(end 41.41724 -41.36644)
		(width 0.3048)
		(layer "F.Cu")
		(net "P3V3_STBY")
	)
	(segment
		(start 182.372 -33.9344)
		(end 182.372 -34.7472)
		(width 0.3048)
		(layer "F.Cu")
		(net "P3V3_STBY")
	)
	(segment
		(start 134.62 -19.2278)
		(end 134.62 -19.389344)
		(width 0.3048)
		(layer "F.Cu")
		(net "P3V3_STBY")
	)
	(segment
		(start 155.702 -28.5242)
		(end 155.301442 -28.5242)
		(width 0.3048)
		(layer "F.Cu")
		(net "P3V3_STBY")
	)
	(segment
		(start 62.770766 -44.2468)
		(end 62.889384 -44.365418)
		(width 0.3048)
		(layer "F.Cu")
		(net "P3V3_STBY")
	)
	(segment
		(start 177.7492 -57.5818)
		(end 177.165 -57.5818)
		(width 0.508)
		(layer "F.Cu")
		(net "P3V3_STBY")
	)
	(segment
		(start 47.1424 -22.2758)
		(end 47.117 -22.3012)
		(width 0.3048)
		(layer "F.Cu")
		(net "P3V3_STBY")
	)
	(segment
		(start 128.35001 -70.806564)
		(end 128.35001 -69.669406)
		(width 0.3048)
		(layer "F.Cu")
		(net "P3V3_STBY")
	)
	(segment
		(start 107.75696 -63.99276)
		(end 107.569 -63.8048)
		(width 0.3048)
		(layer "F.Cu")
		(net "P3V3_STBY")
	)
	(segment
		(start 5.793994 -52.730654)
		(end 5.331206 -52.730654)
		(width 0.254)
		(layer "F.Cu")
		(net "P3V3_STBY")
	)
	(segment
		(start 182.118 -49.2252)
		(end 182.118 -50.7238)
		(width 0.3048)
		(layer "F.Cu")
		(net "P3V3_STBY")
	)
	(segment
		(start 153.3652 -40.79367)
		(end 152.29967 -40.79367)
		(width 0.3048)
		(layer "F.Cu")
		(net "P3V3_STBY")
	)
	(segment
		(start 128.014984 -69.33438)
		(end 128.014984 -69.133974)
		(width 0.3048)
		(layer "F.Cu")
		(net "P3V3_STBY")
	)
	(segment
		(start 152.512268 -29.7942)
		(end 152.453848 -29.73578)
		(width 0.3048)
		(layer "F.Cu")
		(net "P3V3_STBY")
	)
	(segment
		(start 35.076638 -13.284962)
		(end 34.8488 -13.5128)
		(width 0.3048)
		(layer "F.Cu")
		(net "P3V3_STBY")
	)
	(segment
		(start 61.468 -44.2468)
		(end 62.770766 -44.2468)
		(width 0.3048)
		(layer "F.Cu")
		(net "P3V3_STBY")
	)
	(segment
		(start 188.13272 -48.91024)
		(end 189.04204 -48.91024)
		(width 0.3048)
		(layer "F.Cu")
		(net "P3V3_STBY")
	)
	(segment
		(start 158.611824 -28.829)
		(end 158.7754 -28.992576)
		(width 0.3048)
		(layer "F.Cu")
		(net "P3V3_STBY")
	)
	(segment
		(start 140.4366 -21.301456)
		(end 140.4366 -22.6314)
		(width 0.3048)
		(layer "F.Cu")
		(net "P3V3_STBY")
	)
	(segment
		(start 134.652004 -21.726398)
		(end 134.652004 -21.969222)
		(width 0.3048)
		(layer "F.Cu")
		(net "P3V3_STBY")
	)
	(segment
		(start 146.558 -22.2758)
		(end 146.9136 -22.6314)
		(width 0.3048)
		(layer "F.Cu")
		(net "P3V3_STBY")
	)
	(segment
		(start 166.024052 -42.480992)
		(end 165.629844 -42.8752)
		(width 0.3048)
		(layer "F.Cu")
		(net "P3V3_STBY")
	)
	(segment
		(start 133.35 -42.037)
		(end 133.10743 -41.79443)
		(width 0.3048)
		(layer "F.Cu")
		(net "P3V3_STBY")
	)
	(segment
		(start 91.0336 -13.6398)
		(end 90.6526 -13.2588)
		(width 0.3048)
		(layer "F.Cu")
		(net "P3V3_STBY")
	)
	(segment
		(start 81.026 -67.0306)
		(end 80.9244 -67.1322)
		(width 0.3048)
		(layer "F.Cu")
		(net "P3V3_STBY")
	)
	(segment
		(start 178.11623 -47.56277)
		(end 178.11623 -46.6852)
		(width 0.508)
		(layer "F.Cu")
		(net "P3V3_STBY")
	)
	(segment
		(start 91.948 -13.6398)
		(end 91.186 -13.6398)
		(width 0.3048)
		(layer "F.Cu")
		(net "P3V3_STBY")
	)
	(segment
		(start 168.76141 -50.7365)
		(end 168.840912 -50.656998)
		(width 0.508)
		(layer "F.Cu")
		(net "P3V3_STBY")
	)
	(segment
		(start 155.301442 -28.5242)
		(end 154.2796 -29.546042)
		(width 0.3048)
		(layer "F.Cu")
		(net "P3V3_STBY")
	)
	(segment
		(start 163.2966 -41.636188)
		(end 163.062412 -41.402)
		(width 0.3048)
		(layer "F.Cu")
		(net "P3V3_STBY")
	)
	(segment
		(start 180.975 -47.371)
		(end 180.975 -48.641)
		(width 0.3048)
		(layer "F.Cu")
		(net "P3V3_STBY")
	)
	(segment
		(start 5.003546 -52.402994)
		(end 5.003546 -51.536854)
		(width 0.254)
		(layer "F.Cu")
		(net "P3V3_STBY")
	)
	(segment
		(start 189.103 -49.3014)
		(end 189.103 -48.9712)
		(width 0.3048)
		(layer "F.Cu")
		(net "P3V3_STBY")
	)
	(segment
		(start 114.046 -69.6214)
		(end 114.1476 -69.5198)
		(width 0.3048)
		(layer "F.Cu")
		(net "P3V3_STBY")
	)
	(segment
		(start 110.0582 -69.7992)
		(end 109.2962 -70.5612)
		(width 0.3048)
		(layer "F.Cu")
		(net "P3V3_STBY")
	)
	(segment
		(start 156.464 -27.7622)
		(end 156.4767 -27.7495)
		(width 0.3048)
		(layer "F.Cu")
		(net "P3V3_STBY")
	)
	(segment
		(start 4.2926 -48.4632)
		(end 4.2926 -49.6824)
		(width 0.254)
		(layer "F.Cu")
		(net "P3V3_STBY")
	)
	(segment
		(start 158.680404 -27.27833)
		(end 158.680404 -28.085796)
		(width 0.508)
		(layer "F.Cu")
		(net "P3V3_STBY")
	)
	(segment
		(start 153.3652 -32.29356)
		(end 151.01316 -32.29356)
		(width 0.3048)
		(layer "F.Cu")
		(net "P3V3_STBY")
	)
	(segment
		(start 132.1308 -30.79369)
		(end 131.101338 -30.79369)
		(width 0.3048)
		(layer "F.Cu")
		(net "P3V3_STBY")
	)
	(segment
		(start 137.9728 -19.177)
		(end 137.9728 -18.415)
		(width 0.3048)
		(layer "F.Cu")
		(net "P3V3_STBY")
	)
	(segment
		(start 142.7226 -57.658)
		(end 142.629636 -57.750964)
		(width 0.3048)
		(layer "F.Cu")
		(net "P3V3_STBY")
	)
	(segment
		(start 178.11623 -45.67936)
		(end 175.87087 -43.434)
		(width 0.508)
		(layer "F.Cu")
		(net "P3V3_STBY")
	)
	(segment
		(start 128.35001 -69.669406)
		(end 128.014984 -69.33438)
		(width 0.3048)
		(layer "F.Cu")
		(net "P3V3_STBY")
	)
	(segment
		(start 60.706 -25.0952)
		(end 60.706 -24.8158)
		(width 0.3048)
		(layer "F.Cu")
		(net "P3V3_STBY")
	)
	(segment
		(start 127.7112 -33.02)
		(end 127.7112 -33.528)
		(width 0.3048)
		(layer "F.Cu")
		(net "P3V3_STBY")
	)
	(segment
		(start 125.222 -30.5308)
		(end 127.7112 -33.02)
		(width 0.3048)
		(layer "F.Cu")
		(net "P3V3_STBY")
	)
	(segment
		(start 91.948 -13.6398)
		(end 92.71 -13.6398)
		(width 0.3048)
		(layer "F.Cu")
		(net "P3V3_STBY")
	)
	(segment
		(start 59.431174 -15.01775)
		(end 59.951874 -14.49705)
		(width 0.3048)
		(layer "F.Cu")
		(net "P3V3_STBY")
	)
	(segment
		(start 3.6957 -47.5615)
		(end 3.6957 -44.0309)
		(width 0.254)
		(layer "F.Cu")
		(net "P3V3_STBY")
	)
	(segment
		(start 71.4502 -57.15)
		(end 71.4502 -56.388)
		(width 0.3048)
		(layer "F.Cu")
		(net "P3V3_STBY")
	)
	(segment
		(start 158.7754 -28.992576)
		(end 158.7754 -29.0576)
		(width 0.3048)
		(layer "F.Cu")
		(net "P3V3_STBY")
	)
	(segment
		(start 9.8806 -47.7774)
		(end 8.509 -49.149)
		(width 0.254)
		(layer "F.Cu")
		(net "P3V3_STBY")
	)
	(segment
		(start 153.3652 -36.29406)
		(end 154.047444 -36.29406)
		(width 0.3048)
		(layer "F.Cu")
		(net "P3V3_STBY")
	)
	(segment
		(start 180.975 -48.641)
		(end 181.5592 -49.2252)
		(width 0.3048)
		(layer "F.Cu")
		(net "P3V3_STBY")
	)
	(segment
		(start 142.37462 -57.5818)
		(end 142.543784 -57.750964)
		(width 0.3048)
		(layer "F.Cu")
		(net "P3V3_STBY")
	)
	(segment
		(start 105.918 -65.1764)
		(end 107.2896 -63.8048)
		(width 0.3048)
		(layer "F.Cu")
		(net "P3V3_STBY")
	)
	(segment
		(start 68.3768 -24.0538)
		(end 68.3768 -25.7048)
		(width 0.3048)
		(layer "F.Cu")
		(net "P3V3_STBY")
	)
	(segment
		(start 158.7754 -29.0576)
		(end 159.4104 -29.6926)
		(width 0.3048)
		(layer "F.Cu")
		(net "P3V3_STBY")
	)
	(segment
		(start 166.807896 -30.2514)
		(end 166.0144 -31.044896)
		(width 0.508)
		(layer "F.Cu")
		(net "P3V3_STBY")
	)
	(segment
		(start 154.5082 -36.754816)
		(end 154.5082 -36.80206)
		(width 0.3048)
		(layer "F.Cu")
		(net "P3V3_STBY")
	)
	(segment
		(start 202.946 -11.735054)
		(end 202.946 -12.573)
		(width 0.3048)
		(layer "F.Cu")
		(net "P3V3_STBY")
	)
	(segment
		(start 174.117 -57.5818)
		(end 174.879 -57.5818)
		(width 0.3048)
		(layer "F.Cu")
		(net "P3V3_STBY")
	)
	(segment
		(start 176.911 -49.3395)
		(end 176.911 -48.768)
		(width 0.508)
		(layer "F.Cu")
		(net "P3V3_STBY")
	)
	(segment
		(start 62.3062 -23.241)
		(end 60.96 -23.241)
		(width 0.3048)
		(layer "F.Cu")
		(net "P3V3_STBY")
	)
	(segment
		(start 24.257 -20.32)
		(end 23.241 -21.336)
		(width 0.3048)
		(layer "F.Cu")
		(net "P3V3_STBY")
	)
	(segment
		(start 164.719 -39.023544)
		(end 164.719 -36.576)
		(width 0.3048)
		(layer "F.Cu")
		(net "P3V3_STBY")
	)
	(segment
		(start 134.61365 -21.688044)
		(end 134.652004 -21.726398)
		(width 0.3048)
		(layer "F.Cu")
		(net "P3V3_STBY")
	)
	(segment
		(start 174.056294 -43.652694)
		(end 174.3456 -43.942)
		(width 0.508)
		(layer "F.Cu")
		(net "P3V3_STBY")
	)
	(segment
		(start 81.026 -66.3448)
		(end 81.026 -67.0306)
		(width 0.3048)
		(layer "F.Cu")
		(net "P3V3_STBY")
	)
	(segment
		(start 170.053 -53.721)
		(end 169.672 -53.721)
		(width 0.508)
		(layer "F.Cu")
		(net "P3V3_STBY")
	)
	(segment
		(start 5.461 -49.403)
		(end 5.864606 -48.999394)
		(width 0.254)
		(layer "F.Cu")
		(net "P3V3_STBY")
	)
	(segment
		(start 142.2908 -48.26)
		(end 142.512796 -48.038004)
		(width 0.3048)
		(layer "F.Cu")
		(net "P3V3_STBY")
	)
	(segment
		(start 175.387 -42.037)
		(end 174.56404 -41.21404)
		(width 0.508)
		(layer "F.Cu")
		(net "P3V3_STBY")
	)
	(segment
		(start 175.387 -43.434)
		(end 175.387 -42.037)
		(width 0.508)
		(layer "F.Cu")
		(net "P3V3_STBY")
	)
	(segment
		(start 159.4104 -31.2674)
		(end 160.0708 -31.9278)
		(width 0.3048)
		(layer "F.Cu")
		(net "P3V3_STBY")
	)
	(segment
		(start 204.224128 -13.851128)
		(end 204.224128 -14.486128)
		(width 0.3048)
		(layer "F.Cu")
		(net "P3V3_STBY")
	)
	(segment
		(start 205.105 -17.761966)
		(end 205.367128 -17.499838)
		(width 0.508)
		(layer "F.Cu")
		(net "P3V3_STBY")
	)
	(segment
		(start 28.829 -13.7668)
		(end 28.5242 -13.462)
		(width 0.3048)
		(layer "F.Cu")
		(net "P3V3_STBY")
	)
	(segment
		(start 199.263 -6.35)
		(end 199.745854 -6.832854)
		(width 0.3048)
		(layer "F.Cu")
		(net "P3V3_STBY")
	)
	(segment
		(start 163.83 -42.8498)
		(end 163.615624 -42.8498)
		(width 0.3048)
		(layer "F.Cu")
		(net "P3V3_STBY")
	)
	(segment
		(start 31.56966 -11.05154)
		(end 31.7754 -10.8458)
		(width 0.3048)
		(layer "F.Cu")
		(net "P3V3_STBY")
	)
	(segment
		(start 168.402 -49.1998)
		(end 168.7068 -48.895)
		(width 0.3048)
		(layer "F.Cu")
		(net "P3V3_STBY")
	)
	(segment
		(start 182.67807 -50.7238)
		(end 182.118 -50.7238)
		(width 0.3048)
		(layer "F.Cu")
		(net "P3V3_STBY")
	)
	(segment
		(start 198.5518 -6.35)
		(end 199.263 -6.35)
		(width 0.3048)
		(layer "F.Cu")
		(net "P3V3_STBY")
	)
	(segment
		(start 164.3634 -42.8752)
		(end 164.719 -42.8752)
		(width 0.3048)
		(layer "F.Cu")
		(net "P3V3_STBY")
	)
	(segment
		(start 134.652004 -21.969222)
		(end 135.449818 -22.767036)
		(width 0.3048)
		(layer "F.Cu")
		(net "P3V3_STBY")
	)
	(segment
		(start 144.03324 -54.39664)
		(end 142.9766 -53.34)
		(width 0.3048)
		(layer "F.Cu")
		(net "P3V3_STBY")
	)
	(segment
		(start 92.71 -13.6398)
		(end 93.472 -13.6398)
		(width 0.3048)
		(layer "F.Cu")
		(net "P3V3_STBY")
	)
	(segment
		(start 150.4188 -38.9128)
		(end 150.4188 -36.83)
		(width 0.3048)
		(layer "F.Cu")
		(net "P3V3_STBY")
	)
	(segment
		(start 28.194 -13.196824)
		(end 28.194 -12.319)
		(width 0.3048)
		(layer "F.Cu")
		(net "P3V3_STBY")
	)
	(segment
		(start 164.719 -35.814)
		(end 164.719 -36.576)
		(width 0.508)
		(layer "F.Cu")
		(net "P3V3_STBY")
	)
	(segment
		(start 168.126156 -49.51095)
		(end 168.402 -49.235106)
		(width 0.3048)
		(layer "F.Cu")
		(net "P3V3_STBY")
	)
	(segment
		(start 151.01316 -32.29356)
		(end 150.7236 -32.004)
		(width 0.3048)
		(layer "F.Cu")
		(net "P3V3_STBY")
	)
	(segment
		(start 114.046 -70.6882)
		(end 114.046 -69.6214)
		(width 0.3048)
		(layer "F.Cu")
		(net "P3V3_STBY")
	)
	(segment
		(start 138.539728 -19.743928)
		(end 138.879072 -19.743928)
		(width 0.3048)
		(layer "F.Cu")
		(net "P3V3_STBY")
	)
	(segment
		(start 143.357092 -46.482508)
		(end 143.49857 -46.34103)
		(width 0.3048)
		(layer "F.Cu")
		(net "P3V3_STBY")
	)
	(segment
		(start 134.1374 -33.02)
		(end 134.1374 -30.353)
		(width 0.3048)
		(layer "F.Cu")
		(net "P3V3_STBY")
	)
	(segment
		(start 154.047444 -36.29406)
		(end 154.5082 -36.754816)
		(width 0.3048)
		(layer "F.Cu")
		(net "P3V3_STBY")
	)
	(segment
		(start 90.6526 -13.2588)
		(end 85.09635 -13.2588)
		(width 0.3048)
		(layer "F.Cu")
		(net "P3V3_STBY")
	)
	(segment
		(start 158.680404 -28.085796)
		(end 158.242 -28.5242)
		(width 0.508)
		(layer "F.Cu")
		(net "P3V3_STBY")
	)
	(segment
		(start 4.572 -49.9618)
		(end 5.1308 -49.403)
		(width 0.254)
		(layer "F.Cu")
		(net "P3V3_STBY")
	)
	(segment
		(start 132.1308 -41.79443)
		(end 131.17195 -41.79443)
		(width 0.3048)
		(layer "F.Cu")
		(net "P3V3_STBY")
	)
	(segment
		(start 178.82743 -45.974)
		(end 179.578 -45.974)
		(width 0.3048)
		(layer "F.Cu")
		(net "P3V3_STBY")
	)
	(segment
		(start 182.6006 -23.876)
		(end 182.6006 -22.86)
		(width 0.508)
		(layer "F.Cu")
		(net "P3V3_STBY")
	)
	(segment
		(start 143.891 -22.098)
		(end 143.764 -22.225)
		(width 0.3048)
		(layer "F.Cu")
		(net "P3V3_STBY")
	)
	(segment
		(start 158.242 -28.5242)
		(end 158.5468 -28.829)
		(width 0.3048)
		(layer "F.Cu")
		(net "P3V3_STBY")
	)
	(segment
		(start 28.829 -13.7668)
		(end 28.535884 -13.7668)
		(width 0.3048)
		(layer "F.Cu")
		(net "P3V3_STBY")
	)
	(segment
		(start 143.49857 -46.34103)
		(end 143.49857 -45.1612)
		(width 0.3048)
		(layer "F.Cu")
		(net "P3V3_STBY")
	)
	(segment
		(start 176.774094 -59.0296)
		(end 177.165 -58.638694)
		(width 0.3048)
		(layer "F.Cu")
		(net "P3V3_STBY")
	)
	(segment
		(start 160.9598 -33.782)
		(end 160.0708 -33.782)
		(width 0.3048)
		(layer "F.Cu")
		(net "P3V3_STBY")
	)
	(segment
		(start 133.10743 -41.79443)
		(end 132.1308 -41.79443)
		(width 0.3048)
		(layer "F.Cu")
		(net "P3V3_STBY")
	)
	(segment
		(start 134.62 -19.389344)
		(end 134.61365 -19.395694)
		(width 0.3048)
		(layer "F.Cu")
		(net "P3V3_STBY")
	)
	(segment
		(start 174.030894 -43.652694)
		(end 174.056294 -43.652694)
		(width 0.508)
		(layer "F.Cu")
		(net "P3V3_STBY")
	)
	(segment
		(start 134.2136 -37.13353)
		(end 134.2136 -36.840414)
		(width 0.3048)
		(layer "F.Cu")
		(net "P3V3_STBY")
	)
	(segment
		(start 143.764 -22.225)
		(end 143.764 -22.6314)
		(width 0.3048)
		(layer "F.Cu")
		(net "P3V3_STBY")
	)
	(segment
		(start 162.6108 -41.131744)
		(end 164.719 -39.023544)
		(width 0.3048)
		(layer "F.Cu")
		(net "P3V3_STBY")
	)
	(segment
		(start 152.29967 -40.79367)
		(end 150.4188 -38.9128)
		(width 0.3048)
		(layer "F.Cu")
		(net "P3V3_STBY")
	)
	(segment
		(start 178.11623 -46.6852)
		(end 178.82743 -45.974)
		(width 0.3048)
		(layer "F.Cu")
		(net "P3V3_STBY")
	)
	(segment
		(start 76.54163 -63.71717)
		(end 75.9206 -64.3382)
		(width 0.3048)
		(layer "F.Cu")
		(net "P3V3_STBY")
	)
	(segment
		(start 15.2654 -56.6928)
		(end 14.605 -56.6928)
		(width 0.3048)
		(layer "F.Cu")
		(net "P3V3_STBY")
	)
	(segment
		(start 167.916352 -50.7746)
		(end 167.4876 -50.345848)
		(width 0.3048)
		(layer "F.Cu")
		(net "P3V3_STBY")
	)
	(segment
		(start 145.466816 -55.03672)
		(end 144.826736 -54.39664)
		(width 0.3048)
		(layer "F.Cu")
		(net "P3V3_STBY")
	)
	(segment
		(start 164.3634 -22.6314)
		(end 163.85159 -23.14321)
		(width 0.3048)
		(layer "F.Cu")
		(net "P3V3_STBY")
	)
	(segment
		(start 4.572 -49.9872)
		(end 5.5626 -50.9778)
		(width 0.254)
		(layer "F.Cu")
		(net "P3V3_STBY")
	)
	(segment
		(start 143.4338 -57.658)
		(end 142.7226 -57.658)
		(width 0.3048)
		(layer "F.Cu")
		(net "P3V3_STBY")
	)
	(segment
		(start 5.003546 -51.536854)
		(end 5.5626 -50.9778)
		(width 0.254)
		(layer "F.Cu")
		(net "P3V3_STBY")
	)
	(segment
		(start 63.6016 -45.8216)
		(end 63.6016 -45.075856)
		(width 0.3048)
		(layer "F.Cu")
		(net "P3V3_STBY")
	)
	(segment
		(start 168.6052 -50.7746)
		(end 167.916352 -50.7746)
		(width 0.3048)
		(layer "F.Cu")
		(net "P3V3_STBY")
	)
	(segment
		(start 28.5242 -13.462)
		(end 28.459176 -13.462)
		(width 0.3048)
		(layer "F.Cu")
		(net "P3V3_STBY")
	)
	(segment
		(start 3.6957 -44.0309)
		(end 4.7244 -43.0022)
		(width 0.254)
		(layer "F.Cu")
		(net "P3V3_STBY")
	)
	(segment
		(start 181.5592 -49.2252)
		(end 182.118 -49.2252)
		(width 0.3048)
		(layer "F.Cu")
		(net "P3V3_STBY")
	)
	(segment
		(start 12.4968 -63.6016)
		(end 11.2776 -63.6016)
		(width 0.508)
		(layer "F.Cu")
		(net "P3V3_STBY")
	)
	(segment
		(start 166.37 -55.5498)
		(end 166.1922 -55.372)
		(width 0.508)
		(layer "F.Cu")
		(net "P3V3_STBY")
	)
	(segment
		(start 198.5518 -5.588)
		(end 198.5518 -6.35)
		(width 0.3048)
		(layer "F.Cu")
		(net "P3V3_STBY")
	)
	(segment
		(start 137.9982 -23.9268)
		(end 137.9982 -22.7965)
		(width 0.3048)
		(layer "F.Cu")
		(net "P3V3_STBY")
	)
	(segment
		(start 133.35 -43.307)
		(end 133.35 -42.037)
		(width 0.3048)
		(layer "F.Cu")
		(net "P3V3_STBY")
	)
	(segment
		(start 154.047444 -29.7942)
		(end 153.3652 -29.7942)
		(width 0.3048)
		(layer "F.Cu")
		(net "P3V3_STBY")
	)
	(segment
		(start 71.4502 -56.2229)
		(end 70.7263 -55.499)
		(width 0.3048)
		(layer "F.Cu")
		(net "P3V3_STBY")
	)
	(segment
		(start 75.8698 -64.3382)
		(end 74.4474 -62.9158)
		(width 0.3048)
		(layer "F.Cu")
		(net "P3V3_STBY")
	)
	(segment
		(start 201.473054 -10.668)
		(end 201.878946 -10.668)
		(width 0.3048)
		(layer "F.Cu")
		(net "P3V3_STBY")
	)
	(segment
		(start 142.9766 -53.34)
		(end 141.8082 -53.34)
		(width 0.3048)
		(layer "F.Cu")
		(net "P3V3_STBY")
	)
	(segment
		(start 205.367128 -17.499838)
		(end 205.367128 -15.629128)
		(width 0.508)
		(layer "F.Cu")
		(net "P3V3_STBY")
	)
	(segment
		(start 199.745854 -8.9408)
		(end 201.473054 -10.668)
		(width 0.3048)
		(layer "F.Cu")
		(net "P3V3_STBY")
	)
	(segment
		(start 167.005 -55.5498)
		(end 167.8432 -55.5498)
		(width 0.508)
		(layer "F.Cu")
		(net "P3V3_STBY")
	)
	(segment
		(start 37.1602 -11.6332)
		(end 37.1602 -12.4079)
		(width 0.3048)
		(layer "F.Cu")
		(net "P3V3_STBY")
	)
	(segment
		(start 141.7066 -57.5818)
		(end 142.37462 -57.5818)
		(width 0.3048)
		(layer "F.Cu")
		(net "P3V3_STBY")
	)
	(segment
		(start 131.101338 -30.79369)
		(end 131.041648 -30.85338)
		(width 0.3048)
		(layer "F.Cu")
		(net "P3V3_STBY")
	)
	(segment
		(start 174.030894 -43.11396)
		(end 174.030894 -43.652694)
		(width 0.508)
		(layer "F.Cu")
		(net "P3V3_STBY")
	)
	(segment
		(start 41.87444 -44.69384)
		(end 41.87444 -43.363896)
		(width 0.3048)
		(layer "F.Cu")
		(net "P3V3_STBY")
	)
	(segment
		(start 9.8806 -47.498)
		(end 9.8806 -47.7774)
		(width 0.254)
		(layer "F.Cu")
		(net "P3V3_STBY")
	)
	(segment
		(start 178.11623 -46.6852)
		(end 178.11623 -45.67936)
		(width 0.508)
		(layer "F.Cu")
		(net "P3V3_STBY")
	)
	(segment
		(start 131.6228 -45.0342)
		(end 133.35 -43.307)
		(width 0.3048)
		(layer "F.Cu")
		(net "P3V3_STBY")
	)
	(segment
		(start 167.2336 -23.114)
		(end 166.751 -22.6314)
		(width 0.3048)
		(layer "F.Cu")
		(net "P3V3_STBY")
	)
	(segment
		(start 41.41724 -41.36644)
		(end 41.1226 -41.0718)
		(width 0.3048)
		(layer "F.Cu")
		(net "P3V3_STBY")
	)
	(segment
		(start 163.83 -42.8498)
		(end 164.338 -42.8498)
		(width 0.3048)
		(layer "F.Cu")
		(net "P3V3_STBY")
	)
	(segment
		(start 85.09635 -13.2588)
		(end 84.1502 -12.31265)
		(width 0.3048)
		(layer "F.Cu")
		(net "P3V3_STBY")
	)
	(segment
		(start 110.0582 -69.6214)
		(end 110.0582 -69.7992)
		(width 0.3048)
		(layer "F.Cu")
		(net "P3V3_STBY")
	)
	(segment
		(start 131.041648 -30.85338)
		(end 130.42138 -30.85338)
		(width 0.3048)
		(layer "F.Cu")
		(net "P3V3_STBY")
	)
	(segment
		(start 164.338 -42.8498)
		(end 164.3634 -42.8752)
		(width 0.3048)
		(layer "F.Cu")
		(net "P3V3_STBY")
	)
	(segment
		(start 68.3768 -25.7048)
		(end 67.698112 -26.383488)
		(width 0.3048)
		(layer "F.Cu")
		(net "P3V3_STBY")
	)
	(segment
		(start 152.453848 -29.73578)
		(end 151.990552 -29.73578)
		(width 0.3048)
		(layer "F.Cu")
		(net "P3V3_STBY")
	)
	(segment
		(start 176.911 -48.768)
		(end 178.11623 -47.56277)
		(width 0.508)
		(layer "F.Cu")
		(net "P3V3_STBY")
	)
	(segment
		(start 181.5846 -33.5026)
		(end 182.0164 -33.9344)
		(width 0.3048)
		(layer "F.Cu")
		(net "P3V3_STBY")
	)
	(segment
		(start 168.402 -49.235106)
		(end 168.402 -49.1998)
		(width 0.3048)
		(layer "F.Cu")
		(net "P3V3_STBY")
	)
	(segment
		(start 166.0144 -31.044896)
		(end 166.0144 -31.0896)
		(width 0.508)
		(layer "F.Cu")
		(net "P3V3_STBY")
	)
	(segment
		(start 59.8678 -25.908)
		(end 59.8678 -25.146)
		(width 0.3048)
		(layer "F.Cu")
		(net "P3V3_STBY")
	)
	(segment
		(start 4.445 -48.3108)
		(end 3.6957 -47.5615)
		(width 0.254)
		(layer "F.Cu")
		(net "P3V3_STBY")
	)
	(segment
		(start 131.06273 -41.90365)
		(end 130.43535 -41.90365)
		(width 0.3048)
		(layer "F.Cu")
		(net "P3V3_STBY")
	)
	(segment
		(start 101.8286 -69.342)
		(end 101.8286 -67.9196)
		(width 0.3048)
		(layer "F.Cu")
		(net "P3V3_STBY")
	)
	(segment
		(start 160.0708 -31.9278)
		(end 160.0708 -33.782)
		(width 0.3048)
		(layer "F.Cu")
		(net "P3V3_STBY")
	)
	(segment
		(start 168.6433 -50.7365)
		(end 168.76141 -50.7365)
		(width 0.508)
		(layer "F.Cu")
		(net "P3V3_STBY")
	)
	(segment
		(start 4.2926 -49.6824)
		(end 4.572 -49.9618)
		(width 0.254)
		(layer "F.Cu")
		(net "P3V3_STBY")
	)
	(segment
		(start 176.911 -49.3395)
		(end 176.911 -51.054)
		(width 0.508)
		(layer "F.Cu")
		(net "P3V3_STBY")
	)
	(segment
		(start 26.543 -19.822668)
		(end 26.045668 -20.32)
		(width 0.3048)
		(layer "F.Cu")
		(net "P3V3_STBY")
	)
	(segment
		(start 141.49832 -57.79008)
		(end 141.7066 -57.5818)
		(width 0.3048)
		(layer "F.Cu")
		(net "P3V3_STBY")
	)
	(segment
		(start 28.194 -12.319)
		(end 29.46146 -11.05154)
		(width 0.3048)
		(layer "F.Cu")
		(net "P3V3_STBY")
	)
	(segment
		(start 138.99769 -45.1612)
		(end 138.99769 -46.350174)
		(width 0.3048)
		(layer "F.Cu")
		(net "P3V3_STBY")
	)
	(segment
		(start 134.61365 -19.395694)
		(end 134.61365 -21.688044)
		(width 0.3048)
		(layer "F.Cu")
		(net "P3V3_STBY")
	)
	(segment
		(start 71.4502 -56.388)
		(end 71.4502 -56.2229)
		(width 0.3048)
		(layer "F.Cu")
		(net "P3V3_STBY")
	)
	(segment
		(start 170.550078 -51.656234)
		(end 170.550078 -53.223922)
		(width 0.508)
		(layer "F.Cu")
		(net "P3V3_STBY")
	)
	(segment
		(start 182.372 -35.6362)
		(end 182.3212 -35.5854)
		(width 0.3048)
		(layer "F.Cu")
		(net "P3V3_STBY")
	)
	(segment
		(start 36.283138 -13.284962)
		(end 35.076638 -13.284962)
		(width 0.3048)
		(layer "F.Cu")
		(net "P3V3_STBY")
	)
	(segment
		(start 4.572 -49.9618)
		(end 4.572 -49.9872)
		(width 0.254)
		(layer "F.Cu")
		(net "P3V3_STBY")
	)
	(segment
		(start 28.535884 -13.7668)
		(end 26.543 -15.759684)
		(width 0.3048)
		(layer "F.Cu")
		(net "P3V3_STBY")
	)
	(segment
		(start 67.698112 -32.261556)
		(end 68.3006 -32.864044)
		(width 0.3048)
		(layer "F.Cu")
		(net "P3V3_STBY")
	)
	(segment
		(start 141.49832 -58.669428)
		(end 141.49832 -57.79008)
		(width 0.3048)
		(layer "F.Cu")
		(net "P3V3_STBY")
	)
	(segment
		(start 5.1308 -49.403)
		(end 5.461 -49.403)
		(width 0.254)
		(layer "F.Cu")
		(net "P3V3_STBY")
	)
	(segment
		(start 143.256 -47.380906)
		(end 143.256 -46.705266)
		(width 0.3048)
		(layer "F.Cu")
		(net "P3V3_STBY")
	)
	(segment
		(start 101.4984 -67.5894)
		(end 101.0412 -67.5894)
		(width 0.3048)
		(layer "F.Cu")
		(net "P3V3_STBY")
	)
	(segment
		(start 141.4526 -53.6956)
		(end 141.8082 -53.34)
		(width 0.3048)
		(layer "F.Cu")
		(net "P3V3_STBY")
	)
	(segment
		(start 141.0462 -53.6956)
		(end 141.4526 -53.6956)
		(width 0.3048)
		(layer "F.Cu")
		(net "P3V3_STBY")
	)
	(segment
		(start 163.062412 -41.402)
		(end 162.6108 -41.402)
		(width 0.3048)
		(layer "F.Cu")
		(net "P3V3_STBY")
	)
	(via
		(at 110.0582 -69.6214)
		(size 0.508)
		(drill 0.254)
		(layers "F.Cu" "B.Cu")
		(net "P3V3_STBY")
	)
	(via
		(at 87.2744 -68.707)
		(size 0.7112)
		(drill 0.4064)
		(layers "F.Cu" "B.Cu")
		(net "P3V3_STBY")
	)
	(via
		(at 77.3176 -22.4536)
		(size 0.508)
		(drill 0.254)
		(layers "F.Cu" "B.Cu")
		(net "P3V3_STBY")
	)
	(via
		(at 129.921 -30.353)
		(size 0.508)
		(drill 0.254)
		(layers "F.Cu" "B.Cu")
		(net "P3V3_STBY")
	)
	(via
		(at 14.605 -56.6928)
		(size 0.508)
		(drill 0.254)
		(layers "F.Cu" "B.Cu")
		(net "P3V3_STBY")
	)
	(via
		(at 80.9244 -67.1322)
		(size 0.508)
		(drill 0.254)
		(layers "F.Cu" "B.Cu")
		(net "P3V3_STBY")
	)
	(via
		(at 42.1386 -46.101)
		(size 0.508)
		(drill 0.254)
		(layers "F.Cu" "B.Cu")
		(net "P3V3_STBY")
	)
	(via
		(at 23.241 -21.336)
		(size 0.508)
		(drill 0.254)
		(layers "F.Cu" "B.Cu")
		(net "P3V3_STBY")
	)
	(via
		(at 135.449818 -22.767036)
		(size 0.508)
		(drill 0.254)
		(layers "F.Cu" "B.Cu")
		(net "P3V3_STBY")
	)
	(via
		(at 75.9206 -64.3382)
		(size 0.508)
		(drill 0.254)
		(layers "F.Cu" "B.Cu")
		(net "P3V3_STBY")
	)
	(via
		(at 11.2776 -63.6016)
		(size 0.508)
		(drill 0.254)
		(layers "F.Cu" "B.Cu")
		(net "P3V3_STBY")
	)
	(via
		(at 28.7528 -37.2618)
		(size 0.7112)
		(drill 0.4064)
		(layers "F.Cu" "B.Cu")
		(net "P3V3_STBY")
	)
	(via
		(at 131.6228 -46.5836)
		(size 0.508)
		(drill 0.254)
		(layers "F.Cu" "B.Cu")
		(net "P3V3_STBY")
	)
	(via
		(at 71.526146 -66.496946)
		(size 0.508)
		(drill 0.254)
		(layers "F.Cu" "B.Cu")
		(net "P3V3_STBY")
	)
	(via
		(at 52.07 -52.451)
		(size 0.508)
		(drill 0.254)
		(layers "F.Cu" "B.Cu")
		(net "P3V3_STBY")
	)
	(via
		(at 149.0472 -54.1528)
		(size 0.508)
		(drill 0.254)
		(layers "F.Cu" "B.Cu")
		(net "P3V3_STBY")
	)
	(via
		(at 162.731958 -23.14321)
		(size 0.508)
		(drill 0.254)
		(layers "F.Cu" "B.Cu")
		(net "P3V3_STBY")
	)
	(via
		(at 150.4188 -36.83)
		(size 0.508)
		(drill 0.254)
		(layers "F.Cu" "B.Cu")
		(net "P3V3_STBY")
	)
	(via
		(at 119.913654 -67.58686)
		(size 0.508)
		(drill 0.254)
		(layers "F.Cu" "B.Cu")
		(net "P3V3_STBY")
	)
	(via
		(at 161.29 -28.067)
		(size 0.508)
		(drill 0.254)
		(layers "F.Cu" "B.Cu")
		(net "P3V3_STBY")
	)
	(via
		(at 139.281916 -46.6344)
		(size 0.508)
		(drill 0.254)
		(layers "F.Cu" "B.Cu")
		(net "P3V3_STBY")
	)
	(via
		(at 60.0456 -24.1554)
		(size 0.7112)
		(drill 0.4064)
		(layers "F.Cu" "B.Cu")
		(net "P3V3_STBY")
	)
	(via
		(at 177.546 -41.21277)
		(size 0.5588)
		(drill 0.3048)
		(layers "F.Cu" "B.Cu")
		(net "P3V3_STBY")
	)
	(via
		(at 48.895 -41.1226)
		(size 0.7112)
		(drill 0.4064)
		(layers "F.Cu" "B.Cu")
		(net "P3V3_STBY")
	)
	(via
		(at 181.5846 -33.5026)
		(size 0.508)
		(drill 0.254)
		(layers "F.Cu" "B.Cu")
		(net "P3V3_STBY")
	)
	(via
		(at 168.6052 -50.7746)
		(size 0.508)
		(drill 0.254)
		(layers "F.Cu" "B.Cu")
		(net "P3V3_STBY")
	)
	(via
		(at 125.222 -30.301946)
		(size 0.508)
		(drill 0.254)
		(layers "F.Cu" "B.Cu")
		(net "P3V3_STBY")
	)
	(via
		(at 84.1502 -12.31265)
		(size 0.508)
		(drill 0.254)
		(layers "F.Cu" "B.Cu")
		(net "P3V3_STBY")
	)
	(via
		(at 158.680404 -27.27833)
		(size 0.508)
		(drill 0.254)
		(layers "F.Cu" "B.Cu")
		(net "P3V3_STBY")
	)
	(via
		(at 75.4761 -23.1394)
		(size 0.508)
		(drill 0.254)
		(layers "F.Cu" "B.Cu")
		(net "P3V3_STBY")
	)
	(via
		(at 150.7236 -32.004)
		(size 0.508)
		(drill 0.254)
		(layers "F.Cu" "B.Cu")
		(net "P3V3_STBY")
	)
	(via
		(at 84.963 -67.6402)
		(size 0.7112)
		(drill 0.4064)
		(layers "F.Cu" "B.Cu")
		(net "P3V3_STBY")
	)
	(via
		(at 29.1338 -40.3352)
		(size 0.7112)
		(drill 0.4064)
		(layers "F.Cu" "B.Cu")
		(net "P3V3_STBY")
	)
	(via
		(at 141.8082 -53.34)
		(size 0.508)
		(drill 0.254)
		(layers "F.Cu" "B.Cu")
		(net "P3V3_STBY")
	)
	(via
		(at 109.22 -5.461)
		(size 0.508)
		(drill 0.254)
		(layers "F.Cu" "B.Cu")
		(net "P3V3_STBY")
	)
	(via
		(at 74.8792 -23.9014)
		(size 0.7112)
		(drill 0.4064)
		(layers "F.Cu" "B.Cu")
		(net "P3V3_STBY")
	)
	(via
		(at 84.9122 -68.707)
		(size 0.7112)
		(drill 0.4064)
		(layers "F.Cu" "B.Cu")
		(net "P3V3_STBY")
	)
	(via
		(at 164.719 -36.576)
		(size 0.508)
		(drill 0.254)
		(layers "F.Cu" "B.Cu")
		(net "P3V3_STBY")
	)
	(via
		(at 188.7474 -49.657)
		(size 0.508)
		(drill 0.254)
		(layers "F.Cu" "B.Cu")
		(net "P3V3_STBY")
	)
	(via
		(at 178.11623 -46.6852)
		(size 0.508)
		(drill 0.254)
		(layers "F.Cu" "B.Cu")
		(net "P3V3_STBY")
	)
	(via
		(at 18.7706 -35.179)
		(size 0.7112)
		(drill 0.3556)
		(layers "F.Cu" "B.Cu")
		(net "P3V3_STBY")
	)
	(via
		(at 51.205384 -52.452016)
		(size 0.508)
		(drill 0.254)
		(layers "F.Cu" "B.Cu")
		(net "P3V3_STBY")
	)
	(via
		(at 34.0614 -24.5364)
		(size 0.7112)
		(drill 0.4064)
		(layers "F.Cu" "B.Cu")
		(net "P3V3_STBY")
	)
	(via
		(at 139.0904 -57.7342)
		(size 0.7112)
		(drill 0.3556)
		(layers "F.Cu" "B.Cu")
		(net "P3V3_STBY")
	)
	(via
		(at 140.4366 -22.6314)
		(size 0.508)
		(drill 0.254)
		(layers "F.Cu" "B.Cu")
		(net "P3V3_STBY")
	)
	(via
		(at 114.6302 -5.5118)
		(size 0.508)
		(drill 0.254)
		(layers "F.Cu" "B.Cu")
		(net "P3V3_STBY")
	)
	(via
		(at 198.628 -34.798)
		(size 0.5588)
		(drill 0.3048)
		(layers "F.Cu" "B.Cu")
		(net "P3V3_STBY")
	)
	(via
		(at 166.0144 -31.0896)
		(size 0.508)
		(drill 0.254)
		(layers "F.Cu" "B.Cu")
		(net "P3V3_STBY")
	)
	(via
		(at 64.262 -67.818)
		(size 0.7112)
		(drill 0.4064)
		(layers "F.Cu" "B.Cu")
		(net "P3V3_STBY")
	)
	(via
		(at 41.1226 -41.0718)
		(size 0.508)
		(drill 0.254)
		(layers "F.Cu" "B.Cu")
		(net "P3V3_STBY")
	)
	(via
		(at 41.5798 -45.4406)
		(size 0.508)
		(drill 0.254)
		(layers "F.Cu" "B.Cu")
		(net "P3V3_STBY")
	)
	(via
		(at 114.1476 -69.5198)
		(size 0.508)
		(drill 0.254)
		(layers "F.Cu" "B.Cu")
		(net "P3V3_STBY")
	)
	(via
		(at 62.889384 -44.365418)
		(size 0.508)
		(drill 0.254)
		(layers "F.Cu" "B.Cu")
		(net "P3V3_STBY")
	)
	(via
		(at 134.1374 -30.353)
		(size 0.508)
		(drill 0.254)
		(layers "F.Cu" "B.Cu")
		(net "P3V3_STBY")
	)
	(via
		(at 77.3176 -57.1246)
		(size 0.508)
		(drill 0.254)
		(layers "F.Cu" "B.Cu")
		(net "P3V3_STBY")
	)
	(via
		(at 28.7274 -38.354)
		(size 0.7112)
		(drill 0.4064)
		(layers "F.Cu" "B.Cu")
		(net "P3V3_STBY")
	)
	(via
		(at 48.9204 -42.3418)
		(size 0.7112)
		(drill 0.4064)
		(layers "F.Cu" "B.Cu")
		(net "P3V3_STBY")
	)
	(via
		(at 143.764 -22.6314)
		(size 0.508)
		(drill 0.254)
		(layers "F.Cu" "B.Cu")
		(net "P3V3_STBY")
	)
	(via
		(at 48.006 -22.2758)
		(size 0.7112)
		(drill 0.4064)
		(layers "F.Cu" "B.Cu")
		(net "P3V3_STBY")
	)
	(via
		(at 30.226 -40.4114)
		(size 0.7112)
		(drill 0.4064)
		(layers "F.Cu" "B.Cu")
		(net "P3V3_STBY")
	)
	(via
		(at 30.861 -23.622)
		(size 0.7112)
		(drill 0.3556)
		(layers "F.Cu" "B.Cu")
		(net "P3V3_STBY")
	)
	(via
		(at 134.2136 -36.840414)
		(size 0.508)
		(drill 0.254)
		(layers "F.Cu" "B.Cu")
		(net "P3V3_STBY")
	)
	(via
		(at 60.99302 -19.6342)
		(size 0.7112)
		(drill 0.4064)
		(layers "F.Cu" "B.Cu")
		(net "P3V3_STBY")
	)
	(via
		(at 166.6748 -36.576)
		(size 0.508)
		(drill 0.254)
		(layers "F.Cu" "B.Cu")
		(net "P3V3_STBY")
	)
	(via
		(at 143.357092 -46.604174)
		(size 0.508)
		(drill 0.254)
		(layers "F.Cu" "B.Cu")
		(net "P3V3_STBY")
	)
	(via
		(at 146.9136 -22.6314)
		(size 0.508)
		(drill 0.254)
		(layers "F.Cu" "B.Cu")
		(net "P3V3_STBY")
	)
	(via
		(at 137.9093 -22.7076)
		(size 0.508)
		(drill 0.254)
		(layers "F.Cu" "B.Cu")
		(net "P3V3_STBY")
	)
	(via
		(at 4.445 -48.3108)
		(size 0.508)
		(drill 0.254)
		(layers "F.Cu" "B.Cu")
		(net "P3V3_STBY")
	)
	(via
		(at 190.5254 -4.0894)
		(size 0.508)
		(drill 0.254)
		(layers "F.Cu" "B.Cu")
		(net "P3V3_STBY")
	)
	(via
		(at 154.5082 -36.80206)
		(size 0.508)
		(drill 0.254)
		(layers "F.Cu" "B.Cu")
		(net "P3V3_STBY")
	)
	(via
		(at 182.6006 -23.876)
		(size 0.508)
		(drill 0.254)
		(layers "F.Cu" "B.Cu")
		(net "P3V3_STBY")
	)
	(via
		(at 93.1418 -17.4498)
		(size 0.508)
		(drill 0.254)
		(layers "F.Cu" "B.Cu")
		(net "P3V3_STBY")
	)
	(via
		(at 142.543784 -57.750964)
		(size 0.508)
		(drill 0.254)
		(layers "F.Cu" "B.Cu")
		(net "P3V3_STBY")
	)
	(via
		(at 35.56 -49.657)
		(size 0.508)
		(drill 0.254)
		(layers "F.Cu" "B.Cu")
		(net "P3V3_STBY")
	)
	(via
		(at 29.845 -37.3253)
		(size 0.7112)
		(drill 0.4064)
		(layers "F.Cu" "B.Cu")
		(net "P3V3_STBY")
	)
	(via
		(at 158.209742 -51.8668)
		(size 0.508)
		(drill 0.254)
		(layers "F.Cu" "B.Cu")
		(net "P3V3_STBY")
	)
	(via
		(at 162.052 -26.162)
		(size 0.7112)
		(drill 0.3556)
		(layers "F.Cu" "B.Cu")
		(net "P3V3_STBY")
	)
	(via
		(at 9.525 -67.056)
		(size 0.7112)
		(drill 0.4064)
		(layers "F.Cu" "B.Cu")
		(net "P3V3_STBY")
	)
	(via
		(at 132.400294 -41.335706)
		(size 0.7112)
		(drill 0.3556)
		(layers "F.Cu" "B.Cu")
		(net "P3V3_STBY")
	)
	(via
		(at 8.509 -49.8094)
		(size 0.508)
		(drill 0.254)
		(layers "F.Cu" "B.Cu")
		(net "P3V3_STBY")
	)
	(via
		(at 69.723 -54.61)
		(size 0.7112)
		(drill 0.3556)
		(layers "F.Cu" "B.Cu")
		(net "P3V3_STBY")
	)
	(via
		(at 69.1642 -38.0746)
		(size 0.508)
		(drill 0.254)
		(layers "F.Cu" "B.Cu")
		(net "P3V3_STBY")
	)
	(via
		(at 101.8286 -69.342)
		(size 0.508)
		(drill 0.254)
		(layers "F.Cu" "B.Cu")
		(net "P3V3_STBY")
	)
	(via
		(at 128.35001 -68.199)
		(size 0.508)
		(drill 0.254)
		(layers "F.Cu" "B.Cu")
		(net "P3V3_STBY")
	)
	(via
		(at 70.7263 -55.0672)
		(size 0.508)
		(drill 0.254)
		(layers "F.Cu" "B.Cu")
		(net "P3V3_STBY")
	)
	(via
		(at 59.431174 -15.01775)
		(size 0.508)
		(drill 0.254)
		(layers "F.Cu" "B.Cu")
		(net "P3V3_STBY")
	)
	(via
		(at 105.918 -65.532)
		(size 0.508)
		(drill 0.254)
		(layers "F.Cu" "B.Cu")
		(net "P3V3_STBY")
	)
	(via
		(at 68.3006 -32.864044)
		(size 0.508)
		(drill 0.254)
		(layers "F.Cu" "B.Cu")
		(net "P3V3_STBY")
	)
	(segment
		(start 190.373 -8.668766)
		(end 190.149988 -8.891778)
		(width 0.3048)
		(layer "B.Cu")
		(net "P3V3_STBY")
	)
	(segment
		(start 128.76022 -25.158192)
		(end 128.874012 -25.0444)
		(width 0.508)
		(layer "B.Cu")
		(net "P3V3_STBY")
	)
	(segment
		(start 117.91696 -65.986914)
		(end 117.91696 -65.29324)
		(width 0.3048)
		(layer "B.Cu")
		(net "P3V3_STBY")
	)
	(segment
		(start 197.0532 -31.115)
		(end 197.0532 -32.004)
		(width 0.508)
		(layer "B.Cu")
		(net "P3V3_STBY")
	)
	(segment
		(start 67.945 -32.0802)
		(end 68.2498 -32.0802)
		(width 0.381)
		(layer "B.Cu")
		(net "P3V3_STBY")
	)
	(segment
		(start 49.53 -42.9514)
		(end 48.9204 -42.3418)
		(width 0.3048)
		(layer "B.Cu")
		(net "P3V3_STBY")
	)
	(segment
		(start 142.543784 -57.750964)
		(end 139.107164 -57.750964)
		(width 0.508)
		(layer "B.Cu")
		(net "P3V3_STBY")
	)
	(segment
		(start 161.29 -26.924)
		(end 161.29 -28.067)
		(width 0.508)
		(layer "B.Cu")
		(net "P3V3_STBY")
	)
	(segment
		(start 153.769822 -37.540438)
		(end 151.01316 -37.540438)
		(width 0.508)
		(layer "B.Cu")
		(net "P3V3_STBY")
	)
	(segment
		(start 34.0614 -24.5364)
		(end 33.274 -23.749)
		(width 0.508)
		(layer "B.Cu")
		(net "P3V3_STBY")
	)
	(segment
		(start 117.094 -22.687026)
		(end 119.565166 -25.158192)
		(width 0.508)
		(layer "B.Cu")
		(net "P3V3_STBY")
	)
	(segment
		(start 134.1882 -38.481)
		(end 148.838412 -38.481)
		(width 0.508)
		(layer "B.Cu")
		(net "P3V3_STBY")
	)
	(segment
		(start 139.281916 -46.442884)
		(end 139.281916 -46.6344)
		(width 0.3048)
		(layer "B.Cu")
		(net "P3V3_STBY")
	)
	(segment
		(start 8.919718 -69.499734)
		(end 10.908284 -71.4883)
		(width 1.016)
		(layer "B.Cu")
		(net "P3V3_STBY")
	)
	(segment
		(start 129.9718 -32.004)
		(end 126.924054 -32.004)
		(width 0.3048)
		(layer "B.Cu")
		(net "P3V3_STBY")
	)
	(segment
		(start 69.73824 -38.64864)
		(end 69.1642 -38.0746)
		(width 0.3048)
		(layer "B.Cu")
		(net "P3V3_STBY")
	)
	(segment
		(start 143.9926 -48.26)
		(end 143.9926 -47.498)
		(width 0.3048)
		(layer "B.Cu")
		(net "P3V3_STBY")
	)
	(segment
		(start 129.0828 -25.0444)
		(end 129.286 -24.8412)
		(width 0.508)
		(layer "B.Cu")
		(net "P3V3_STBY")
	)
	(segment
		(start 117.91696 -65.29324)
		(end 118.491 -64.7192)
		(width 0.3048)
		(layer "B.Cu")
		(net "P3V3_STBY")
	)
	(segment
		(start 77.216 -23.3934)
		(end 77.9018 -24.0792)
		(width 0.3048)
		(layer "B.Cu")
		(net "P3V3_STBY")
	)
	(segment
		(start 141.730984 -56.938164)
		(end 142.543784 -57.750964)
		(width 0.508)
		(layer "B.Cu")
		(net "P3V3_STBY")
	)
	(segment
		(start 136.799066 -23.21306)
		(end 136.293606 -22.7076)
		(width 0.3048)
		(layer "B.Cu")
		(net "P3V3_STBY")
	)
	(segment
		(start 190.149988 -9.89076)
		(end 190.149988 -10.76579)
		(width 0.3048)
		(layer "B.Cu")
		(net "P3V3_STBY")
	)
	(segment
		(start 30.861 -23.622)
		(end 30.856174 -23.622)
		(width 0.508)
		(layer "B.Cu")
		(net "P3V3_STBY")
	)
	(segment
		(start 134.1882 -38.481)
		(end 134.1882 -39.5478)
		(width 0.508)
		(layer "B.Cu")
		(net "P3V3_STBY")
	)
	(segment
		(start 55.499 -69.215)
		(end 57.1754 -70.8914)
		(width 1.016)
		(layer "B.Cu")
		(net "P3V3_STBY")
	)
	(segment
		(start 59.431174 -15.01775)
		(end 59.805824 -15.3924)
		(width 0.381)
		(layer "B.Cu")
		(net "P3V3_STBY")
	)
	(segment
		(start 197.0532 -33.990788)
		(end 197.581012 -34.5186)
		(width 0.508)
		(layer "B.Cu")
		(net "P3V3_STBY")
	)
	(segment
		(start 150.2156 -37.103812)
		(end 150.2156 -37.0332)
		(width 0.508)
		(layer "B.Cu")
		(net "P3V3_STBY")
	)
	(segment
		(start 36.5252 -48.6156)
		(end 36.2966 -48.387)
		(width 0.3048)
		(layer "B.Cu")
		(net "P3V3_STBY")
	)
	(segment
		(start 197.581012 -34.5186)
		(end 198.3486 -34.5186)
		(width 0.508)
		(layer "B.Cu")
		(net "P3V3_STBY")
	)
	(segment
		(start 134.4168 -59.5122)
		(end 136.1948 -57.7342)
		(width 0.508)
		(layer "B.Cu")
		(net "P3V3_STBY")
	)
	(segment
		(start 28.513278 -71.4883)
		(end 29.240226 -72.215248)
		(width 1.016)
		(layer "B.Cu")
		(net "P3V3_STBY")
	)
	(segment
		(start 148.233892 -22.6314)
		(end 146.9136 -22.6314)
		(width 0.508)
		(layer "B.Cu")
		(net "P3V3_STBY")
	)
	(segment
		(start 143.764 -22.6314)
		(end 143.764 -22.479)
		(width 0.508)
		(layer "B.Cu")
		(net "P3V3_STBY")
	)
	(segment
		(start 140.4366 -22.6314)
		(end 140.4366 -24.638)
		(width 0.508)
		(layer "B.Cu")
		(net "P3V3_STBY")
	)
	(segment
		(start 35.814 -49.403)
		(end 36.5252 -49.403)
		(width 0.3048)
		(layer "B.Cu")
		(net "P3V3_STBY")
	)
	(segment
		(start 148.838412 -38.481)
		(end 150.2156 -37.103812)
		(width 0.508)
		(layer "B.Cu")
		(net "P3V3_STBY")
	)
	(segment
		(start 58.711592 -18.579592)
		(end 58.711592 -19.722592)
		(width 0.3048)
		(layer "B.Cu")
		(net "P3V3_STBY")
	)
	(segment
		(start 145.2118 -44.069)
		(end 140.716 -44.069)
		(width 0.3048)
		(layer "B.Cu")
		(net "P3V3_STBY")
	)
	(segment
		(start 197.0532 -32.893)
		(end 197.0532 -33.782)
		(width 0.508)
		(layer "B.Cu")
		(net "P3V3_STBY")
	)
	(segment
		(start 153.82367 -54.9402)
		(end 149.8346 -54.9402)
		(width 0.508)
		(layer "B.Cu")
		(net "P3V3_STBY")
	)
	(segment
		(start 164.338 -36.195)
		(end 155.11526 -36.195)
		(width 0.508)
		(layer "B.Cu")
		(net "P3V3_STBY")
	)
	(segment
		(start 107.602274 -5.082032)
		(end 108.73613 -5.082032)
		(width 0.3048)
		(layer "B.Cu")
		(net "P3V3_STBY")
	)
	(segment
		(start 129.286 -24.8412)
		(end 130.048 -24.0792)
		(width 0.508)
		(layer "B.Cu")
		(net "P3V3_STBY")
	)
	(segment
		(start 105.283 -16.3068)
		(end 105.5878 -16.002)
		(width 0.3048)
		(layer "B.Cu")
		(net "P3V3_STBY")
	)
	(segment
		(start 30.856174 -23.622)
		(end 28.398978 -21.164804)
		(width 0.508)
		(layer "B.Cu")
		(net "P3V3_STBY")
	)
	(segment
		(start 70.7263 -55.0672)
		(end 70.1802 -55.0672)
		(width 0.3048)
		(layer "B.Cu")
		(net "P3V3_STBY")
	)
	(segment
		(start 68.20408 -34.96564)
		(end 67.33032 -34.09188)
		(width 0.381)
		(layer "B.Cu")
		(net "P3V3_STBY")
	)
	(segment
		(start 70.485 -53.8988)
		(end 70.4342 -53.8988)
		(width 0.3048)
		(layer "B.Cu")
		(net "P3V3_STBY")
	)
	(segment
		(start 128.8415 -61.2775)
		(end 129.0828 -61.0362)
		(width 0.508)
		(layer "B.Cu")
		(net "P3V3_STBY")
	)
	(segment
		(start 31.9278 -54.6608)
		(end 34.525458 -54.6608)
		(width 0.3048)
		(layer "B.Cu")
		(net "P3V3_STBY")
	)
	(segment
		(start 177.91303 -46.921928)
		(end 177.91303 -46.8884)
		(width 0.508)
		(layer "B.Cu")
		(net "P3V3_STBY")
	)
	(segment
		(start 143.357092 -46.604174)
		(end 143.357092 -46.99)
		(width 0.3048)
		(layer "B.Cu")
		(net "P3V3_STBY")
	)
	(segment
		(start 71.3994 -62.3316)
		(end 71.6534 -62.0776)
		(width 0.3048)
		(layer "B.Cu")
		(net "P3V3_STBY")
	)
	(segment
		(start 150.5966 -37.123878)
		(end 150.5966 -37.0078)
		(width 0.508)
		(layer "B.Cu")
		(net "P3V3_STBY")
	)
	(segment
		(start 46.609 -69.215)
		(end 55.499 -69.215)
		(width 1.016)
		(layer "B.Cu")
		(net "P3V3_STBY")
	)
	(segment
		(start 9.525 -67.056)
		(end 8.919718 -67.661282)
		(width 1.016)
		(layer "B.Cu")
		(net "P3V3_STBY")
	)
	(segment
		(start 134.1882 -37.719)
		(end 134.1882 -36.865814)
		(width 0.508)
		(layer "B.Cu")
		(net "P3V3_STBY")
	)
	(segment
		(start 134.1882 -30.4038)
		(end 134.1882 -31.115)
		(width 0.3048)
		(layer "B.Cu")
		(net "P3V3_STBY")
	)
	(segment
		(start 17.1958 -35.179)
		(end 18.7706 -35.179)
		(width 0.508)
		(layer "B.Cu")
		(net "P3V3_STBY")
	)
	(segment
		(start 149.0472 -54.1528)
		(end 147.8788 -54.1528)
		(width 0.508)
		(layer "B.Cu")
		(net "P3V3_STBY")
	)
	(segment
		(start 128.016 -64.262)
		(end 128.35001 -63.92799)
		(width 0.3048)
		(layer "B.Cu")
		(net "P3V3_STBY")
	)
	(segment
		(start 168.8084 -50.5714)
		(end 170.484546 -50.5714)
		(width 0.508)
		(layer "B.Cu")
		(net "P3V3_STBY")
	)
	(segment
		(start 35.7378 -52.324)
		(end 36.2458 -51.816)
		(width 0.3048)
		(layer "B.Cu")
		(net "P3V3_STBY")
	)
	(segment
		(start 114.6302 -5.5118)
		(end 114.8588 -5.7404)
		(width 0.508)
		(layer "B.Cu")
		(net "P3V3_STBY")
	)
	(segment
		(start 137.9093 -22.7076)
		(end 137.809986 -22.7076)
		(width 0.3048)
		(layer "B.Cu")
		(net "P3V3_STBY")
	)
	(segment
		(start 197.5612 -43.434)
		(end 197.5612 -42.672)
		(width 0.508)
		(layer "B.Cu")
		(net "P3V3_STBY")
	)
	(segment
		(start 149.8346 -54.9402)
		(end 149.0472 -54.1528)
		(width 0.508)
		(layer "B.Cu")
		(net "P3V3_STBY")
	)
	(segment
		(start 71.526146 -66.496946)
		(end 71.3994 -66.3702)
		(width 0.3048)
		(layer "B.Cu")
		(net "P3V3_STBY")
	)
	(segment
		(start 158.922212 -51.8668)
		(end 160.446212 -53.3908)
		(width 0.508)
		(layer "B.Cu")
		(net "P3V3_STBY")
	)
	(segment
		(start 190.149988 -10.76579)
		(end 189.2046 -11.711178)
		(width 0.3048)
		(layer "B.Cu")
		(net "P3V3_STBY")
	)
	(segment
		(start 189.9158 -49.657)
		(end 194.9958 -44.577)
		(width 0.508)
		(layer "B.Cu")
		(net "P3V3_STBY")
	)
	(segment
		(start 189.1538 -12.701778)
		(end 189.1538 -11.863578)
		(width 0.3048)
		(layer "B.Cu")
		(net "P3V3_STBY")
	)
	(segment
		(start 67.33032 -34.09188)
		(end 67.33032 -32.69488)
		(width 0.381)
		(layer "B.Cu")
		(net "P3V3_STBY")
	)
	(segment
		(start 60.198 -15.3924)
		(end 60.452 -15.6464)
		(width 0.3048)
		(layer "B.Cu")
		(net "P3V3_STBY")
	)
	(segment
		(start 162.052 -26.162)
		(end 161.29 -26.924)
		(width 0.508)
		(layer "B.Cu")
		(net "P3V3_STBY")
	)
	(segment
		(start 135.449818 -24.638)
		(end 135.449818 -22.767036)
		(width 0.508)
		(layer "B.Cu")
		(net "P3V3_STBY")
	)
	(segment
		(start 60.452 -16.764)
		(end 60.4012 -16.8148)
		(width 0.3048)
		(layer "B.Cu")
		(net "P3V3_STBY")
	)
	(segment
		(start 147.066 -53.34)
		(end 141.8082 -53.34)
		(width 0.508)
		(layer "B.Cu")
		(net "P3V3_STBY")
	)
	(segment
		(start 60.452 -15.6464)
		(end 60.452 -16.764)
		(width 0.3048)
		(layer "B.Cu")
		(net "P3V3_STBY")
	)
	(segment
		(start 29.556964 -72.529954)
		(end 43.294046 -72.529954)
		(width 1.016)
		(layer "B.Cu")
		(net "P3V3_STBY")
	)
	(segment
		(start 143.9418 -23.495)
		(end 143.9418 -22.8092)
		(width 0.3048)
		(layer "B.Cu")
		(net "P3V3_STBY")
	)
	(segment
		(start 107.273344 -5.410962)
		(end 107.602274 -5.082032)
		(width 0.3048)
		(layer "B.Cu")
		(net "P3V3_STBY")
	)
	(segment
		(start 171.444158 -53.3908)
		(end 172.374052 -52.460906)
		(width 0.508)
		(layer "B.Cu")
		(net "P3V3_STBY")
	)
	(segment
		(start 131.6228 -42.1132)
		(end 131.6228 -46.5836)
		(width 0.508)
		(layer "B.Cu")
		(net "P3V3_STBY")
	)
	(segment
		(start 160.446212 -53.3908)
		(end 171.444158 -53.3908)
		(width 0.508)
		(layer "B.Cu")
		(net "P3V3_STBY")
	)
	(segment
		(start 177.91303 -46.8884)
		(end 178.11623 -46.6852)
		(width 0.508)
		(layer "B.Cu")
		(net "P3V3_STBY")
	)
	(segment
		(start 143.357092 -46.298104)
		(end 143.2052 -46.146212)
		(width 0.3048)
		(layer "B.Cu")
		(net "P3V3_STBY")
	)
	(segment
		(start 77.9018 -24.0792)
		(end 78.486 -24.0792)
		(width 0.3048)
		(layer "B.Cu")
		(net "P3V3_STBY")
	)
	(segment
		(start 109.115352 -5.461)
		(end 109.22 -5.461)
		(width 0.3048)
		(layer "B.Cu")
		(net "P3V3_STBY")
	)
	(segment
		(start 134.1882 -37.719)
		(end 134.1882 -38.481)
		(width 0.508)
		(layer "B.Cu")
		(net "P3V3_STBY")
	)
	(segment
		(start 139.9032 -45.8216)
		(end 139.281916 -46.442884)
		(width 0.3048)
		(layer "B.Cu")
		(net "P3V3_STBY")
	)
	(segment
		(start 18.7706 -35.179)
		(end 21.971 -35.179)
		(width 0.508)
		(layer "B.Cu")
		(net "P3V3_STBY")
	)
	(segment
		(start 128.35001 -62.599824)
		(end 128.35001 -61.76899)
		(width 0.3048)
		(layer "B.Cu")
		(net "P3V3_STBY")
	)
	(segment
		(start 128.35001 -63.92799)
		(end 128.35001 -62.599824)
		(width 0.3048)
		(layer "B.Cu")
		(net "P3V3_STBY")
	)
	(segment
		(start 105.918 -65.532)
		(end 103.9622 -63.5762)
		(width 0.3048)
		(layer "B.Cu")
		(net "P3V3_STBY")
	)
	(segment
		(start 59.431174 -15.01775)
		(end 58.86704 -14.453616)
		(width 0.381)
		(layer "B.Cu")
		(net "P3V3_STBY")
	)
	(segment
		(start 145.669 -44.5262)
		(end 145.2118 -44.069)
		(width 0.3048)
		(layer "B.Cu")
		(net "P3V3_STBY")
	)
	(segment
		(start 10.908284 -71.4883)
		(end 28.513278 -71.4883)
		(width 1.016)
		(layer "B.Cu")
		(net "P3V3_STBY")
	)
	(segment
		(start 21.971 -35.179)
		(end 25.019 -38.227)
		(width 0.508)
		(layer "B.Cu")
		(net "P3V3_STBY")
	)
	(segment
		(start 143.764 -22.6314)
		(end 144.4244 -21.971)
		(width 0.508)
		(layer "B.Cu")
		(net "P3V3_STBY")
	)
	(segment
		(start 129.921 -30.353)
		(end 129.9718 -30.4038)
		(width 0.3048)
		(layer "B.Cu")
		(net "P3V3_STBY")
	)
	(segment
		(start 158.199074 -26.797)
		(end 152.399492 -26.797)
		(width 0.508)
		(layer "B.Cu")
		(net "P3V3_STBY")
	)
	(segment
		(start 60.4012 -16.8148)
		(end 60.4012 -16.88973)
		(width 0.3048)
		(layer "B.Cu")
		(net "P3V3_STBY")
	)
	(segment
		(start 71.3994 -66.3702)
		(end 71.3994 -62.3316)
		(width 0.3048)
		(layer "B.Cu")
		(net "P3V3_STBY")
	)
	(segment
		(start 143.1798 -47.498)
		(end 143.9926 -47.498)
		(width 0.3048)
		(layer "B.Cu")
		(net "P3V3_STBY")
	)
	(segment
		(start 131.4196 -61.0362)
		(end 132.08 -60.3758)
		(width 0.508)
		(layer "B.Cu")
		(net "P3V3_STBY")
	)
	(segment
		(start 107.273344 -9.070848)
		(end 107.273344 -5.410962)
		(width 0.3048)
		(layer "B.Cu")
		(net "P3V3_STBY")
	)
	(segment
		(start 130.765042 -21.336)
		(end 134.018782 -21.336)
		(width 0.508)
		(layer "B.Cu")
		(net "P3V3_STBY")
	)
	(segment
		(start 137.304526 -23.21306)
		(end 136.799066 -23.21306)
		(width 0.3048)
		(layer "B.Cu")
		(net "P3V3_STBY")
	)
	(segment
		(start 143.764 -22.479)
		(end 143.2306 -21.9456)
		(width 0.508)
		(layer "B.Cu")
		(net "P3V3_STBY")
	)
	(segment
		(start 143.9418 -22.8092)
		(end 143.764 -22.6314)
		(width 0.3048)
		(layer "B.Cu")
		(net "P3V3_STBY")
	)
	(segment
		(start 162.052 -25.781)
		(end 162.052 -26.162)
		(width 0.508)
		(layer "B.Cu")
		(net "P3V3_STBY")
	)
	(segment
		(start 68.2498 -32.0802)
		(end 68.3006 -32.131)
		(width 0.508)
		(layer "B.Cu")
		(net "P3V3_STBY")
	)
	(segment
		(start 134.1882 -31.877)
		(end 134.1882 -31.115)
		(width 0.3048)
		(layer "B.Cu")
		(net "P3V3_STBY")
	)
	(segment
		(start 161.29 -28.067)
		(end 159.469074 -28.067)
		(width 0.508)
		(layer "B.Cu")
		(net "P3V3_STBY")
	)
	(segment
		(start 155.0162 -53.74767)
		(end 153.82367 -54.9402)
		(width 0.508)
		(layer "B.Cu")
		(net "P3V3_STBY")
	)
	(segment
		(start 69.87032 -38.9128)
		(end 69.73824 -38.78072)
		(width 0.3048)
		(layer "B.Cu")
		(net "P3V3_STBY")
	)
	(segment
		(start 189.1538 -11.863578)
		(end 189.2046 -11.812778)
		(width 0.3048)
		(layer "B.Cu")
		(net "P3V3_STBY")
	)
	(segment
		(start 159.469074 -28.067)
		(end 158.680404 -27.27833)
		(width 0.508)
		(layer "B.Cu")
		(net "P3V3_STBY")
	)
	(segment
		(start 60.4012 -16.88973)
		(end 58.711592 -18.579592)
		(width 0.3048)
		(layer "B.Cu")
		(net "P3V3_STBY")
	)
	(segment
		(start 28.398978 -21.164804)
		(end 23.412196 -21.164804)
		(width 0.508)
		(layer "B.Cu")
		(net "P3V3_STBY")
	)
	(segment
		(start 132.400294 -41.335706)
		(end 131.6228 -42.1132)
		(width 0.508)
		(layer "B.Cu")
		(net "P3V3_STBY")
	)
	(segment
		(start 108.4199 -13.205206)
		(end 108.4199 -10.217404)
		(width 0.3048)
		(layer "B.Cu")
		(net "P3V3_STBY")
	)
	(segment
		(start 25.019 -38.227)
		(end 28.6004 -38.227)
		(width 0.508)
		(layer "B.Cu")
		(net "P3V3_STBY")
	)
	(segment
		(start 164.719 -36.576)
		(end 164.338 -36.195)
		(width 0.508)
		(layer "B.Cu")
		(net "P3V3_STBY")
	)
	(segment
		(start 77.020166 -23.3934)
		(end 77.216 -23.3934)
		(width 0.3048)
		(layer "B.Cu")
		(net "P3V3_STBY")
	)
	(segment
		(start 137.9093 -23.5585)
		(end 137.9093 -22.7076)
		(width 0.3048)
		(layer "B.Cu")
		(net "P3V3_STBY")
	)
	(segment
		(start 61.1886 -70.8914)
		(end 64.262 -67.818)
		(width 1.016)
		(layer "B.Cu")
		(net "P3V3_STBY")
	)
	(segment
		(start 118.999 -64.7192)
		(end 119.888 -64.7192)
		(width 0.3048)
		(layer "B.Cu")
		(net "P3V3_STBY")
	)
	(segment
		(start 136.211818 -25.4)
		(end 135.449818 -24.638)
		(width 0.508)
		(layer "B.Cu")
		(net "P3V3_STBY")
	)
	(segment
		(start 188.7474 -49.657)
		(end 189.9158 -49.657)
		(width 0.508)
		(layer "B.Cu")
		(net "P3V3_STBY")
	)
	(segment
		(start 34.525458 -54.6608)
		(end 35.7378 -53.448458)
		(width 0.3048)
		(layer "B.Cu")
		(net "P3V3_STBY")
	)
	(segment
		(start 69.73824 -38.78072)
		(end 69.73824 -38.64864)
		(width 0.3048)
		(layer "B.Cu")
		(net "P3V3_STBY")
	)
	(segment
		(start 134.1374 -30.353)
		(end 134.1882 -30.4038)
		(width 0.3048)
		(layer "B.Cu")
		(net "P3V3_STBY")
	)
	(segment
		(start 141.8082 -53.34)
		(end 141.730984 -53.417216)
		(width 0.508)
		(layer "B.Cu")
		(net "P3V3_STBY")
	)
	(segment
		(start 130.048 -24.0792)
		(end 130.048 -22.053042)
		(width 0.508)
		(layer "B.Cu")
		(net "P3V3_STBY")
	)
	(segment
		(start 108.4199 -10.217404)
		(end 107.273344 -9.070848)
		(width 0.3048)
		(layer "B.Cu")
		(net "P3V3_STBY")
	)
	(segment
		(start 158.209742 -51.8668)
		(end 156.482542 -53.594)
		(width 0.508)
		(layer "B.Cu")
		(net "P3V3_STBY")
	)
	(segment
		(start 109.930946 -5.461)
		(end 109.22 -5.461)
		(width 0.3048)
		(layer "B.Cu")
		(net "P3V3_STBY")
	)
	(segment
		(start 143.2306 -21.9456)
		(end 140.9446 -21.9456)
		(width 0.508)
		(layer "B.Cu")
		(net "P3V3_STBY")
	)
	(segment
		(start 146.323558 -21.971)
		(end 146.9136 -22.561042)
		(width 0.508)
		(layer "B.Cu")
		(net "P3V3_STBY")
	)
	(segment
		(start 119.565166 -25.158192)
		(end 128.76022 -25.158192)
		(width 0.508)
		(layer "B.Cu")
		(net "P3V3_STBY")
	)
	(segment
		(start 154.5082 -36.80206)
		(end 153.769822 -37.540438)
		(width 0.508)
		(layer "B.Cu")
		(net "P3V3_STBY")
	)
	(segment
		(start 35.56 -49.657)
		(end 36.2458 -50.3428)
		(width 0.3048)
		(layer "B.Cu")
		(net "P3V3_STBY")
	)
	(segment
		(start 105.623106 -16.002)
		(end 108.4199 -13.205206)
		(width 0.3048)
		(layer "B.Cu")
		(net "P3V3_STBY")
	)
	(segment
		(start 134.1882 -36.815014)
		(end 134.1882 -31.877)
		(width 0.508)
		(layer "B.Cu")
		(net "P3V3_STBY")
	)
	(segment
		(start 70.6374 -38.9128)
		(end 69.87032 -38.9128)
		(width 0.3048)
		(layer "B.Cu")
		(net "P3V3_STBY")
	)
	(segment
		(start 119.516906 -67.58686)
		(end 119.913654 -67.58686)
		(width 0.3048)
		(layer "B.Cu")
		(net "P3V3_STBY")
	)
	(segment
		(start 177.292 -42.1132)
		(end 177.292 -41.46677)
		(width 0.3048)
		(layer "B.Cu")
		(net "P3V3_STBY")
	)
	(segment
		(start 35.7378 -53.448458)
		(end 35.7378 -52.324)
		(width 0.3048)
		(layer "B.Cu")
		(net "P3V3_STBY")
	)
	(segment
		(start 156.482542 -53.594)
		(end 155.0162 -53.594)
		(width 0.508)
		(layer "B.Cu")
		(net "P3V3_STBY")
	)
	(segment
		(start 23.241 -21.336)
		(end 21.463 -21.336)
		(width 0.508)
		(layer "B.Cu")
		(net "P3V3_STBY")
	)
	(segment
		(start 198.3486 -34.5186)
		(end 198.628 -34.798)
		(width 0.508)
		(layer "B.Cu")
		(net "P3V3_STBY")
	)
	(segment
		(start 190.5254 -4.0894)
		(end 190.373 -4.2418)
		(width 0.3048)
		(layer "B.Cu")
		(net "P3V3_STBY")
	)
	(segment
		(start 133.1468 -59.5122)
		(end 133.35 -59.5122)
		(width 0.508)
		(layer "B.Cu")
		(net "P3V3_STBY")
	)
	(segment
		(start 70.4342 -53.8988)
		(end 69.723 -54.61)
		(width 0.3048)
		(layer "B.Cu")
		(net "P3V3_STBY")
	)
	(segment
		(start 29.240226 -72.215248)
		(end 29.556964 -72.529954)
		(width 1.016)
		(layer "B.Cu")
		(net "P3V3_STBY")
	)
	(segment
		(start 141.730984 -53.417216)
		(end 141.730984 -56.938164)
		(width 0.508)
		(layer "B.Cu")
		(net "P3V3_STBY")
	)
	(segment
		(start 53.7972 -52.451)
		(end 52.07 -52.451)
		(width 0.3048)
		(layer "B.Cu")
		(net "P3V3_STBY")
	)
	(segment
		(start 30.988 -23.749)
		(end 30.861 -23.622)
		(width 0.508)
		(layer "B.Cu")
		(net "P3V3_STBY")
	)
	(segment
		(start 143.1798 -47.167292)
		(end 143.1798 -47.498)
		(width 0.3048)
		(layer "B.Cu")
		(net "P3V3_STBY")
	)
	(segment
		(start 147.8788 -54.1528)
		(end 147.066 -53.34)
		(width 0.508)
		(layer "B.Cu")
		(net "P3V3_STBY")
	)
	(segment
		(start 23.412196 -21.164804)
		(end 23.241 -21.336)
		(width 0.508)
		(layer "B.Cu")
		(net "P3V3_STBY")
	)
	(segment
		(start 190.373 -4.2418)
		(end 190.373 -8.668766)
		(width 0.3048)
		(layer "B.Cu")
		(net "P3V3_STBY")
	)
	(segment
		(start 143.357092 -46.604174)
		(end 143.357092 -46.298104)
		(width 0.3048)
		(layer "B.Cu")
		(net "P3V3_STBY")
	)
	(segment
		(start 60.30722 -20.32)
		(end 60.99302 -19.6342)
		(width 0.3048)
		(layer "B.Cu")
		(net "P3V3_STBY")
	)
	(segment
		(start 108.73613 -5.082032)
		(end 109.115352 -5.461)
		(width 0.3048)
		(layer "B.Cu")
		(net "P3V3_STBY")
	)
	(segment
		(start 194.9958 -44.577)
		(end 196.4182 -44.577)
		(width 0.508)
		(layer "B.Cu")
		(net "P3V3_STBY")
	)
	(segment
		(start 139.107164 -57.750964)
		(end 139.0904 -57.7342)
		(width 0.508)
		(layer "B.Cu")
		(net "P3V3_STBY")
	)
	(segment
		(start 28.6004 -38.227)
		(end 28.7274 -38.354)
		(width 0.508)
		(layer "B.Cu")
		(net "P3V3_STBY")
	)
	(segment
		(start 168.6052 -50.7746)
		(end 168.8084 -50.5714)
		(width 0.508)
		(layer "B.Cu")
		(net "P3V3_STBY")
	)
	(segment
		(start 143.2052 -46.146212)
		(end 143.2052 -45.466)
		(width 0.3048)
		(layer "B.Cu")
		(net "P3V3_STBY")
	)
	(segment
		(start 146.9136 -22.561042)
		(end 146.9136 -22.6314)
		(width 0.508)
		(layer "B.Cu")
		(net "P3V3_STBY")
	)
	(segment
		(start 36.5252 -49.403)
		(end 36.5252 -48.6156)
		(width 0.3048)
		(layer "B.Cu")
		(net "P3V3_STBY")
	)
	(segment
		(start 110.109 -5.2832)
		(end 109.930946 -5.461)
		(width 0.3048)
		(layer "B.Cu")
		(net "P3V3_STBY")
	)
	(segment
		(start 172.374052 -52.460906)
		(end 177.91303 -46.921928)
		(width 0.508)
		(layer "B.Cu")
		(net "P3V3_STBY")
	)
	(segment
		(start 77.343 -56.4642)
		(end 77.343 -57.0992)
		(width 0.3048)
		(layer "B.Cu")
		(net "P3V3_STBY")
	)
	(segment
		(start 145.669 -44.5262)
		(end 146.431 -44.5262)
		(width 0.3048)
		(layer "B.Cu")
		(net "P3V3_STBY")
	)
	(segment
		(start 67.33032 -32.69488)
		(end 67.945 -32.0802)
		(width 0.381)
		(layer "B.Cu")
		(net "P3V3_STBY")
	)
	(segment
		(start 134.2136 -36.840414)
		(end 134.1882 -36.815014)
		(width 0.508)
		(layer "B.Cu")
		(net "P3V3_STBY")
	)
	(segment
		(start 153.77414 -36.068)
		(end 154.5082 -36.80206)
		(width 0.3048)
		(layer "B.Cu")
		(net "P3V3_STBY")
	)
	(segment
		(start 129.9718 -32.004)
		(end 129.9718 -31.115)
		(width 0.3048)
		(layer "B.Cu")
		(net "P3V3_STBY")
	)
	(segment
		(start 20.447 -22.352)
		(end 19.3548 -22.352)
		(width 0.508)
		(layer "B.Cu")
		(net "P3V3_STBY")
	)
	(segment
		(start 137.8458 -23.622)
		(end 137.9093 -23.5585)
		(width 0.3048)
		(layer "B.Cu")
		(net "P3V3_STBY")
	)
	(segment
		(start 166.6748 -36.576)
		(end 164.719 -36.576)
		(width 0.508)
		(layer "B.Cu")
		(net "P3V3_STBY")
	)
	(segment
		(start 135.509254 -22.7076)
		(end 135.449818 -22.767036)
		(width 0.3048)
		(layer "B.Cu")
		(net "P3V3_STBY")
	)
	(segment
		(start 153.7462 -36.068)
		(end 153.77414 -36.068)
		(width 0.3048)
		(layer "B.Cu")
		(net "P3V3_STBY")
	)
	(segment
		(start 197.5612 -42.672)
		(end 197.5612 -41.91)
		(width 0.508)
		(layer "B.Cu")
		(net "P3V3_STBY")
	)
	(segment
		(start 137.8458 -24.384)
		(end 137.8458 -23.622)
		(width 0.3048)
		(layer "B.Cu")
		(net "P3V3_STBY")
	)
	(segment
		(start 150.5966 -37.0078)
		(end 150.4188 -36.83)
		(width 0.508)
		(layer "B.Cu")
		(net "P3V3_STBY")
	)
	(segment
		(start 196.4182 -44.577)
		(end 197.5612 -43.434)
		(width 0.508)
		(layer "B.Cu")
		(net "P3V3_STBY")
	)
	(segment
		(start 126.924054 -32.004)
		(end 125.222 -30.301946)
		(width 0.3048)
		(layer "B.Cu")
		(net "P3V3_STBY")
	)
	(segment
		(start 197.5612 -41.91)
		(end 197.5612 -41.148)
		(width 0.508)
		(layer "B.Cu")
		(net "P3V3_STBY")
	)
	(segment
		(start 170.484546 -50.5714)
		(end 172.374052 -52.460906)
		(width 0.508)
		(layer "B.Cu")
		(net "P3V3_STBY")
	)
	(segment
		(start 58.86704 -14.453616)
		(end 58.86704 -14.26972)
		(width 0.381)
		(layer "B.Cu")
		(net "P3V3_STBY")
	)
	(segment
		(start 155.0162 -53.594)
		(end 155.0162 -53.74767)
		(width 0.508)
		(layer "B.Cu")
		(net "P3V3_STBY")
	)
	(segment
		(start 152.399492 -26.797)
		(end 148.233892 -22.6314)
		(width 0.508)
		(layer "B.Cu")
		(net "P3V3_STBY")
	)
	(segment
		(start 140.716 -44.069)
		(end 139.9032 -44.8818)
		(width 0.3048)
		(layer "B.Cu")
		(net "P3V3_STBY")
	)
	(segment
		(start 140.9446 -21.9456)
		(end 140.4366 -22.4536)
		(width 0.508)
		(layer "B.Cu")
		(net "P3V3_STBY")
	)
	(segment
		(start 128.35001 -68.199)
		(end 128.016 -67.86499)
		(width 0.508)
		(layer "B.Cu")
		(net "P3V3_STBY")
	)
	(segment
		(start 33.274 -23.749)
		(end 30.988 -23.749)
		(width 0.508)
		(layer "B.Cu")
		(net "P3V3_STBY")
	)
	(segment
		(start 114.8588 -13.43152)
		(end 117.094 -15.66672)
		(width 0.508)
		(layer "B.Cu")
		(net "P3V3_STBY")
	)
	(segment
		(start 57.1754 -70.8914)
		(end 61.1886 -70.8914)
		(width 1.016)
		(layer "B.Cu")
		(net "P3V3_STBY")
	)
	(segment
		(start 59.805824 -15.3924)
		(end 60.198 -15.3924)
		(width 0.381)
		(layer "B.Cu")
		(net "P3V3_STBY")
	)
	(segment
		(start 100.457 -63.5762)
		(end 100.33 -63.4492)
		(width 0.3048)
		(layer "B.Cu")
		(net "P3V3_STBY")
	)
	(segment
		(start 197.0532 -32.004)
		(end 197.0532 -32.893)
		(width 0.508)
		(layer "B.Cu")
		(net "P3V3_STBY")
	)
	(segment
		(start 136.293606 -22.7076)
		(end 135.509254 -22.7076)
		(width 0.3048)
		(layer "B.Cu")
		(net "P3V3_STBY")
	)
	(segment
		(start 132.2832 -60.3758)
		(end 133.1468 -59.5122)
		(width 0.508)
		(layer "B.Cu")
		(net "P3V3_STBY")
	)
	(segment
		(start 43.294046 -72.529954)
		(end 46.609 -69.215)
		(width 1.016)
		(layer "B.Cu")
		(net "P3V3_STBY")
	)
	(segment
		(start 117.094 -15.66672)
		(end 117.094 -22.687026)
		(width 0.508)
		(layer "B.Cu")
		(net "P3V3_STBY")
	)
	(segment
		(start 59.309 -20.32)
		(end 60.30722 -20.32)
		(width 0.3048)
		(layer "B.Cu")
		(net "P3V3_STBY")
	)
	(segment
		(start 162.8902 -24.9428)
		(end 162.052 -25.781)
		(width 0.508)
		(layer "B.Cu")
		(net "P3V3_STBY")
	)
	(segment
		(start 77.343 -57.0992)
		(end 77.3176 -57.1246)
		(width 0.3048)
		(layer "B.Cu")
		(net "P3V3_STBY")
	)
	(segment
		(start 134.018782 -21.336)
		(end 135.449818 -22.767036)
		(width 0.508)
		(layer "B.Cu")
		(net "P3V3_STBY")
	)
	(segment
		(start 103.9622 -63.5762)
		(end 100.457 -63.5762)
		(width 0.3048)
		(layer "B.Cu")
		(net "P3V3_STBY")
	)
	(segment
		(start 133.35 -59.5122)
		(end 134.4168 -59.5122)
		(width 0.508)
		(layer "B.Cu")
		(net "P3V3_STBY")
	)
	(segment
		(start 151.01316 -37.540438)
		(end 150.5966 -37.123878)
		(width 0.508)
		(layer "B.Cu")
		(net "P3V3_STBY")
	)
	(segment
		(start 140.4366 -24.638)
		(end 139.6746 -25.4)
		(width 0.508)
		(layer "B.Cu")
		(net "P3V3_STBY")
	)
	(segment
		(start 31.496 -54.0258)
		(end 30.734 -54.0258)
		(width 0.3048)
		(layer "B.Cu")
		(net "P3V3_STBY")
	)
	(segment
		(start 31.496 -54.0258)
		(end 31.496 -54.229)
		(width 0.3048)
		(layer "B.Cu")
		(net "P3V3_STBY")
	)
	(segment
		(start 70.1802 -55.0672)
		(end 69.723 -54.61)
		(width 0.3048)
		(layer "B.Cu")
		(net "P3V3_STBY")
	)
	(segment
		(start 35.56 -49.657)
		(end 35.814 -49.403)
		(width 0.3048)
		(layer "B.Cu")
		(net "P3V3_STBY")
	)
	(segment
		(start 158.680404 -27.27833)
		(end 158.199074 -26.797)
		(width 0.508)
		(layer "B.Cu")
		(net "P3V3_STBY")
	)
	(segment
		(start 155.11526 -36.195)
		(end 154.5082 -36.80206)
		(width 0.508)
		(layer "B.Cu")
		(net "P3V3_STBY")
	)
	(segment
		(start 117.91696 -65.986914)
		(end 119.516906 -67.58686)
		(width 0.3048)
		(layer "B.Cu")
		(net "P3V3_STBY")
	)
	(segment
		(start 68.3006 -32.131)
		(end 68.3006 -32.864044)
		(width 0.508)
		(layer "B.Cu")
		(net "P3V3_STBY")
	)
	(segment
		(start 128.016 -67.86499)
		(end 128.016 -64.262)
		(width 0.508)
		(layer "B.Cu")
		(net "P3V3_STBY")
	)
	(segment
		(start 8.919718 -67.661282)
		(end 8.919718 -69.499734)
		(width 1.016)
		(layer "B.Cu")
		(net "P3V3_STBY")
	)
	(segment
		(start 128.35001 -61.76899)
		(end 128.8415 -61.2775)
		(width 0.3048)
		(layer "B.Cu")
		(net "P3V3_STBY")
	)
	(segment
		(start 118.491 -64.7192)
		(end 118.999 -64.7192)
		(width 0.3048)
		(layer "B.Cu")
		(net "P3V3_STBY")
	)
	(segment
		(start 177.292 -41.46677)
		(end 177.546 -41.21277)
		(width 0.3048)
		(layer "B.Cu")
		(net "P3V3_STBY")
	)
	(segment
		(start 128.874012 -25.0444)
		(end 129.0828 -25.0444)
		(width 0.508)
		(layer "B.Cu")
		(net "P3V3_STBY")
	)
	(segment
		(start 129.9718 -30.4038)
		(end 129.9718 -31.115)
		(width 0.3048)
		(layer "B.Cu")
		(net "P3V3_STBY")
	)
	(segment
		(start 137.809986 -22.7076)
		(end 137.304526 -23.21306)
		(width 0.3048)
		(layer "B.Cu")
		(net "P3V3_STBY")
	)
	(segment
		(start 130.048 -22.053042)
		(end 130.765042 -21.336)
		(width 0.508)
		(layer "B.Cu")
		(net "P3V3_STBY")
	)
	(segment
		(start 134.1882 -39.5478)
		(end 132.400294 -41.335706)
		(width 0.508)
		(layer "B.Cu")
		(net "P3V3_STBY")
	)
	(segment
		(start 140.4366 -22.4536)
		(end 140.4366 -22.6314)
		(width 0.508)
		(layer "B.Cu")
		(net "P3V3_STBY")
	)
	(segment
		(start 144.4244 -21.971)
		(end 146.323558 -21.971)
		(width 0.508)
		(layer "B.Cu")
		(net "P3V3_STBY")
	)
	(segment
		(start 134.1882 -36.865814)
		(end 134.2136 -36.840414)
		(width 0.508)
		(layer "B.Cu")
		(net "P3V3_STBY")
	)
	(segment
		(start 158.209742 -51.8668)
		(end 158.922212 -51.8668)
		(width 0.508)
		(layer "B.Cu")
		(net "P3V3_STBY")
	)
	(segment
		(start 76.613766 -22.987)
		(end 77.020166 -23.3934)
		(width 0.3048)
		(layer "B.Cu")
		(net "P3V3_STBY")
	)
	(segment
		(start 36.2458 -50.3428)
		(end 36.2458 -51.054)
		(width 0.3048)
		(layer "B.Cu")
		(net "P3V3_STBY")
	)
	(segment
		(start 79.248 -24.0792)
		(end 78.486 -24.0792)
		(width 0.3048)
		(layer "B.Cu")
		(net "P3V3_STBY")
	)
	(segment
		(start 114.8588 -5.7404)
		(end 114.8588 -13.43152)
		(width 0.508)
		(layer "B.Cu")
		(net "P3V3_STBY")
	)
	(segment
		(start 129.0828 -61.0362)
		(end 131.4196 -61.0362)
		(width 0.508)
		(layer "B.Cu")
		(net "P3V3_STBY")
	)
	(segment
		(start 190.149988 -8.891778)
		(end 190.149988 -9.89076)
		(width 0.3048)
		(layer "B.Cu")
		(net "P3V3_STBY")
	)
	(segment
		(start 162.731958 -23.14321)
		(end 162.8902 -23.301452)
		(width 0.508)
		(layer "B.Cu")
		(net "P3V3_STBY")
	)
	(segment
		(start 143.357092 -46.99)
		(end 143.1798 -47.167292)
		(width 0.3048)
		(layer "B.Cu")
		(net "P3V3_STBY")
	)
	(segment
		(start 49.53 -43.0022)
		(end 49.53 -42.9514)
		(width 0.3048)
		(layer "B.Cu")
		(net "P3V3_STBY")
	)
	(segment
		(start 139.9032 -44.8818)
		(end 139.9032 -45.466)
		(width 0.3048)
		(layer "B.Cu")
		(net "P3V3_STBY")
	)
	(segment
		(start 162.8902 -23.301452)
		(end 162.8902 -24.9428)
		(width 0.508)
		(layer "B.Cu")
		(net "P3V3_STBY")
	)
	(segment
		(start 189.2046 -11.711178)
		(end 189.2046 -11.812778)
		(width 0.3048)
		(layer "B.Cu")
		(net "P3V3_STBY")
	)
	(segment
		(start 150.2156 -37.0332)
		(end 150.4188 -36.83)
		(width 0.508)
		(layer "B.Cu")
		(net "P3V3_STBY")
	)
	(segment
		(start 21.463 -21.336)
		(end 20.447 -22.352)
		(width 0.508)
		(layer "B.Cu")
		(net "P3V3_STBY")
	)
	(segment
		(start 31.496 -54.229)
		(end 31.9278 -54.6608)
		(width 0.3048)
		(layer "B.Cu")
		(net "P3V3_STBY")
	)
	(segment
		(start 105.5878 -16.002)
		(end 105.623106 -16.002)
		(width 0.3048)
		(layer "B.Cu")
		(net "P3V3_STBY")
	)
	(segment
		(start 36.2458 -51.816)
		(end 36.2458 -51.054)
		(width 0.3048)
		(layer "B.Cu")
		(net "P3V3_STBY")
	)
	(segment
		(start 132.08 -60.3758)
		(end 132.2832 -60.3758)
		(width 0.508)
		(layer "B.Cu")
		(net "P3V3_STBY")
	)
	(segment
		(start 139.9032 -45.466)
		(end 139.9032 -45.8216)
		(width 0.3048)
		(layer "B.Cu")
		(net "P3V3_STBY")
	)
	(segment
		(start 136.1948 -57.7342)
		(end 139.0904 -57.7342)
		(width 0.508)
		(layer "B.Cu")
		(net "P3V3_STBY")
	)
	(segment
		(start 58.711592 -19.722592)
		(end 59.309 -20.32)
		(width 0.3048)
		(layer "B.Cu")
		(net "P3V3_STBY")
	)
	(segment
		(start 139.6746 -25.4)
		(end 136.211818 -25.4)
		(width 0.508)
		(layer "B.Cu")
		(net "P3V3_STBY")
	)
	(segment
		(start 197.0532 -33.782)
		(end 197.0532 -33.990788)
		(width 0.508)
		(layer "B.Cu")
		(net "P3V3_STBY")
	)
	(segment
		(start 77.3176 -22.4536)
		(end 77.3176 -20.52828)
		(width 0.3048)
		(layer "In2.Cu")
		(net "P3V3_STBY")
	)
	(segment
		(start 82.991198 -15.97025)
		(end 84.1502 -14.811248)
		(width 0.3048)
		(layer "In2.Cu")
		(net "P3V3_STBY")
	)
	(segment
		(start 81.87563 -15.97025)
		(end 82.991198 -15.97025)
		(width 0.3048)
		(layer "In2.Cu")
		(net "P3V3_STBY")
	)
	(segment
		(start 72.2503 -56.5912)
		(end 74.4093 -56.5912)
		(width 0.3048)
		(layer "In2.Cu")
		(net "P3V3_STBY")
	)
	(segment
		(start 74.4093 -56.5912)
		(end 74.9427 -57.1246)
		(width 0.3048)
		(layer "In2.Cu")
		(net "P3V3_STBY")
	)
	(segment
		(start 182.6006 -23.876)
		(end 182.6006 -32.78632)
		(width 0.508)
		(layer "In2.Cu")
		(net "P3V3_STBY")
	)
	(segment
		(start 74.9427 -57.1246)
		(end 77.3176 -57.1246)
		(width 0.3048)
		(layer "In2.Cu")
		(net "P3V3_STBY")
	)
	(segment
		(start 70.7263 -55.0672)
		(end 72.2503 -56.5912)
		(width 0.3048)
		(layer "In2.Cu")
		(net "P3V3_STBY")
	)
	(segment
		(start 109.2708 -5.5118)
		(end 109.22 -5.461)
		(width 0.3048)
		(layer "In2.Cu")
		(net "P3V3_STBY")
	)
	(segment
		(start 77.3176 -20.52828)
		(end 81.87563 -15.97025)
		(width 0.3048)
		(layer "In2.Cu")
		(net "P3V3_STBY")
	)
	(segment
		(start 181.88432 -33.5026)
		(end 181.5846 -33.5026)
		(width 0.508)
		(layer "In2.Cu")
		(net "P3V3_STBY")
	)
	(segment
		(start 84.1502 -14.811248)
		(end 84.1502 -12.31265)
		(width 0.3048)
		(layer "In2.Cu")
		(net "P3V3_STBY")
	)
	(segment
		(start 182.6006 -32.78632)
		(end 181.88432 -33.5026)
		(width 0.508)
		(layer "In2.Cu")
		(net "P3V3_STBY")
	)
	(segment
		(start 177.546 -37.368988)
		(end 177.546 -41.21277)
		(width 0.508)
		(layer "In2.Cu")
		(net "P3V3_STBY")
	)
	(segment
		(start 181.412388 -33.5026)
		(end 177.546 -37.368988)
		(width 0.508)
		(layer "In2.Cu")
		(net "P3V3_STBY")
	)
	(segment
		(start 181.5846 -33.5026)
		(end 181.412388 -33.5026)
		(width 0.508)
		(layer "In2.Cu")
		(net "P3V3_STBY")
	)
	(segment
		(start 114.6302 -5.5118)
		(end 109.2708 -5.5118)
		(width 0.3048)
		(layer "In2.Cu")
		(net "P3V3_STBY")
	)
	(segment
		(start 83.24469 -21.6916)
		(end 83.33359 -21.6027)
		(width 0.508)
		(layer "In4.Cu")
		(net "P3V3_STBY")
	)
	(segment
		(start 62.889384 -44.365418)
		(end 62.889384 -42.596816)
		(width 0.508)
		(layer "In4.Cu")
		(net "P3V3_STBY")
	)
	(segment
		(start 177.546 -41.21277)
		(end 178.11623 -41.783)
		(width 0.508)
		(layer "In4.Cu")
		(net "P3V3_STBY")
	)
	(segment
		(start 66.7766 -38.7096)
		(end 68.13931 -38.7096)
		(width 0.508)
		(layer "In4.Cu")
		(net "P3V3_STBY")
	)
	(segment
		(start 178.11623 -41.783)
		(end 178.11623 -46.6852)
		(width 0.508)
		(layer "In4.Cu")
		(net "P3V3_STBY")
	)
	(segment
		(start 62.889384 -42.596816)
		(end 66.7766 -38.7096)
		(width 0.508)
		(layer "In4.Cu")
		(net "P3V3_STBY")
	)
	(segment
		(start 194.056 -34.544)
		(end 198.374 -34.544)
		(width 0.508)
		(layer "In4.Cu")
		(net "P3V3_STBY")
	)
	(segment
		(start 4.445 -48.3108)
		(end 4.445 -48.8442)
		(width 0.3048)
		(layer "In4.Cu")
		(net "P3V3_STBY")
	)
	(segment
		(start 83.33359 -21.6027)
		(end 85.311996 -21.6027)
		(width 0.508)
		(layer "In4.Cu")
		(net "P3V3_STBY")
	)
	(segment
		(start 77.3176 -22.4536)
		(end 78.0796 -21.6916)
		(width 0.508)
		(layer "In4.Cu")
		(net "P3V3_STBY")
	)
	(segment
		(start 192.3796 -36.2204)
		(end 194.056 -34.544)
		(width 0.508)
		(layer "In4.Cu")
		(net "P3V3_STBY")
	)
	(segment
		(start 78.0796 -21.6916)
		(end 83.24469 -21.6916)
		(width 0.508)
		(layer "In4.Cu")
		(net "P3V3_STBY")
	)
	(segment
		(start 198.374 -34.544)
		(end 198.628 -34.798)
		(width 0.508)
		(layer "In4.Cu")
		(net "P3V3_STBY")
	)
	(segment
		(start 7.9756 -49.276)
		(end 8.509 -49.8094)
		(width 0.3048)
		(layer "In4.Cu")
		(net "P3V3_STBY")
	)
	(segment
		(start 85.311996 -21.6027)
		(end 85.502496 -21.7932)
		(width 0.508)
		(layer "In4.Cu")
		(net "P3V3_STBY")
	)
	(segment
		(start 4.8768 -49.276)
		(end 7.9756 -49.276)
		(width 0.3048)
		(layer "In4.Cu")
		(net "P3V3_STBY")
	)
	(segment
		(start 181.5846 -33.5026)
		(end 184.3024 -36.2204)
		(width 0.508)
		(layer "In4.Cu")
		(net "P3V3_STBY")
	)
	(segment
		(start 89.608914 -21.7932)
		(end 93.1418 -18.260314)
		(width 0.508)
		(layer "In4.Cu")
		(net "P3V3_STBY")
	)
	(segment
		(start 93.1418 -18.260314)
		(end 93.1418 -17.4498)
		(width 0.508)
		(layer "In4.Cu")
		(net "P3V3_STBY")
	)
	(segment
		(start 85.502496 -21.7932)
		(end 89.608914 -21.7932)
		(width 0.508)
		(layer "In4.Cu")
		(net "P3V3_STBY")
	)
	(segment
		(start 184.3024 -36.2204)
		(end 192.3796 -36.2204)
		(width 0.508)
		(layer "In4.Cu")
		(net "P3V3_STBY")
	)
	(segment
		(start 68.13931 -38.7096)
		(end 68.77431 -38.0746)
		(width 0.508)
		(layer "In4.Cu")
		(net "P3V3_STBY")
	)
	(segment
		(start 4.445 -48.8442)
		(end 4.8768 -49.276)
		(width 0.3048)
		(layer "In4.Cu")
		(net "P3V3_STBY")
	)
	(segment
		(start 68.77431 -38.0746)
		(end 69.1642 -38.0746)
		(width 0.508)
		(layer "In4.Cu")
		(net "P3V3_STBY")
	)
	(segment
		(start 143.356838 -46.514258)
		(end 143.356838 -46.60392)
		(width 0.3048)
		(layer "In7.Cu")
		(net "P3V3_STBY")
	)
	(segment
		(start 190.459614 -4.155186)
		(end 190.459614 -9.565386)
		(width 0.508)
		(layer "In7.Cu")
		(net "P3V3_STBY")
	)
	(segment
		(start 30.744668 -37.3253)
		(end 31.5722 -36.497768)
		(width 1.016)
		(layer "In7.Cu")
		(net "P3V3_STBY")
	)
	(segment
		(start 184.5818 -48.6918)
		(end 180.12283 -48.6918)
		(width 0.3048)
		(layer "In7.Cu")
		(net "P3V3_STBY")
	)
	(segment
		(start 197.613778 -2.541778)
		(end 192.073022 -2.541778)
		(width 0.508)
		(layer "In7.Cu")
		(net "P3V3_STBY")
	)
	(segment
		(start 138.69289 -46.045374)
		(end 132.161026 -46.045374)
		(width 0.3048)
		(layer "In7.Cu")
		(net "P3V3_STBY")
	)
	(segment
		(start 139.281916 -46.6344)
		(end 139.866116 -46.0502)
		(width 0.3048)
		(layer "In7.Cu")
		(net "P3V3_STBY")
	)
	(segment
		(start 184.785 -20.828)
		(end 182.6006 -23.0124)
		(width 0.508)
		(layer "In7.Cu")
		(net "P3V3_STBY")
	)
	(segment
		(start 4.445 -49.784)
		(end 6.35 -51.689)
		(width 0.3048)
		(layer "In7.Cu")
		(net "P3V3_STBY")
	)
	(segment
		(start 150.4188 -36.83)
		(end 150.4188 -32.3088)
		(width 0.3048)
		(layer "In7.Cu")
		(net "P3V3_STBY")
	)
	(segment
		(start 166.6748 -36.576)
		(end 166.6748 -31.75)
		(width 0.508)
		(layer "In7.Cu")
		(net "P3V3_STBY")
	)
	(segment
		(start 32.7406 -25.8572)
		(end 34.0614 -24.5364)
		(width 1.016)
		(layer "In7.Cu")
		(net "P3V3_STBY")
	)
	(segment
		(start 205.994 -12.716256)
		(end 205.994 -6.096)
		(width 0.508)
		(layer "In7.Cu")
		(net "P3V3_STBY")
	)
	(segment
		(start 199.770746 -4.698746)
		(end 197.613778 -2.541778)
		(width 0.508)
		(layer "In7.Cu")
		(net "P3V3_STBY")
	)
	(segment
		(start 190.5254 -4.0894)
		(end 190.459614 -4.155186)
		(width 0.508)
		(layer "In7.Cu")
		(net "P3V3_STBY")
	)
	(segment
		(start 192.073022 -2.541778)
		(end 190.5254 -4.0894)
		(width 0.508)
		(layer "In7.Cu")
		(net "P3V3_STBY")
	)
	(segment
		(start 29.845 -37.3253)
		(end 30.744668 -37.3253)
		(width 1.016)
		(layer "In7.Cu")
		(net "P3V3_STBY")
	)
	(segment
		(start 188.7474 -49.657)
		(end 185.547 -49.657)
		(width 0.3048)
		(layer "In7.Cu")
		(net "P3V3_STBY")
	)
	(segment
		(start 205.994 -6.096)
		(end 204.596746 -4.698746)
		(width 0.508)
		(layer "In7.Cu")
		(net "P3V3_STBY")
	)
	(segment
		(start 143.356838 -46.60392)
		(end 143.357092 -46.604174)
		(width 0.3048)
		(layer "In7.Cu")
		(net "P3V3_STBY")
	)
	(segment
		(start 185.547 -49.657)
		(end 184.5818 -48.6918)
		(width 0.3048)
		(layer "In7.Cu")
		(net "P3V3_STBY")
	)
	(segment
		(start 190.459614 -9.565386)
		(end 184.785 -15.24)
		(width 0.508)
		(layer "In7.Cu")
		(net "P3V3_STBY")
	)
	(segment
		(start 184.785 -15.24)
		(end 184.785 -20.828)
		(width 0.508)
		(layer "In7.Cu")
		(net "P3V3_STBY")
	)
	(segment
		(start 7.747 -67.056)
		(end 9.525 -67.056)
		(width 0.3048)
		(layer "In7.Cu")
		(net "P3V3_STBY")
	)
	(segment
		(start 4.445 -48.3108)
		(end 4.445 -49.784)
		(width 0.3048)
		(layer "In7.Cu")
		(net "P3V3_STBY")
	)
	(segment
		(start 142.89278 -46.0502)
		(end 143.356838 -46.514258)
		(width 0.3048)
		(layer "In7.Cu")
		(net "P3V3_STBY")
	)
	(segment
		(start 180.12283 -48.6918)
		(end 178.11623 -46.6852)
		(width 0.3048)
		(layer "In7.Cu")
		(net "P3V3_STBY")
	)
	(segment
		(start 139.866116 -46.0502)
		(end 142.89278 -46.0502)
		(width 0.3048)
		(layer "In7.Cu")
		(net "P3V3_STBY")
	)
	(segment
		(start 31.5722 -33.600136)
		(end 31.3309 -33.358836)
		(width 1.016)
		(layer "In7.Cu")
		(net "P3V3_STBY")
	)
	(segment
		(start 32.7406 -29.605478)
		(end 32.7406 -25.8572)
		(width 1.016)
		(layer "In7.Cu")
		(net "P3V3_STBY")
	)
	(segment
		(start 204.224128 -14.486128)
		(end 205.994 -12.716256)
		(width 0.508)
		(layer "In7.Cu")
		(net "P3V3_STBY")
	)
	(segment
		(start 182.6006 -23.0124)
		(end 182.6006 -23.876)
		(width 0.508)
		(layer "In7.Cu")
		(net "P3V3_STBY")
	)
	(segment
		(start 204.596746 -4.698746)
		(end 199.770746 -4.698746)
		(width 0.508)
		(layer "In7.Cu")
		(net "P3V3_STBY")
	)
	(segment
		(start 132.161026 -46.045374)
		(end 131.6228 -46.5836)
		(width 0.3048)
		(layer "In7.Cu")
		(net "P3V3_STBY")
	)
	(segment
		(start 31.5722 -36.497768)
		(end 31.5722 -33.600136)
		(width 1.016)
		(layer "In7.Cu")
		(net "P3V3_STBY")
	)
	(segment
		(start 166.6748 -31.75)
		(end 166.0144 -31.0896)
		(width 0.508)
		(layer "In7.Cu")
		(net "P3V3_STBY")
	)
	(segment
		(start 31.3309 -31.015178)
		(end 32.7406 -29.605478)
		(width 1.016)
		(layer "In7.Cu")
		(net "P3V3_STBY")
	)
	(segment
		(start 150.4188 -32.3088)
		(end 150.7236 -32.004)
		(width 0.3048)
		(layer "In7.Cu")
		(net "P3V3_STBY")
	)
	(segment
		(start 31.3309 -33.358836)
		(end 31.3309 -31.015178)
		(width 1.016)
		(layer "In7.Cu")
		(net "P3V3_STBY")
	)
	(segment
		(start 6.35 -51.689)
		(end 6.35 -65.659)
		(width 0.3048)
		(layer "In7.Cu")
		(net "P3V3_STBY")
	)
	(segment
		(start 6.35 -65.659)
		(end 7.747 -67.056)
		(width 0.3048)
		(layer "In7.Cu")
		(net "P3V3_STBY")
	)
	(segment
		(start 139.281916 -46.6344)
		(end 138.69289 -46.045374)
		(width 0.3048)
		(layer "In7.Cu")
		(net "P3V3_STBY")
	)
	(segment
		(start 101.5746 -69.088)
		(end 87.6554 -69.088)
		(width 0.508)
		(layer "In9.Cu")
		(net "P3V3_STBY")
	)
	(segment
		(start 110.0582 -69.6214)
		(end 108.171488 -67.734688)
		(width 0.508)
		(layer "In9.Cu")
		(net "P3V3_STBY")
	)
	(segment
		(start 180.6448 -33.5026)
		(end 181.5846 -33.5026)
		(width 0.508)
		(layer "In9.Cu")
		(net "P3V3_STBY")
	)
	(segment
		(start 94.59087 -17.847056)
		(end 94.193614 -17.4498)
		(width 0.508)
		(layer "In9.Cu")
		(net "P3V3_STBY")
	)
	(segment
		(start 119.913654 -67.685412)
		(end 119.913654 -67.58686)
		(width 0.508)
		(layer "In9.Cu")
		(net "P3V3_STBY")
	)
	(segment
		(start 115.16614 -67.58686)
		(end 119.913654 -67.58686)
		(width 0.508)
		(layer "In9.Cu")
		(net "P3V3_STBY")
	)
	(segment
		(start 130.4798 -30.9118)
		(end 133.5786 -30.9118)
		(width 0.3048)
		(layer "In9.Cu")
		(net "P3V3_STBY")
	)
	(segment
		(start 113.6142 -68.9864)
		(end 114.1476 -69.5198)
		(width 0.508)
		(layer "In9.Cu")
		(net "P3V3_STBY")
	)
	(segment
		(start 110.6932 -68.9864)
		(end 113.6142 -68.9864)
		(width 0.508)
		(layer "In9.Cu")
		(net "P3V3_STBY")
	)
	(segment
		(start 114.6302 -10.179812)
		(end 106.962956 -17.847056)
		(width 0.508)
		(layer "In9.Cu")
		(net "P3V3_STBY")
	)
	(segment
		(start 110.0582 -69.6214)
		(end 110.6932 -68.9864)
		(width 0.508)
		(layer "In9.Cu")
		(net "P3V3_STBY")
	)
	(segment
		(start 129.921 -30.353)
		(end 130.4798 -30.9118)
		(width 0.3048)
		(layer "In9.Cu")
		(net "P3V3_STBY")
	)
	(segment
		(start 114.427 -68.326)
		(end 115.16614 -67.58686)
		(width 0.508)
		(layer "In9.Cu")
		(net "P3V3_STBY")
	)
	(segment
		(start 114.1476 -69.5198)
		(end 114.427 -69.2404)
		(width 0.508)
		(layer "In9.Cu")
		(net "P3V3_STBY")
	)
	(segment
		(start 67.564 -36.4744)
		(end 69.1642 -38.0746)
		(width 0.3048)
		(layer "In9.Cu")
		(net "P3V3_STBY")
	)
	(segment
		(start 68.3006 -32.864044)
		(end 67.564 -33.600644)
		(width 0.3048)
		(layer "In9.Cu")
		(net "P3V3_STBY")
	)
	(segment
		(start 108.120688 -67.734688)
		(end 105.918 -65.532)
		(width 0.508)
		(layer "In9.Cu")
		(net "P3V3_STBY")
	)
	(segment
		(start 114.6302 -5.5118)
		(end 114.6302 -10.179812)
		(width 0.508)
		(layer "In9.Cu")
		(net "P3V3_STBY")
	)
	(segment
		(start 166.751 -36.576)
		(end 166.878 -36.703)
		(width 0.508)
		(layer "In9.Cu")
		(net "P3V3_STBY")
	)
	(segment
		(start 67.564 -33.600644)
		(end 67.564 -36.4744)
		(width 0.3048)
		(layer "In9.Cu")
		(net "P3V3_STBY")
	)
	(segment
		(start 106.962956 -17.847056)
		(end 94.59087 -17.847056)
		(width 0.508)
		(layer "In9.Cu")
		(net "P3V3_STBY")
	)
	(segment
		(start 108.171488 -67.734688)
		(end 108.120688 -67.734688)
		(width 0.508)
		(layer "In9.Cu")
		(net "P3V3_STBY")
	)
	(segment
		(start 128.35001 -68.199)
		(end 128.27381 -68.2752)
		(width 0.508)
		(layer "In9.Cu")
		(net "P3V3_STBY")
	)
	(segment
		(start 114.427 -69.2404)
		(end 114.427 -68.326)
		(width 0.508)
		(layer "In9.Cu")
		(net "P3V3_STBY")
	)
	(segment
		(start 166.878 -36.703)
		(end 177.4444 -36.703)
		(width 0.508)
		(layer "In9.Cu")
		(net "P3V3_STBY")
	)
	(segment
		(start 120.503442 -68.2752)
		(end 119.913654 -67.685412)
		(width 0.508)
		(layer "In9.Cu")
		(net "P3V3_STBY")
	)
	(segment
		(start 133.5786 -30.9118)
		(end 134.1374 -30.353)
		(width 0.3048)
		(layer "In9.Cu")
		(net "P3V3_STBY")
	)
	(segment
		(start 177.4444 -36.703)
		(end 180.6448 -33.5026)
		(width 0.508)
		(layer "In9.Cu")
		(net "P3V3_STBY")
	)
	(segment
		(start 87.6554 -69.088)
		(end 87.2744 -68.707)
		(width 0.508)
		(layer "In9.Cu")
		(net "P3V3_STBY")
	)
	(segment
		(start 128.27381 -68.2752)
		(end 120.503442 -68.2752)
		(width 0.508)
		(layer "In9.Cu")
		(net "P3V3_STBY")
	)
	(segment
		(start 101.8286 -69.342)
		(end 101.5746 -69.088)
		(width 0.508)
		(layer "In9.Cu")
		(net "P3V3_STBY")
	)
	(segment
		(start 166.6748 -36.576)
		(end 166.751 -36.576)
		(width 0.508)
		(layer "In9.Cu")
		(net "P3V3_STBY")
	)
	(segment
		(start 94.193614 -17.4498)
		(end 93.1418 -17.4498)
		(width 0.508)
		(layer "In9.Cu")
		(net "P3V3_STBY")
	)
	(segment
		(start 38.23335 -37.83965)
		(end 38.23335 -37.549074)
		(width 0.1143)
		(layer "F.Cu")
		(net "SMB_XDP_DATA_R")
	)
	(segment
		(start 39.1287 -36.653724)
		(end 39.1287 -33.97758)
		(width 0.1143)
		(layer "F.Cu")
		(net "SMB_XDP_DATA_R")
	)
	(segment
		(start 40.5511 -32.55518)
		(end 42.10177 -32.55518)
		(width 0.1143)
		(layer "F.Cu")
		(net "SMB_XDP_DATA_R")
	)
	(segment
		(start 38.23335 -37.549074)
		(end 39.1287 -36.653724)
		(width 0.1143)
		(layer "F.Cu")
		(net "SMB_XDP_DATA_R")
	)
	(segment
		(start 37.592 -38.481)
		(end 38.23335 -37.83965)
		(width 0.1143)
		(layer "F.Cu")
		(net "SMB_XDP_DATA_R")
	)
	(segment
		(start 39.1287 -33.97758)
		(end 40.5511 -32.55518)
		(width 0.1143)
		(layer "F.Cu")
		(net "SMB_XDP_DATA_R")
	)
	(segment
		(start 37.592 -38.6842)
		(end 37.592 -38.481)
		(width 0.1143)
		(layer "F.Cu")
		(net "SMB_XDP_DATA_R")
	)
	(via
		(at 119.17553 -68.27647)
		(size 0.7112)
		(drill 0.3556)
		(layers "F.Cu" "B.Cu")
		(net "SMB_M_A0_R_CLK")
	)
	(segment
		(start 120.777 -69.1896)
		(end 119.9134 -68.326)
		(width 0.1143)
		(layer "B.Cu")
		(net "SMB_M_A0_R_CLK")
	)
	(segment
		(start 121.3358 -69.7484)
		(end 120.777 -69.1896)
		(width 0.1143)
		(layer "B.Cu")
		(net "SMB_M_A0_R_CLK")
	)
	(segment
		(start 127.450088 -69.538088)
		(end 126.873 -68.961)
		(width 0.1143)
		(layer "B.Cu")
		(net "SMB_M_A0_R_CLK")
	)
	(segment
		(start 119.22506 -68.326)
		(end 119.17553 -68.27647)
		(width 0.1143)
		(layer "B.Cu")
		(net "SMB_M_A0_R_CLK")
	)
	(segment
		(start 119.9134 -68.326)
		(end 119.22506 -68.326)
		(width 0.1143)
		(layer "B.Cu")
		(net "SMB_M_A0_R_CLK")
	)
	(segment
		(start 124.46 -68.961)
		(end 123.6726 -69.7484)
		(width 0.1143)
		(layer "B.Cu")
		(net "SMB_M_A0_R_CLK")
	)
	(segment
		(start 127.450088 -70.79996)
		(end 127.450088 -69.538088)
		(width 0.1143)
		(layer "B.Cu")
		(net "SMB_M_A0_R_CLK")
	)
	(segment
		(start 123.6726 -69.7484)
		(end 121.3358 -69.7484)
		(width 0.1143)
		(layer "B.Cu")
		(net "SMB_M_A0_R_CLK")
	)
	(segment
		(start 126.873 -68.961)
		(end 124.46 -68.961)
		(width 0.1143)
		(layer "B.Cu")
		(net "SMB_M_A0_R_CLK")
	)
	(segment
		(start 105.311448 -49.157636)
		(end 105.699306 -48.769778)
		(width 0.254)
		(layer "F.Cu")
		(net "PV_VDDR")
	)
	(segment
		(start 185.674 -53.975)
		(end 185.674 -53.3908)
		(width 0.3048)
		(layer "F.Cu")
		(net "PV_VDDR")
	)
	(segment
		(start 164.949886 -1.68402)
		(end 164.949886 -2.574798)
		(width 0.3048)
		(layer "F.Cu")
		(net "PV_VDDR")
	)
	(segment
		(start 106.147108 -46.914054)
		(end 106.120438 -46.914054)
		(width 0.254)
		(layer "F.Cu")
		(net "PV_VDDR")
	)
	(segment
		(start 107.7341 -30.181042)
		(end 108.0008 -30.181042)
		(width 0.254)
		(layer "F.Cu")
		(net "PV_VDDR")
	)
	(segment
		(start 106.665268 -50.251868)
		(end 106.3752 -49.9618)
		(width 0.254)
		(layer "F.Cu")
		(net "PV_VDDR")
	)
	(segment
		(start 105.6132 -59.6138)
		(end 108.077 -57.15)
		(width 0.254)
		(layer "F.Cu")
		(net "PV_VDDR")
	)
	(segment
		(start 188.1632 -41.9608)
		(end 188.0362 -41.8338)
		(width 0.508)
		(layer "F.Cu")
		(net "PV_VDDR")
	)
	(segment
		(start 100.492814 -47.69866)
		(end 100.053648 -47.259494)
		(width 0.254)
		(layer "F.Cu")
		(net "PV_VDDR")
	)
	(segment
		(start 157.750002 -69.498464)
		(end 157.590998 -69.33946)
		(width 0.3048)
		(layer "F.Cu")
		(net "PV_VDDR")
	)
	(segment
		(start 186.2582 -53.3908)
		(end 185.674 -53.3908)
		(width 0.3048)
		(layer "F.Cu")
		(net "PV_VDDR")
	)
	(segment
		(start 157.750002 -70.806564)
		(end 157.750002 -69.498464)
		(width 0.3048)
		(layer "F.Cu")
		(net "PV_VDDR")
	)
	(segment
		(start 110.256828 -50.104294)
		(end 110.195868 -50.043334)
		(width 0.254)
		(layer "F.Cu")
		(net "PV_VDDR")
	)
	(segment
		(start 107.201462 -47.3837)
		(end 107.149392 -47.3837)
		(width 0.254)
		(layer "F.Cu")
		(net "PV_VDDR")
	)
	(segment
		(start 106.251248 -29.235654)
		(end 106.251248 -29.266642)
		(width 0.254)
		(layer "F.Cu")
		(net "PV_VDDR")
	)
	(segment
		(start 184.64276 -48.91024)
		(end 184.277 -49.276)
		(width 0.3048)
		(layer "F.Cu")
		(net "PV_VDDR")
	)
	(segment
		(start 105.311448 -49.164494)
		(end 105.311448 -49.157636)
		(width 0.254)
		(layer "F.Cu")
		(net "PV_VDDR")
	)
	(segment
		(start 102.928674 -45.339)
		(end 103.325168 -45.735494)
		(width 0.254)
		(layer "F.Cu")
		(net "PV_VDDR")
	)
	(segment
		(start 108.245148 -28.131262)
		(end 108.585 -28.471114)
		(width 0.254)
		(layer "F.Cu")
		(net "PV_VDDR")
	)
	(segment
		(start 155.949904 -1.68402)
		(end 155.949904 -3.399282)
		(width 0.3048)
		(layer "F.Cu")
		(net "PV_VDDR")
	)
	(segment
		(start 108.890562 -47.2186)
		(end 108.8136 -47.2186)
		(width 0.254)
		(layer "F.Cu")
		(net "PV_VDDR")
	)
	(segment
		(start 104.391714 -47.625)
		(end 104.648 -47.625)
		(width 0.254)
		(layer "F.Cu")
		(net "PV_VDDR")
	)
	(segment
		(start 149.1488 -68.1482)
		(end 149.792182 -68.1482)
		(width 0.3048)
		(layer "F.Cu")
		(net "PV_VDDR")
	)
	(segment
		(start 187.198 -51.1048)
		(end 187.198 -52.451)
		(width 0.3048)
		(layer "F.Cu")
		(net "PV_VDDR")
	)
	(segment
		(start 155.421584 -69.474842)
		(end 155.547822 -69.348604)
		(width 0.3048)
		(layer "F.Cu")
		(net "PV_VDDR")
	)
	(segment
		(start 99.977702 -30.764988)
		(end 99.987862 -30.764988)
		(width 0.254)
		(layer "F.Cu")
		(net "PV_VDDR")
	)
	(segment
		(start 107.536488 -30.378654)
		(end 107.7341 -30.181042)
		(width 0.254)
		(layer "F.Cu")
		(net "PV_VDDR")
	)
	(segment
		(start 101.338888 -45.405294)
		(end 101.689408 -45.755814)
		(width 0.254)
		(layer "F.Cu")
		(net "PV_VDDR")
	)
	(segment
		(start 110.749588 -50.104294)
		(end 110.256828 -50.104294)
		(width 0.254)
		(layer "F.Cu")
		(net "PV_VDDR")
	)
	(segment
		(start 109.974888 -50.264314)
		(end 110.195868 -50.043334)
		(width 0.254)
		(layer "F.Cu")
		(net "PV_VDDR")
	)
	(segment
		(start 155.349956 -69.596)
		(end 155.421584 -69.524372)
		(width 0.3048)
		(layer "F.Cu")
		(net "PV_VDDR")
	)
	(segment
		(start 106.147108 -31.724854)
		(end 106.273854 -31.724854)
		(width 0.254)
		(layer "F.Cu")
		(net "PV_VDDR")
	)
	(segment
		(start 103.190548 -32.8549)
		(end 103.373682 -32.8549)
		(width 0.254)
		(layer "F.Cu")
		(net "PV_VDDR")
	)
	(segment
		(start 109.913928 -29.802836)
		(end 109.306868 -30.409896)
		(width 0.3048)
		(layer "F.Cu")
		(net "PV_VDDR")
	)
	(segment
		(start 102.278688 -30.759654)
		(end 102.278688 -30.842712)
		(width 0.254)
		(layer "F.Cu")
		(net "PV_VDDR")
	)
	(segment
		(start 101.919024 -32.70377)
		(end 102.260908 -33.045654)
		(width 0.254)
		(layer "F.Cu")
		(net "PV_VDDR")
	)
	(segment
		(start 135.001 -57.8739)
		(end 134.874 -58.0009)
		(width 0.3048)
		(layer "F.Cu")
		(net "PV_VDDR")
	)
	(segment
		(start 155.349956 -70.806564)
		(end 155.349956 -69.596)
		(width 0.3048)
		(layer "F.Cu")
		(net "PV_VDDR")
	)
	(segment
		(start 108.951268 -28.135834)
		(end 108.92028 -28.135834)
		(width 0.254)
		(layer "F.Cu")
		(net "PV_VDDR")
	)
	(segment
		(start 84.798408 -65.697608)
		(end 96.886522 -65.697608)
		(width 0.254)
		(layer "F.Cu")
		(net "PV_VDDR")
	)
	(segment
		(start 103.02367 -47.719996)
		(end 102.895908 -47.719996)
		(width 0.254)
		(layer "F.Cu")
		(net "PV_VDDR")
	)
	(segment
		(start 108.052108 -48.900334)
		(end 107.687364 -48.53559)
		(width 0.254)
		(layer "F.Cu")
		(net "PV_VDDR")
	)
	(segment
		(start 185.09996 -48.91024)
		(end 184.64276 -48.91024)
		(width 0.3048)
		(layer "F.Cu")
		(net "PV_VDDR")
	)
	(segment
		(start 160.749996 -2.99212)
		(end 160.909 -3.151124)
		(width 0.3048)
		(layer "F.Cu")
		(net "PV_VDDR")
	)
	(segment
		(start 163.150042 -1.68402)
		(end 163.150042 -2.894584)
		(width 0.3048)
		(layer "F.Cu")
		(net "PV_VDDR")
	)
	(segment
		(start 135.001 -57.277)
		(end 135.001 -57.8739)
		(width 0.3048)
		(layer "F.Cu")
		(net "PV_VDDR")
	)
	(segment
		(start 135.94334 -56.960516)
		(end 135.317484 -56.960516)
		(width 0.3048)
		(layer "F.Cu")
		(net "PV_VDDR")
	)
	(segment
		(start 160.749996 -1.68402)
		(end 160.749996 -2.99212)
		(width 0.3048)
		(layer "F.Cu")
		(net "PV_VDDR")
	)
	(segment
		(start 187.198 -52.451)
		(end 186.2582 -53.3908)
		(width 0.3048)
		(layer "F.Cu")
		(net "PV_VDDR")
	)
	(segment
		(start 101.338888 -45.354494)
		(end 101.338888 -45.405294)
		(width 0.254)
		(layer "F.Cu")
		(net "PV_VDDR")
	)
	(segment
		(start 103.581454 -30.378654)
		(end 103.91394 -30.71114)
		(width 0.254)
		(layer "F.Cu")
		(net "PV_VDDR")
	)
	(segment
		(start 167.105838 -3.07594)
		(end 167.105838 -3.176016)
		(width 0.3048)
		(layer "F.Cu")
		(net "PV_VDDR")
	)
	(segment
		(start 108.557568 -53.034946)
		(end 108.278168 -52.755546)
		(width 0.254)
		(layer "F.Cu")
		(net "PV_VDDR")
	)
	(segment
		(start 106.012488 -48.402494)
		(end 106.012488 -48.456596)
		(width 0.254)
		(layer "F.Cu")
		(net "PV_VDDR")
	)
	(segment
		(start 99.352608 -48.021494)
		(end 99.352608 -48.00219)
		(width 0.254)
		(layer "F.Cu")
		(net "PV_VDDR")
	)
	(segment
		(start 106.251248 -29.266642)
		(end 105.898188 -29.619702)
		(width 0.254)
		(layer "F.Cu")
		(net "PV_VDDR")
	)
	(segment
		(start 109.195108 -46.914054)
		(end 108.890562 -47.2186)
		(width 0.254)
		(layer "F.Cu")
		(net "PV_VDDR")
	)
	(segment
		(start 99.591368 -32.664654)
		(end 99.591368 -32.664146)
		(width 0.254)
		(layer "F.Cu")
		(net "PV_VDDR")
	)
	(segment
		(start 108.077 -56.515)
		(end 108.557568 -56.034432)
		(width 0.254)
		(layer "F.Cu")
		(net "PV_VDDR")
	)
	(segment
		(start 155.949904 -3.399282)
		(end 156.1338 -3.583178)
		(width 0.3048)
		(layer "F.Cu")
		(net "PV_VDDR")
	)
	(segment
		(start 109.289088 -50.741834)
		(end 109.766608 -50.264314)
		(width 0.254)
		(layer "F.Cu")
		(net "PV_VDDR")
	)
	(segment
		(start 135.317484 -56.960516)
		(end 135.001 -57.277)
		(width 0.3048)
		(layer "F.Cu")
		(net "PV_VDDR")
	)
	(segment
		(start 201.3712 -47.337726)
		(end 201.3712 -46.8249)
		(width 0.2032)
		(layer "F.Cu")
		(net "PV_VDDR")
	)
	(segment
		(start 165.321488 -2.9464)
		(end 165.321488 -3.026664)
		(width 0.3048)
		(layer "F.Cu")
		(net "PV_VDDR")
	)
	(segment
		(start 107.671108 -46.914054)
		(end 107.201462 -47.3837)
		(width 0.254)
		(layer "F.Cu")
		(net "PV_VDDR")
	)
	(segment
		(start 107.238546 -32.105854)
		(end 107.2642 -32.0802)
		(width 0.254)
		(layer "F.Cu")
		(net "PV_VDDR")
	)
	(segment
		(start 102.352348 -47.952914)
		(end 102.352348 -48.009556)
		(width 0.254)
		(layer "F.Cu")
		(net "PV_VDDR")
	)
	(segment
		(start 109.432852 -29.49067)
		(end 109.195108 -29.252926)
		(width 0.254)
		(layer "F.Cu")
		(net "PV_VDDR")
	)
	(segment
		(start 105.550208 -29.235654)
		(end 105.550208 -29.271722)
		(width 0.254)
		(layer "F.Cu")
		(net "PV_VDDR")
	)
	(segment
		(start 108.245148 -28.120594)
		(end 108.245148 -28.131262)
		(width 0.254)
		(layer "F.Cu")
		(net "PV_VDDR")
	)
	(segment
		(start 186.817 -45.5422)
		(end 186.817 -45.3898)
		(width 0.3048)
		(layer "F.Cu")
		(net "PV_VDDR")
	)
	(segment
		(start 106.120438 -46.914054)
		(end 105.74401 -46.537626)
		(width 0.254)
		(layer "F.Cu")
		(net "PV_VDDR")
	)
	(segment
		(start 162.550094 -68.392294)
		(end 162.433 -68.2752)
		(width 0.3048)
		(layer "F.Cu")
		(net "PV_VDDR")
	)
	(segment
		(start 104.026208 -49.545494)
		(end 104.734106 -49.545494)
		(width 0.254)
		(layer "F.Cu")
		(net "PV_VDDR")
	)
	(segment
		(start 107.687364 -48.53559)
		(end 107.687364 -48.474884)
		(width 0.254)
		(layer "F.Cu")
		(net "PV_VDDR")
	)
	(segment
		(start 102.039928 -45.405294)
		(end 101.689408 -45.755814)
		(width 0.254)
		(layer "F.Cu")
		(net "PV_VDDR")
	)
	(segment
		(start 107.1372 -21.5646)
		(end 108.6231 -23.0505)
		(width 0.3048)
		(layer "F.Cu")
		(net "PV_VDDR")
	)
	(segment
		(start 163.078414 -3.066034)
		(end 163.00323 -3.141218)
		(width 0.3048)
		(layer "F.Cu")
		(net "PV_VDDR")
	)
	(segment
		(start 109.306868 -30.409896)
		(end 109.704886 -30.807914)
		(width 0.3048)
		(layer "F.Cu")
		(net "PV_VDDR")
	)
	(segment
		(start 103.18115 -32.845502)
		(end 103.190548 -32.8549)
		(width 0.254)
		(layer "F.Cu")
		(net "PV_VDDR")
	)
	(segment
		(start 106.012488 -48.456596)
		(end 105.699306 -48.769778)
		(width 0.254)
		(layer "F.Cu")
		(net "PV_VDDR")
	)
	(segment
		(start 109.195108 -29.252926)
		(end 109.195108 -29.037534)
		(width 0.254)
		(layer "F.Cu")
		(net "PV_VDDR")
	)
	(segment
		(start 101.689408 -45.755814)
		(end 101.689408 -45.763434)
		(width 0.254)
		(layer "F.Cu")
		(net "PV_VDDR")
	)
	(segment
		(start 104.264968 -30.378654)
		(end 104.241346 -30.378654)
		(width 0.254)
		(layer "F.Cu")
		(net "PV_VDDR")
	)
	(segment
		(start 102.260908 -33.045654)
		(end 102.278688 -33.045654)
		(width 0.254)
		(layer "F.Cu")
		(net "PV_VDDR")
	)
	(segment
		(start 188.976 -41.9608)
		(end 188.1632 -41.9608)
		(width 0.508)
		(layer "F.Cu")
		(net "PV_VDDR")
	)
	(segment
		(start 108.072428 -51.70678)
		(end 108.282994 -51.917346)
		(width 0.254)
		(layer "F.Cu")
		(net "PV_VDDR")
	)
	(segment
		(start 103.91394 -30.70606)
		(end 103.91394 -30.71114)
		(width 0.254)
		(layer "F.Cu")
		(net "PV_VDDR")
	)
	(segment
		(start 99.352608 -48.00219)
		(end 99.719384 -47.635414)
		(width 0.254)
		(layer "F.Cu")
		(net "PV_VDDR")
	)
	(segment
		(start 163.078414 -2.966212)
		(end 163.078414 -3.066034)
		(width 0.3048)
		(layer "F.Cu")
		(net "PV_VDDR")
	)
	(segment
		(start 184.8612 -16.3068)
		(end 185.260234 -16.705834)
		(width 0.3048)
		(layer "F.Cu")
		(net "PV_VDDR")
	)
	(segment
		(start 101.981 -31.1404)
		(end 101.958394 -31.1404)
		(width 0.254)
		(layer "F.Cu")
		(net "PV_VDDR")
	)
	(segment
		(start 169.749978 -4.219956)
		(end 170.0784 -4.548378)
		(width 0.3048)
		(layer "F.Cu")
		(net "PV_VDDR")
	)
	(segment
		(start 102.8954 -45.339)
		(end 102.928674 -45.339)
		(width 0.254)
		(layer "F.Cu")
		(net "PV_VDDR")
	)
	(segment
		(start 101.958394 -31.1404)
		(end 101.577648 -30.759654)
		(width 0.254)
		(layer "F.Cu")
		(net "PV_VDDR")
	)
	(segment
		(start 186.817 -45.3898)
		(end 186.182 -44.7548)
		(width 0.3048)
		(layer "F.Cu")
		(net "PV_VDDR")
	)
	(segment
		(start 108.278168 -52.132484)
		(end 108.282994 -52.127658)
		(width 0.254)
		(layer "F.Cu")
		(net "PV_VDDR")
	)
	(segment
		(start 102.039928 -45.354494)
		(end 102.039928 -45.405294)
		(width 0.254)
		(layer "F.Cu")
		(net "PV_VDDR")
	)
	(segment
		(start 106.665268 -50.404014)
		(end 106.665268 -50.251868)
		(width 0.254)
		(layer "F.Cu")
		(net "PV_VDDR")
	)
	(segment
		(start 101.338888 -48.402494)
		(end 101.022912 -48.086518)
		(width 0.254)
		(layer "F.Cu")
		(net "PV_VDDR")
	)
	(segment
		(start 153.550112 -69.907912)
		(end 153.0223 -69.3801)
		(width 0.3048)
		(layer "F.Cu")
		(net "PV_VDDR")
	)
	(segment
		(start 108.282994 -52.127658)
		(end 108.282994 -51.917346)
		(width 0.254)
		(layer "F.Cu")
		(net "PV_VDDR")
	)
	(segment
		(start 160.150048 -70.806564)
		(end 160.150048 -69.48551)
		(width 0.3048)
		(layer "F.Cu")
		(net "PV_VDDR")
	)
	(segment
		(start 105.550208 -29.271722)
		(end 105.898188 -29.619702)
		(width 0.254)
		(layer "F.Cu")
		(net "PV_VDDR")
	)
	(segment
		(start 148.75002 -68.54698)
		(end 149.1488 -68.1482)
		(width 0.3048)
		(layer "F.Cu")
		(net "PV_VDDR")
	)
	(segment
		(start 100.292408 -32.618934)
		(end 100.292408 -32.664654)
		(width 0.254)
		(layer "F.Cu")
		(net "PV_VDDR")
	)
	(segment
		(start 108.6231 -23.0505)
		(end 108.6231 -24.638)
		(width 0.3048)
		(layer "F.Cu")
		(net "PV_VDDR")
	)
	(segment
		(start 102.822502 -32.845502)
		(end 103.18115 -32.845502)
		(width 0.254)
		(layer "F.Cu")
		(net "PV_VDDR")
	)
	(segment
		(start 105.403142 -46.878494)
		(end 105.74401 -46.537626)
		(width 0.254)
		(layer "F.Cu")
		(net "PV_VDDR")
	)
	(segment
		(start 109.704886 -30.807914)
		(end 109.913928 -30.807914)
		(width 0.3048)
		(layer "F.Cu")
		(net "PV_VDDR")
	)
	(segment
		(start 109.913928 -29.786834)
		(end 109.913928 -29.802836)
		(width 0.3048)
		(layer "F.Cu")
		(net "PV_VDDR")
	)
	(segment
		(start 106.062526 -50.274474)
		(end 106.3752 -49.9618)
		(width 0.254)
		(layer "F.Cu")
		(net "PV_VDDR")
	)
	(segment
		(start 101.022912 -48.086518)
		(end 101.022912 -48.019462)
		(width 0.254)
		(layer "F.Cu")
		(net "PV_VDDR")
	)
	(segment
		(start 104.241346 -30.378654)
		(end 103.91394 -30.70606)
		(width 0.254)
		(layer "F.Cu")
		(net "PV_VDDR")
	)
	(segment
		(start 105.181654 -31.5214)
		(end 105.385108 -31.724854)
		(width 0.254)
		(layer "F.Cu")
		(net "PV_VDDR")
	)
	(segment
		(start 160.150048 -69.48551)
		(end 160.003998 -69.33946)
		(width 0.3048)
		(layer "F.Cu")
		(net "PV_VDDR")
	)
	(segment
		(start 108.557568 -56.034432)
		(end 108.557568 -53.034946)
		(width 0.254)
		(layer "F.Cu")
		(net "PV_VDDR")
	)
	(segment
		(start 164.949886 -2.574798)
		(end 165.321488 -2.9464)
		(width 0.3048)
		(layer "F.Cu")
		(net "PV_VDDR")
	)
	(segment
		(start 104.026208 -47.259494)
		(end 104.391714 -47.625)
		(width 0.254)
		(layer "F.Cu")
		(net "PV_VDDR")
	)
	(segment
		(start 100.292408 -30.378654)
		(end 100.292408 -30.460442)
		(width 0.254)
		(layer "F.Cu")
		(net "PV_VDDR")
	)
	(segment
		(start 108.072428 -51.447954)
		(end 108.072428 -51.70678)
		(width 0.254)
		(layer "F.Cu")
		(net "PV_VDDR")
	)
	(segment
		(start 103.325168 -48.021494)
		(end 103.02367 -47.719996)
		(width 0.254)
		(layer "F.Cu")
		(net "PV_VDDR")
	)
	(segment
		(start 105.969308 -50.274474)
		(end 106.062526 -50.274474)
		(width 0.254)
		(layer "F.Cu")
		(net "PV_VDDR")
	)
	(segment
		(start 104.8004 -31.5214)
		(end 105.181654 -31.5214)
		(width 0.254)
		(layer "F.Cu")
		(net "PV_VDDR")
	)
	(segment
		(start 101.551994 -33.02)
		(end 101.577648 -33.045654)
		(width 0.254)
		(layer "F.Cu")
		(net "PV_VDDR")
	)
	(segment
		(start 106.273854 -31.724854)
		(end 106.654854 -32.105854)
		(width 0.254)
		(layer "F.Cu")
		(net "PV_VDDR")
	)
	(segment
		(start 108.278168 -52.755546)
		(end 108.278168 -52.132484)
		(width 0.254)
		(layer "F.Cu")
		(net "PV_VDDR")
	)
	(segment
		(start 201.70394 -47.670466)
		(end 201.3712 -47.337726)
		(width 0.2032)
		(layer "F.Cu")
		(net "PV_VDDR")
	)
	(segment
		(start 151.150066 -69.402706)
		(end 151.228044 -69.324728)
		(width 0.3048)
		(layer "F.Cu")
		(net "PV_VDDR")
	)
	(segment
		(start 109.931708 -29.080714)
		(end 109.521752 -29.49067)
		(width 0.254)
		(layer "F.Cu")
		(net "PV_VDDR")
	)
	(segment
		(start 109.521752 -29.49067)
		(end 109.432852 -29.49067)
		(width 0.254)
		(layer "F.Cu")
		(net "PV_VDDR")
	)
	(segment
		(start 167.349932 -1.68402)
		(end 167.349932 -2.831846)
		(width 0.3048)
		(layer "F.Cu")
		(net "PV_VDDR")
	)
	(segment
		(start 100.292408 -30.460442)
		(end 99.987862 -30.764988)
		(width 0.254)
		(layer "F.Cu")
		(net "PV_VDDR")
	)
	(segment
		(start 149.792182 -68.1482)
		(end 149.8346 -68.105782)
		(width 0.3048)
		(layer "F.Cu")
		(net "PV_VDDR")
	)
	(segment
		(start 169.749978 -1.68402)
		(end 169.749978 -4.219956)
		(width 0.3048)
		(layer "F.Cu")
		(net "PV_VDDR")
	)
	(segment
		(start 111.510826 -31.481014)
		(end 111.57585 -31.546038)
		(width 0.254)
		(layer "F.Cu")
		(net "PV_VDDR")
	)
	(segment
		(start 108.6231 -24.638)
		(end 108.4072 -24.8539)
		(width 0.3048)
		(layer "F.Cu")
		(net "PV_VDDR")
	)
	(segment
		(start 107.75823 -49.911)
		(end 108.041948 -50.194718)
		(width 0.254)
		(layer "F.Cu")
		(net "PV_VDDR")
	)
	(segment
		(start 162.550094 -70.806564)
		(end 162.550094 -68.392294)
		(width 0.3048)
		(layer "F.Cu")
		(net "PV_VDDR")
	)
	(segment
		(start 153.0223 -69.3801)
		(end 153.0223 -69.3166)
		(width 0.3048)
		(layer "F.Cu")
		(net "PV_VDDR")
	)
	(segment
		(start 151.150066 -70.806564)
		(end 151.150066 -69.402706)
		(width 0.3048)
		(layer "F.Cu")
		(net "PV_VDDR")
	)
	(segment
		(start 102.278688 -30.842712)
		(end 101.981 -31.1404)
		(width 0.254)
		(layer "F.Cu")
		(net "PV_VDDR")
	)
	(segment
		(start 99.591368 -30.378654)
		(end 99.977702 -30.764988)
		(width 0.254)
		(layer "F.Cu")
		(net "PV_VDDR")
	)
	(segment
		(start 155.421584 -69.524372)
		(end 155.421584 -69.474842)
		(width 0.3048)
		(layer "F.Cu")
		(net "PV_VDDR")
	)
	(segment
		(start 104.264968 -32.664654)
		(end 104.19207 -32.591756)
		(width 0.254)
		(layer "F.Cu")
		(net "PV_VDDR")
	)
	(segment
		(start 103.636826 -32.591756)
		(end 103.563928 -32.664654)
		(width 0.254)
		(layer "F.Cu")
		(net "PV_VDDR")
	)
	(segment
		(start 105.311448 -46.878494)
		(end 105.403142 -46.878494)
		(width 0.254)
		(layer "F.Cu")
		(net "PV_VDDR")
	)
	(segment
		(start 158.34995 -3.005074)
		(end 158.496 -3.151124)
		(width 0.3048)
		(layer "F.Cu")
		(net "PV_VDDR")
	)
	(segment
		(start 107.1372 -20.701)
		(end 107.1372 -21.5646)
		(width 0.3048)
		(layer "F.Cu")
		(net "PV_VDDR")
	)
	(segment
		(start 103.373682 -32.8549)
		(end 103.563928 -32.664654)
		(width 0.254)
		(layer "F.Cu")
		(net "PV_VDDR")
	)
	(segment
		(start 99.591368 -32.664146)
		(end 99.964494 -32.29102)
		(width 0.254)
		(layer "F.Cu")
		(net "PV_VDDR")
	)
	(segment
		(start 185.3692 -54.2798)
		(end 185.674 -53.975)
		(width 0.3048)
		(layer "F.Cu")
		(net "PV_VDDR")
	)
	(segment
		(start 104.19207 -32.591756)
		(end 103.636826 -32.591756)
		(width 0.254)
		(layer "F.Cu")
		(net "PV_VDDR")
	)
	(segment
		(start 109.256068 -50.741834)
		(end 109.289088 -50.741834)
		(width 0.254)
		(layer "F.Cu")
		(net "PV_VDDR")
	)
	(segment
		(start 82.8548 -63.754)
		(end 84.798408 -65.697608)
		(width 0.254)
		(layer "F.Cu")
		(net "PV_VDDR")
	)
	(segment
		(start 99.964494 -32.29102)
		(end 100.292408 -32.618934)
		(width 0.254)
		(layer "F.Cu")
		(net "PV_VDDR")
	)
	(segment
		(start 184.912 -54.2798)
		(end 185.3692 -54.2798)
		(width 0.3048)
		(layer "F.Cu")
		(net "PV_VDDR")
	)
	(segment
		(start 108.92028 -28.135834)
		(end 108.585 -28.471114)
		(width 0.254)
		(layer "F.Cu")
		(net "PV_VDDR")
	)
	(segment
		(start 102.039928 -47.640494)
		(end 102.352348 -47.952914)
		(width 0.254)
		(layer "F.Cu")
		(net "PV_VDDR")
	)
	(segment
		(start 100.492814 -47.76343)
		(end 100.492814 -47.69866)
		(width 0.254)
		(layer "F.Cu")
		(net "PV_VDDR")
	)
	(segment
		(start 163.150042 -2.894584)
		(end 163.078414 -2.966212)
		(width 0.3048)
		(layer "F.Cu")
		(net "PV_VDDR")
	)
	(segment
		(start 109.766608 -50.264314)
		(end 109.974888 -50.264314)
		(width 0.254)
		(layer "F.Cu")
		(net "PV_VDDR")
	)
	(segment
		(start 106.654854 -32.105854)
		(end 107.238546 -32.105854)
		(width 0.254)
		(layer "F.Cu")
		(net "PV_VDDR")
	)
	(segment
		(start 96.886522 -65.697608)
		(end 102.97033 -59.6138)
		(width 0.254)
		(layer "F.Cu")
		(net "PV_VDDR")
	)
	(segment
		(start 107.6452 -49.911)
		(end 107.75823 -49.911)
		(width 0.254)
		(layer "F.Cu")
		(net "PV_VDDR")
	)
	(segment
		(start 108.041948 -50.194718)
		(end 108.041948 -50.213514)
		(width 0.254)
		(layer "F.Cu")
		(net "PV_VDDR")
	)
	(segment
		(start 153.550112 -70.806564)
		(end 153.550112 -69.907912)
		(width 0.3048)
		(layer "F.Cu")
		(net "PV_VDDR")
	)
	(segment
		(start 185.260234 -16.705834)
		(end 185.260234 -17.23771)
		(width 0.3048)
		(layer "F.Cu")
		(net "PV_VDDR")
	)
	(segment
		(start 104.734106 -49.545494)
		(end 104.775 -49.5046)
		(width 0.254)
		(layer "F.Cu")
		(net "PV_VDDR")
	)
	(segment
		(start 167.349932 -2.831846)
		(end 167.105838 -3.07594)
		(width 0.3048)
		(layer "F.Cu")
		(net "PV_VDDR")
	)
	(segment
		(start 102.97033 -59.6138)
		(end 105.6132 -59.6138)
		(width 0.254)
		(layer "F.Cu")
		(net "PV_VDDR")
	)
	(segment
		(start 111.097568 -31.481014)
		(end 111.510826 -31.481014)
		(width 0.254)
		(layer "F.Cu")
		(net "PV_VDDR")
	)
	(segment
		(start 158.34995 -1.68402)
		(end 158.34995 -3.005074)
		(width 0.3048)
		(layer "F.Cu")
		(net "PV_VDDR")
	)
	(segment
		(start 184.277 -49.276)
		(end 184.277 -49.657)
		(width 0.3048)
		(layer "F.Cu")
		(net "PV_VDDR")
	)
	(segment
		(start 108.077 -57.15)
		(end 108.077 -56.515)
		(width 0.254)
		(layer "F.Cu")
		(net "PV_VDDR")
	)
	(segment
		(start 101.0412 -33.02)
		(end 101.551994 -33.02)
		(width 0.254)
		(layer "F.Cu")
		(net "PV_VDDR")
	)
	(segment
		(start 102.7176 -32.7406)
		(end 102.822502 -32.845502)
		(width 0.254)
		(layer "F.Cu")
		(net "PV_VDDR")
	)
	(segment
		(start 103.563928 -30.378654)
		(end 103.581454 -30.378654)
		(width 0.254)
		(layer "F.Cu")
		(net "PV_VDDR")
	)
	(segment
		(start 148.75002 -70.806564)
		(end 148.75002 -68.54698)
		(width 0.3048)
		(layer "F.Cu")
		(net "PV_VDDR")
	)
	(segment
		(start 165.321488 -3.026664)
		(end 165.434264 -3.13944)
		(width 0.3048)
		(layer "F.Cu")
		(net "PV_VDDR")
	)
	(via
		(at 194.945 -6.097778)
		(size 0.7112)
		(drill 0.4064)
		(layers "F.Cu" "B.Cu")
		(net "PV_VDDR")
	)
	(via
		(at 186.182 -47.0154)
		(size 0.7112)
		(drill 0.3556)
		(layers "F.Cu" "B.Cu")
		(net "PV_VDDR")
	)
	(via
		(at 158.4706 -60.8584)
		(size 0.7112)
		(drill 0.4064)
		(layers "F.Cu" "B.Cu")
		(net "PV_VDDR")
	)
	(via
		(at 155.547822 -69.348604)
		(size 0.4318)
		(drill 0.2032)
		(layers "F.Cu" "B.Cu")
		(net "PV_VDDR")
	)
	(via
		(at 200.4568 -53.2892)
		(size 0.7112)
		(drill 0.4064)
		(layers "F.Cu" "B.Cu")
		(net "PV_VDDR")
	)
	(via
		(at 110.195868 -50.043334)
		(size 0.4318)
		(drill 0.2032)
		(layers "F.Cu" "B.Cu")
		(net "PV_VDDR")
	)
	(via
		(at 188.0362 -41.8338)
		(size 0.508)
		(drill 0.254)
		(layers "F.Cu" "B.Cu")
		(net "PV_VDDR")
	)
	(via
		(at 202.0062 -66.2432)
		(size 0.7112)
		(drill 0.4064)
		(layers "F.Cu" "B.Cu")
		(net "PV_VDDR")
	)
	(via
		(at 160.136078 -66.759328)
		(size 0.4318)
		(drill 0.2032)
		(layers "F.Cu" "B.Cu")
		(net "PV_VDDR")
	)
	(via
		(at 107.6452 -49.911)
		(size 0.4318)
		(drill 0.2032)
		(layers "F.Cu" "B.Cu")
		(net "PV_VDDR")
	)
	(via
		(at 167.005 -65.6336)
		(size 0.7112)
		(drill 0.4064)
		(layers "F.Cu" "B.Cu")
		(net "PV_VDDR")
	)
	(via
		(at 160.275778 -5.767578)
		(size 0.4318)
		(drill 0.2032)
		(layers "F.Cu" "B.Cu")
		(net "PV_VDDR")
	)
	(via
		(at 201.549 -52.064666)
		(size 0.7112)
		(drill 0.4064)
		(layers "F.Cu" "B.Cu")
		(net "PV_VDDR")
	)
	(via
		(at 155.344622 -66.51879)
		(size 0.4318)
		(drill 0.2032)
		(layers "F.Cu" "B.Cu")
		(net "PV_VDDR")
	)
	(via
		(at 199.39 -64.7446)
		(size 0.7112)
		(drill 0.4064)
		(layers "F.Cu" "B.Cu")
		(net "PV_VDDR")
	)
	(via
		(at 191.897 -4.064)
		(size 0.7112)
		(drill 0.4064)
		(layers "F.Cu" "B.Cu")
		(net "PV_VDDR")
	)
	(via
		(at 200.406 -62.357)
		(size 0.7112)
		(drill 0.3556)
		(layers "F.Cu" "B.Cu")
		(net "PV_VDDR")
	)
	(via
		(at 163.133278 -5.919978)
		(size 0.4318)
		(drill 0.2032)
		(layers "F.Cu" "B.Cu")
		(net "PV_VDDR")
	)
	(via
		(at 183.1848 -16.5354)
		(size 0.7112)
		(drill 0.4064)
		(layers "F.Cu" "B.Cu")
		(net "PV_VDDR")
	)
	(via
		(at 107.149392 -47.3837)
		(size 0.4318)
		(drill 0.2032)
		(layers "F.Cu" "B.Cu")
		(net "PV_VDDR")
	)
	(via
		(at 193.167 -7.366)
		(size 0.7112)
		(drill 0.4064)
		(layers "F.Cu" "B.Cu")
		(net "PV_VDDR")
	)
	(via
		(at 156.31922 -66.602102)
		(size 0.4318)
		(drill 0.2032)
		(layers "F.Cu" "B.Cu")
		(net "PV_VDDR")
	)
	(via
		(at 108.585 -28.471114)
		(size 0.4318)
		(drill 0.2032)
		(layers "F.Cu" "B.Cu")
		(net "PV_VDDR")
	)
	(via
		(at 99.987862 -30.764988)
		(size 0.4318)
		(drill 0.2032)
		(layers "F.Cu" "B.Cu")
		(net "PV_VDDR")
	)
	(via
		(at 202.946 -30.861)
		(size 0.5588)
		(drill 0.3048)
		(layers "F.Cu" "B.Cu")
		(net "PV_VDDR")
	)
	(via
		(at 199.39 -63.5508)
		(size 0.7112)
		(drill 0.4064)
		(layers "F.Cu" "B.Cu")
		(net "PV_VDDR")
	)
	(via
		(at 158.496 -3.151124)
		(size 0.4318)
		(drill 0.2032)
		(layers "F.Cu" "B.Cu")
		(net "PV_VDDR")
	)
	(via
		(at 149.941788 -66.639694)
		(size 0.4318)
		(drill 0.2032)
		(layers "F.Cu" "B.Cu")
		(net "PV_VDDR")
	)
	(via
		(at 167.972232 -66.979292)
		(size 0.7112)
		(drill 0.4064)
		(layers "F.Cu" "B.Cu")
		(net "PV_VDDR")
	)
	(via
		(at 166.624 -66.3956)
		(size 0.7112)
		(drill 0.4064)
		(layers "F.Cu" "B.Cu")
		(net "PV_VDDR")
	)
	(via
		(at 103.91394 -30.71114)
		(size 0.4318)
		(drill 0.2032)
		(layers "F.Cu" "B.Cu")
		(net "PV_VDDR")
	)
	(via
		(at 104.775 -49.5046)
		(size 0.4318)
		(drill 0.2032)
		(layers "F.Cu" "B.Cu")
		(net "PV_VDDR")
	)
	(via
		(at 201.4728 -59.0804)
		(size 0.7112)
		(drill 0.4064)
		(layers "F.Cu" "B.Cu")
		(net "PV_VDDR")
	)
	(via
		(at 200.4568 -54.4068)
		(size 0.7112)
		(drill 0.4064)
		(layers "F.Cu" "B.Cu")
		(net "PV_VDDR")
	)
	(via
		(at 202.0062 -65.151)
		(size 0.7112)
		(drill 0.4064)
		(layers "F.Cu" "B.Cu")
		(net "PV_VDDR")
	)
	(via
		(at 156.221176 -8.43026)
		(size 0.4318)
		(drill 0.2032)
		(layers "F.Cu" "B.Cu")
		(net "PV_VDDR")
	)
	(via
		(at 202.0062 -67.31)
		(size 0.7112)
		(drill 0.4064)
		(layers "F.Cu" "B.Cu")
		(net "PV_VDDR")
	)
	(via
		(at 102.895908 -47.719996)
		(size 0.4318)
		(drill 0.2032)
		(layers "F.Cu" "B.Cu")
		(net "PV_VDDR")
	)
	(via
		(at 202.946 -31.877)
		(size 0.5588)
		(drill 0.3048)
		(layers "F.Cu" "B.Cu")
		(net "PV_VDDR")
	)
	(via
		(at 201.549 -56.769)
		(size 0.7112)
		(drill 0.4064)
		(layers "F.Cu" "B.Cu")
		(net "PV_VDDR")
	)
	(via
		(at 202.0316 -63.9318)
		(size 0.7112)
		(drill 0.4064)
		(layers "F.Cu" "B.Cu")
		(net "PV_VDDR")
	)
	(via
		(at 156.451554 -5.678424)
		(size 0.4318)
		(drill 0.2032)
		(layers "F.Cu" "B.Cu")
		(net "PV_VDDR")
	)
	(via
		(at 199.6948 -60.1726)
		(size 0.7112)
		(drill 0.4064)
		(layers "F.Cu" "B.Cu")
		(net "PV_VDDR")
	)
	(via
		(at 166.243 -11.711178)
		(size 0.7112)
		(drill 0.4064)
		(layers "F.Cu" "B.Cu")
		(net "PV_VDDR")
	)
	(via
		(at 158.5214 -8.43026)
		(size 0.4318)
		(drill 0.2032)
		(layers "F.Cu" "B.Cu")
		(net "PV_VDDR")
	)
	(via
		(at 109.306868 -30.409896)
		(size 0.4318)
		(drill 0.2032)
		(layers "F.Cu" "B.Cu")
		(net "PV_VDDR")
	)
	(via
		(at 157.27172 -66.723006)
		(size 0.4318)
		(drill 0.2032)
		(layers "F.Cu" "B.Cu")
		(net "PV_VDDR")
	)
	(via
		(at 166.497 -68.707)
		(size 0.7112)
		(drill 0.4064)
		(layers "F.Cu" "B.Cu")
		(net "PV_VDDR")
	)
	(via
		(at 159.17672 -66.799206)
		(size 0.4318)
		(drill 0.2032)
		(layers "F.Cu" "B.Cu")
		(net "PV_VDDR")
	)
	(via
		(at 151.017986 -66.689986)
		(size 0.4318)
		(drill 0.2032)
		(layers "F.Cu" "B.Cu")
		(net "PV_VDDR")
	)
	(via
		(at 200.406 -56.769)
		(size 0.7112)
		(drill 0.4064)
		(layers "F.Cu" "B.Cu")
		(net "PV_VDDR")
	)
	(via
		(at 200.406 -52.064666)
		(size 0.7112)
		(drill 0.4064)
		(layers "F.Cu" "B.Cu")
		(net "PV_VDDR")
	)
	(via
		(at 102.8954 -45.339)
		(size 0.4318)
		(drill 0.2032)
		(layers "F.Cu" "B.Cu")
		(net "PV_VDDR")
	)
	(via
		(at 194.183 -13.716)
		(size 0.7112)
		(drill 0.4064)
		(layers "F.Cu" "B.Cu")
		(net "PV_VDDR")
	)
	(via
		(at 202.77074 -47.695866)
		(size 0.7112)
		(drill 0.4064)
		(layers "F.Cu" "B.Cu")
		(net "PV_VDDR")
	)
	(via
		(at 104.648 -47.625)
		(size 0.4318)
		(drill 0.2032)
		(layers "F.Cu" "B.Cu")
		(net "PV_VDDR")
	)
	(via
		(at 185.674 -53.3908)
		(size 0.508)
		(drill 0.254)
		(layers "F.Cu" "B.Cu")
		(net "PV_VDDR")
	)
	(via
		(at 99.719384 -47.635414)
		(size 0.4318)
		(drill 0.2032)
		(layers "F.Cu" "B.Cu")
		(net "PV_VDDR")
	)
	(via
		(at 157.194758 -7.82066)
		(size 0.4318)
		(drill 0.2032)
		(layers "F.Cu" "B.Cu")
		(net "PV_VDDR")
	)
	(via
		(at 191.389 -5.081778)
		(size 0.7112)
		(drill 0.4064)
		(layers "F.Cu" "B.Cu")
		(net "PV_VDDR")
	)
	(via
		(at 104.8004 -31.5214)
		(size 0.4318)
		(drill 0.2032)
		(layers "F.Cu" "B.Cu")
		(net "PV_VDDR")
	)
	(via
		(at 99.964494 -32.29102)
		(size 0.4318)
		(drill 0.2032)
		(layers "F.Cu" "B.Cu")
		(net "PV_VDDR")
	)
	(via
		(at 199.644 -57.912)
		(size 0.7112)
		(drill 0.4064)
		(layers "F.Cu" "B.Cu")
		(net "PV_VDDR")
	)
	(via
		(at 157.4038 -5.665978)
		(size 0.4318)
		(drill 0.2032)
		(layers "F.Cu" "B.Cu")
		(net "PV_VDDR")
	)
	(via
		(at 101.981 -31.1404)
		(size 0.4318)
		(drill 0.2032)
		(layers "F.Cu" "B.Cu")
		(net "PV_VDDR")
	)
	(via
		(at 184.277 -49.657)
		(size 0.508)
		(drill 0.254)
		(layers "F.Cu" "B.Cu")
		(net "PV_VDDR")
	)
	(via
		(at 191.389 -6.097778)
		(size 0.7112)
		(drill 0.4064)
		(layers "F.Cu" "B.Cu")
		(net "PV_VDDR")
	)
	(via
		(at 201.70394 -47.670466)
		(size 0.7112)
		(drill 0.4064)
		(layers "F.Cu" "B.Cu")
		(net "PV_VDDR")
	)
	(via
		(at 158.36392 -5.731256)
		(size 0.4318)
		(drill 0.2032)
		(layers "F.Cu" "B.Cu")
		(net "PV_VDDR")
	)
	(via
		(at 201.4728 -58.0136)
		(size 0.7112)
		(drill 0.4064)
		(layers "F.Cu" "B.Cu")
		(net "PV_VDDR")
	)
	(via
		(at 153.9748 -68.0212)
		(size 0.4318)
		(drill 0.2032)
		(layers "F.Cu" "B.Cu")
		(net "PV_VDDR")
	)
	(via
		(at 107.687364 -48.474884)
		(size 0.4318)
		(drill 0.2032)
		(layers "F.Cu" "B.Cu")
		(net "PV_VDDR")
	)
	(via
		(at 111.57585 -31.546038)
		(size 0.4318)
		(drill 0.2032)
		(layers "F.Cu" "B.Cu")
		(net "PV_VDDR")
	)
	(via
		(at 201.4728 -60.2488)
		(size 0.7112)
		(drill 0.4064)
		(layers "F.Cu" "B.Cu")
		(net "PV_VDDR")
	)
	(via
		(at 105.699306 -48.769778)
		(size 0.4318)
		(drill 0.2032)
		(layers "F.Cu" "B.Cu")
		(net "PV_VDDR")
	)
	(via
		(at 102.352348 -48.009556)
		(size 0.4318)
		(drill 0.2032)
		(layers "F.Cu" "B.Cu")
		(net "PV_VDDR")
	)
	(via
		(at 195.453 -12.7)
		(size 0.7112)
		(drill 0.4064)
		(layers "F.Cu" "B.Cu")
		(net "PV_VDDR")
	)
	(via
		(at 200.63714 -47.670466)
		(size 0.7112)
		(drill 0.4064)
		(layers "F.Cu" "B.Cu")
		(net "PV_VDDR")
	)
	(via
		(at 101.0412 -33.02)
		(size 0.4318)
		(drill 0.2032)
		(layers "F.Cu" "B.Cu")
		(net "PV_VDDR")
	)
	(via
		(at 152.098756 -60.98413)
		(size 0.7112)
		(drill 0.4064)
		(layers "F.Cu" "B.Cu")
		(net "PV_VDDR")
	)
	(via
		(at 164.2872 -4.472178)
		(size 0.4318)
		(drill 0.2032)
		(layers "F.Cu" "B.Cu")
		(net "PV_VDDR")
	)
	(via
		(at 151.998172 -66.725546)
		(size 0.4318)
		(drill 0.2032)
		(layers "F.Cu" "B.Cu")
		(net "PV_VDDR")
	)
	(via
		(at 161.10712 -66.759328)
		(size 0.4318)
		(drill 0.2032)
		(layers "F.Cu" "B.Cu")
		(net "PV_VDDR")
	)
	(via
		(at 168.709848 -4.154424)
		(size 0.4318)
		(drill 0.2032)
		(layers "F.Cu" "B.Cu")
		(net "PV_VDDR")
	)
	(via
		(at 102.7176 -32.7406)
		(size 0.4318)
		(drill 0.2032)
		(layers "F.Cu" "B.Cu")
		(net "PV_VDDR")
	)
	(via
		(at 162.278822 -64.060324)
		(size 0.4318)
		(drill 0.2032)
		(layers "F.Cu" "B.Cu")
		(net "PV_VDDR")
	)
	(via
		(at 201.4982 -62.7888)
		(size 0.7112)
		(drill 0.4064)
		(layers "F.Cu" "B.Cu")
		(net "PV_VDDR")
	)
	(via
		(at 168.380664 -7.228078)
		(size 0.4318)
		(drill 0.2032)
		(layers "F.Cu" "B.Cu")
		(net "PV_VDDR")
	)
	(via
		(at 199.4916 -51.5112)
		(size 0.7112)
		(drill 0.4064)
		(layers "F.Cu" "B.Cu")
		(net "PV_VDDR")
	)
	(via
		(at 194.945 -7.240778)
		(size 0.7112)
		(drill 0.4064)
		(layers "F.Cu" "B.Cu")
		(net "PV_VDDR")
	)
	(via
		(at 194.945 -8.434578)
		(size 0.7112)
		(drill 0.4064)
		(layers "F.Cu" "B.Cu")
		(net "PV_VDDR")
	)
	(via
		(at 165.1508 -8.459978)
		(size 0.4318)
		(drill 0.2032)
		(layers "F.Cu" "B.Cu")
		(net "PV_VDDR")
	)
	(via
		(at 100.492814 -47.76343)
		(size 0.4318)
		(drill 0.2032)
		(layers "F.Cu" "B.Cu")
		(net "PV_VDDR")
	)
	(via
		(at 168.4782 -5.957316)
		(size 0.4318)
		(drill 0.2032)
		(layers "F.Cu" "B.Cu")
		(net "PV_VDDR")
	)
	(via
		(at 105.74401 -46.537626)
		(size 0.4318)
		(drill 0.2032)
		(layers "F.Cu" "B.Cu")
		(net "PV_VDDR")
	)
	(via
		(at 170.0784 -4.548378)
		(size 0.4318)
		(drill 0.2032)
		(layers "F.Cu" "B.Cu")
		(net "PV_VDDR")
	)
	(via
		(at 101.919024 -32.70377)
		(size 0.4318)
		(drill 0.2032)
		(layers "F.Cu" "B.Cu")
		(net "PV_VDDR")
	)
	(via
		(at 162.180778 -5.888482)
		(size 0.4318)
		(drill 0.2032)
		(layers "F.Cu" "B.Cu")
		(net "PV_VDDR")
	)
	(via
		(at 203.1746 -42.8752)
		(size 0.5588)
		(drill 0.3048)
		(layers "F.Cu" "B.Cu")
		(net "PV_VDDR")
	)
	(via
		(at 159.323278 -5.691378)
		(size 0.4318)
		(drill 0.2032)
		(layers "F.Cu" "B.Cu")
		(net "PV_VDDR")
	)
	(via
		(at 166.520368 -5.771642)
		(size 0.4318)
		(drill 0.2032)
		(layers "F.Cu" "B.Cu")
		(net "PV_VDDR")
	)
	(via
		(at 109.521752 -29.49067)
		(size 0.4318)
		(drill 0.2032)
		(layers "F.Cu" "B.Cu")
		(net "PV_VDDR")
	)
	(via
		(at 165.434264 -3.13944)
		(size 0.4318)
		(drill 0.2032)
		(layers "F.Cu" "B.Cu")
		(net "PV_VDDR")
	)
	(via
		(at 149.733 -65.3034)
		(size 0.4318)
		(drill 0.2032)
		(layers "F.Cu" "B.Cu")
		(net "PV_VDDR")
	)
	(via
		(at 184.15 -16.256)
		(size 0.7112)
		(drill 0.3556)
		(layers "F.Cu" "B.Cu")
		(net "PV_VDDR")
	)
	(via
		(at 101.689408 -45.763434)
		(size 0.4318)
		(drill 0.2032)
		(layers "F.Cu" "B.Cu")
		(net "PV_VDDR")
	)
	(via
		(at 105.898188 -29.619702)
		(size 0.4318)
		(drill 0.2032)
		(layers "F.Cu" "B.Cu")
		(net "PV_VDDR")
	)
	(via
		(at 203.3016 -40.259)
		(size 0.5588)
		(drill 0.3048)
		(layers "F.Cu" "B.Cu")
		(net "PV_VDDR")
	)
	(via
		(at 154.6098 -65.3542)
		(size 0.4318)
		(drill 0.2032)
		(layers "F.Cu" "B.Cu")
		(net "PV_VDDR")
	)
	(via
		(at 108.8136 -47.2186)
		(size 0.4318)
		(drill 0.2032)
		(layers "F.Cu" "B.Cu")
		(net "PV_VDDR")
	)
	(via
		(at 186.182 -44.7548)
		(size 0.508)
		(drill 0.254)
		(layers "F.Cu" "B.Cu")
		(net "PV_VDDR")
	)
	(via
		(at 162.048698 -66.761868)
		(size 0.4318)
		(drill 0.2032)
		(layers "F.Cu" "B.Cu")
		(net "PV_VDDR")
	)
	(via
		(at 191.389 -7.240778)
		(size 0.7112)
		(drill 0.4064)
		(layers "F.Cu" "B.Cu")
		(net "PV_VDDR")
	)
	(via
		(at 199.644 -59.0296)
		(size 0.7112)
		(drill 0.4064)
		(layers "F.Cu" "B.Cu")
		(net "PV_VDDR")
	)
	(via
		(at 160.909 -3.151124)
		(size 0.4318)
		(drill 0.2032)
		(layers "F.Cu" "B.Cu")
		(net "PV_VDDR")
	)
	(via
		(at 199.7202 -61.341)
		(size 0.7112)
		(drill 0.4064)
		(layers "F.Cu" "B.Cu")
		(net "PV_VDDR")
	)
	(via
		(at 199.263 -56.515)
		(size 0.7112)
		(drill 0.4064)
		(layers "F.Cu" "B.Cu")
		(net "PV_VDDR")
	)
	(via
		(at 167.105838 -3.176016)
		(size 0.4318)
		(drill 0.2032)
		(layers "F.Cu" "B.Cu")
		(net "PV_VDDR")
	)
	(via
		(at 200.914 -64.643)
		(size 0.7112)
		(drill 0.3556)
		(layers "F.Cu" "B.Cu")
		(net "PV_VDDR")
	)
	(via
		(at 149.8346 -68.105782)
		(size 0.4318)
		(drill 0.2032)
		(layers "F.Cu" "B.Cu")
		(net "PV_VDDR")
	)
	(via
		(at 167.301418 -67.975988)
		(size 0.7112)
		(drill 0.4064)
		(layers "F.Cu" "B.Cu")
		(net "PV_VDDR")
	)
	(via
		(at 162.56 -11.685778)
		(size 0.7112)
		(drill 0.4064)
		(layers "F.Cu" "B.Cu")
		(net "PV_VDDR")
	)
	(via
		(at 194.1322 -12.4968)
		(size 0.7112)
		(drill 0.4064)
		(layers "F.Cu" "B.Cu")
		(net "PV_VDDR")
	)
	(via
		(at 160.003998 -69.33946)
		(size 0.4318)
		(drill 0.2032)
		(layers "F.Cu" "B.Cu")
		(net "PV_VDDR")
	)
	(via
		(at 163.0426 -8.002778)
		(size 0.4318)
		(drill 0.2032)
		(layers "F.Cu" "B.Cu")
		(net "PV_VDDR")
	)
	(via
		(at 199.60082 -47.9298)
		(size 0.7112)
		(drill 0.4064)
		(layers "F.Cu" "B.Cu")
		(net "PV_VDDR")
	)
	(via
		(at 161.340038 -64.668908)
		(size 0.4318)
		(drill 0.2032)
		(layers "F.Cu" "B.Cu")
		(net "PV_VDDR")
	)
	(via
		(at 194.945 -4.954778)
		(size 0.7112)
		(drill 0.4064)
		(layers "F.Cu" "B.Cu")
		(net "PV_VDDR")
	)
	(via
		(at 153.0223 -69.3166)
		(size 0.4318)
		(drill 0.2032)
		(layers "F.Cu" "B.Cu")
		(net "PV_VDDR")
	)
	(via
		(at 194.1068 -11.2268)
		(size 0.7112)
		(drill 0.4064)
		(layers "F.Cu" "B.Cu")
		(net "PV_VDDR")
	)
	(via
		(at 134.874 -58.0009)
		(size 0.508)
		(drill 0.254)
		(layers "F.Cu" "B.Cu")
		(net "PV_VDDR")
	)
	(via
		(at 162.433 -68.2752)
		(size 0.4318)
		(drill 0.2032)
		(layers "F.Cu" "B.Cu")
		(net "PV_VDDR")
	)
	(via
		(at 156.2354 -60.6806)
		(size 0.7112)
		(drill 0.4064)
		(layers "F.Cu" "B.Cu")
		(net "PV_VDDR")
	)
	(via
		(at 167.4876 -5.894578)
		(size 0.4318)
		(drill 0.2032)
		(layers "F.Cu" "B.Cu")
		(net "PV_VDDR")
	)
	(via
		(at 160.896046 -8.43026)
		(size 0.4318)
		(drill 0.2032)
		(layers "F.Cu" "B.Cu")
		(net "PV_VDDR")
	)
	(via
		(at 157.590998 -69.33946)
		(size 0.4318)
		(drill 0.2032)
		(layers "F.Cu" "B.Cu")
		(net "PV_VDDR")
	)
	(via
		(at 108.4072 -24.8539)
		(size 0.4318)
		(drill 0.2032)
		(layers "F.Cu" "B.Cu")
		(net "PV_VDDR")
	)
	(via
		(at 101.022912 -48.019462)
		(size 0.4318)
		(drill 0.2032)
		(layers "F.Cu" "B.Cu")
		(net "PV_VDDR")
	)
	(via
		(at 193.294 -14.859)
		(size 0.7112)
		(drill 0.4064)
		(layers "F.Cu" "B.Cu")
		(net "PV_VDDR")
	)
	(via
		(at 108.0008 -30.181042)
		(size 0.4318)
		(drill 0.2032)
		(layers "F.Cu" "B.Cu")
		(net "PV_VDDR")
	)
	(via
		(at 151.228044 -69.324728)
		(size 0.4318)
		(drill 0.2032)
		(layers "F.Cu" "B.Cu")
		(net "PV_VDDR")
	)
	(via
		(at 155.40863 -64.445642)
		(size 0.4318)
		(drill 0.2032)
		(layers "F.Cu" "B.Cu")
		(net "PV_VDDR")
	)
	(via
		(at 193.294 -4.065778)
		(size 0.7112)
		(drill 0.4064)
		(layers "F.Cu" "B.Cu")
		(net "PV_VDDR")
	)
	(via
		(at 199.39 -62.4332)
		(size 0.7112)
		(drill 0.4064)
		(layers "F.Cu" "B.Cu")
		(net "PV_VDDR")
	)
	(via
		(at 166.502842 -67.720464)
		(size 0.7112)
		(drill 0.4064)
		(layers "F.Cu" "B.Cu")
		(net "PV_VDDR")
	)
	(via
		(at 158.22422 -66.723006)
		(size 0.4318)
		(drill 0.2032)
		(layers "F.Cu" "B.Cu")
		(net "PV_VDDR")
	)
	(via
		(at 201.4728 -61.5696)
		(size 0.7112)
		(drill 0.4064)
		(layers "F.Cu" "B.Cu")
		(net "PV_VDDR")
	)
	(via
		(at 167.1066 -8.43026)
		(size 0.4318)
		(drill 0.2032)
		(layers "F.Cu" "B.Cu")
		(net "PV_VDDR")
	)
	(via
		(at 164.084 -11.685778)
		(size 0.7112)
		(drill 0.4064)
		(layers "F.Cu" "B.Cu")
		(net "PV_VDDR")
	)
	(via
		(at 163.00323 -3.141218)
		(size 0.4318)
		(drill 0.2032)
		(layers "F.Cu" "B.Cu")
		(net "PV_VDDR")
	)
	(via
		(at 167.077898 -67.101466)
		(size 0.7112)
		(drill 0.4064)
		(layers "F.Cu" "B.Cu")
		(net "PV_VDDR")
	)
	(via
		(at 107.2642 -32.0802)
		(size 0.4318)
		(drill 0.2032)
		(layers "F.Cu" "B.Cu")
		(net "PV_VDDR")
	)
	(via
		(at 156.1338 -3.583178)
		(size 0.4318)
		(drill 0.2032)
		(layers "F.Cu" "B.Cu")
		(net "PV_VDDR")
	)
	(via
		(at 161.228278 -5.767578)
		(size 0.4318)
		(drill 0.2032)
		(layers "F.Cu" "B.Cu")
		(net "PV_VDDR")
	)
	(via
		(at 167.591994 -66.232278)
		(size 0.7112)
		(drill 0.4064)
		(layers "F.Cu" "B.Cu")
		(net "PV_VDDR")
	)
	(via
		(at 200.4568 -55.5498)
		(size 0.7112)
		(drill 0.4064)
		(layers "F.Cu" "B.Cu")
		(net "PV_VDDR")
	)
	(via
		(at 108.282994 -51.917346)
		(size 0.4318)
		(drill 0.2032)
		(layers "F.Cu" "B.Cu")
		(net "PV_VDDR")
	)
	(via
		(at 153.209498 -64.022224)
		(size 0.4318)
		(drill 0.2032)
		(layers "F.Cu" "B.Cu")
		(net "PV_VDDR")
	)
	(via
		(at 106.3752 -49.9618)
		(size 0.4318)
		(drill 0.2032)
		(layers "F.Cu" "B.Cu")
		(net "PV_VDDR")
	)
	(via
		(at 163.8808 -7.037578)
		(size 0.4318)
		(drill 0.2032)
		(layers "F.Cu" "B.Cu")
		(net "PV_VDDR")
	)
	(segment
		(start 156.1084 -2.933446)
		(end 156.1084 -3.557778)
		(width 0.3048)
		(layer "B.Cu")
		(net "PV_VDDR")
	)
	(segment
		(start 160.154874 -72.39)
		(end 161.2392 -72.39)
		(width 0.3048)
		(layer "B.Cu")
		(net "PV_VDDR")
	)
	(segment
		(start 148.497544 -69.550026)
		(end 148.497544 -66.538856)
		(width 0.254)
		(layer "B.Cu")
		(net "PV_VDDR")
	)
	(segment
		(start 203.073 -31.75)
		(end 202.946 -31.877)
		(width 0.508)
		(layer "B.Cu")
		(net "PV_VDDR")
	)
	(segment
		(start 203.6318 -31.75)
		(end 203.073 -31.75)
		(width 0.508)
		(layer "B.Cu")
		(net "PV_VDDR")
	)
	(segment
		(start 158.649924 -1.690624)
		(end 158.649924 -2.9972)
		(width 0.3048)
		(layer "B.Cu")
		(net "PV_VDDR")
	)
	(segment
		(start 162.391598 -68.316602)
		(end 162.433 -68.2752)
		(width 0.3048)
		(layer "B.Cu")
		(net "PV_VDDR")
	)
	(segment
		(start 165.321488 -3.026664)
		(end 165.434264 -3.13944)
		(width 0.3048)
		(layer "B.Cu")
		(net "PV_VDDR")
	)
	(segment
		(start 161.04997 -3.010154)
		(end 160.909 -3.151124)
		(width 0.3048)
		(layer "B.Cu")
		(net "PV_VDDR")
	)
	(segment
		(start 170.027854 -2.940558)
		(end 170.027854 -4.421632)
		(width 0.254)
		(layer "B.Cu")
		(net "PV_VDDR")
	)
	(segment
		(start 148.450046 -70.79996)
		(end 148.450046 -69.597524)
		(width 0.254)
		(layer "B.Cu")
		(net "PV_VDDR")
	)
	(segment
		(start 184.277 -51.9938)
		(end 185.674 -53.3908)
		(width 0.3048)
		(layer "B.Cu")
		(net "PV_VDDR")
	)
	(segment
		(start 170.049952 -2.91846)
		(end 170.027854 -2.940558)
		(width 0.254)
		(layer "B.Cu")
		(net "PV_VDDR")
	)
	(segment
		(start 203.8604 -42.3418)
		(end 203.708 -42.3418)
		(width 0.508)
		(layer "B.Cu")
		(net "PV_VDDR")
	)
	(segment
		(start 186.182 -47.0154)
		(end 186.182 -47.752)
		(width 0.3048)
		(layer "B.Cu")
		(net "PV_VDDR")
	)
	(segment
		(start 153.250138 -70.79996)
		(end 153.250138 -69.615812)
		(width 0.3048)
		(layer "B.Cu")
		(net "PV_VDDR")
	)
	(segment
		(start 153.0223 -69.387974)
		(end 153.0223 -69.3166)
		(width 0.3048)
		(layer "B.Cu")
		(net "PV_VDDR")
	)
	(segment
		(start 170.0784 -4.472178)
		(end 170.0784 -4.548378)
		(width 0.254)
		(layer "B.Cu")
		(net "PV_VDDR")
	)
	(segment
		(start 148.450046 -69.597524)
		(end 148.497544 -69.550026)
		(width 0.254)
		(layer "B.Cu")
		(net "PV_VDDR")
	)
	(segment
		(start 155.421584 -69.474842)
		(end 155.547822 -69.348604)
		(width 0.3048)
		(layer "B.Cu")
		(net "PV_VDDR")
	)
	(segment
		(start 203.708 -42.3418)
		(end 203.1746 -42.8752)
		(width 0.508)
		(layer "B.Cu")
		(net "PV_VDDR")
	)
	(segment
		(start 153.250138 -69.615812)
		(end 153.0223 -69.387974)
		(width 0.3048)
		(layer "B.Cu")
		(net "PV_VDDR")
	)
	(segment
		(start 170.027854 -4.421632)
		(end 170.0784 -4.472178)
		(width 0.254)
		(layer "B.Cu")
		(net "PV_VDDR")
	)
	(segment
		(start 159.850074 -70.79996)
		(end 159.850074 -72.0852)
		(width 0.3048)
		(layer "B.Cu")
		(net "PV_VDDR")
	)
	(segment
		(start 186.182 -43.688)
		(end 186.182 -44.7548)
		(width 0.508)
		(layer "B.Cu")
		(net "PV_VDDR")
	)
	(segment
		(start 163.450016 -2.59461)
		(end 163.078414 -2.966212)
		(width 0.3048)
		(layer "B.Cu")
		(net "PV_VDDR")
	)
	(segment
		(start 156.1084 -3.557778)
		(end 156.1338 -3.583178)
		(width 0.3048)
		(layer "B.Cu")
		(net "PV_VDDR")
	)
	(segment
		(start 170.049952 -1.690624)
		(end 170.049952 -2.91846)
		(width 0.254)
		(layer "B.Cu")
		(net "PV_VDDR")
	)
	(segment
		(start 159.850074 -72.0852)
		(end 160.154874 -72.39)
		(width 0.3048)
		(layer "B.Cu")
		(net "PV_VDDR")
	)
	(segment
		(start 163.450016 -1.690624)
		(end 163.450016 -2.59461)
		(width 0.3048)
		(layer "B.Cu")
		(net "PV_VDDR")
	)
	(segment
		(start 155.049982 -70.79996)
		(end 155.049982 -69.895974)
		(width 0.3048)
		(layer "B.Cu")
		(net "PV_VDDR")
	)
	(segment
		(start 160.003998 -69.33946)
		(end 159.850074 -69.493384)
		(width 0.3048)
		(layer "B.Cu")
		(net "PV_VDDR")
	)
	(segment
		(start 203.6826 -39.751)
		(end 203.3016 -40.132)
		(width 0.508)
		(layer "B.Cu")
		(net "PV_VDDR")
	)
	(segment
		(start 150.850092 -70.79996)
		(end 150.850092 -69.723508)
		(width 0.3048)
		(layer "B.Cu")
		(net "PV_VDDR")
	)
	(segment
		(start 186.182 -44.7548)
		(end 186.182 -47.0154)
		(width 0.3048)
		(layer "B.Cu")
		(net "PV_VDDR")
	)
	(segment
		(start 162.25012 -70.79996)
		(end 162.25012 -69.95668)
		(width 0.3048)
		(layer "B.Cu")
		(net "PV_VDDR")
	)
	(segment
		(start 184.277 -49.657)
		(end 184.277 -51.9938)
		(width 0.3048)
		(layer "B.Cu")
		(net "PV_VDDR")
	)
	(segment
		(start 165.321488 -2.9464)
		(end 165.321488 -3.026664)
		(width 0.3048)
		(layer "B.Cu")
		(net "PV_VDDR")
	)
	(segment
		(start 159.850074 -69.493384)
		(end 159.850074 -70.79996)
		(width 0.3048)
		(layer "B.Cu")
		(net "PV_VDDR")
	)
	(segment
		(start 186.182 -47.752)
		(end 184.277 -49.657)
		(width 0.3048)
		(layer "B.Cu")
		(net "PV_VDDR")
	)
	(segment
		(start 165.24986 -2.874772)
		(end 165.321488 -2.9464)
		(width 0.3048)
		(layer "B.Cu")
		(net "PV_VDDR")
	)
	(segment
		(start 167.649906 -2.631948)
		(end 167.105838 -3.176016)
		(width 0.3048)
		(layer "B.Cu")
		(net "PV_VDDR")
	)
	(segment
		(start 155.421584 -69.524372)
		(end 155.421584 -69.474842)
		(width 0.3048)
		(layer "B.Cu")
		(net "PV_VDDR")
	)
	(segment
		(start 163.078414 -3.066034)
		(end 163.00323 -3.141218)
		(width 0.3048)
		(layer "B.Cu")
		(net "PV_VDDR")
	)
	(segment
		(start 165.24986 -1.690624)
		(end 165.24986 -2.874772)
		(width 0.3048)
		(layer "B.Cu")
		(net "PV_VDDR")
	)
	(segment
		(start 148.497544 -66.538856)
		(end 149.733 -65.3034)
		(width 0.254)
		(layer "B.Cu")
		(net "PV_VDDR")
	)
	(segment
		(start 203.6318 -30.861)
		(end 202.946 -30.861)
		(width 0.508)
		(layer "B.Cu")
		(net "PV_VDDR")
	)
	(segment
		(start 163.078414 -2.966212)
		(end 163.078414 -3.066034)
		(width 0.3048)
		(layer "B.Cu")
		(net "PV_VDDR")
	)
	(segment
		(start 162.391598 -69.815202)
		(end 162.391598 -68.316602)
		(width 0.3048)
		(layer "B.Cu")
		(net "PV_VDDR")
	)
	(segment
		(start 157.450028 -70.79996)
		(end 157.450028 -69.48043)
		(width 0.3048)
		(layer "B.Cu")
		(net "PV_VDDR")
	)
	(segment
		(start 162.25012 -69.95668)
		(end 162.391598 -69.815202)
		(width 0.3048)
		(layer "B.Cu")
		(net "PV_VDDR")
	)
	(segment
		(start 150.850092 -69.723508)
		(end 151.150066 -69.423534)
		(width 0.3048)
		(layer "B.Cu")
		(net "PV_VDDR")
	)
	(segment
		(start 161.04997 -1.690624)
		(end 161.04997 -3.010154)
		(width 0.3048)
		(layer "B.Cu")
		(net "PV_VDDR")
	)
	(segment
		(start 188.0362 -41.8338)
		(end 186.182 -43.688)
		(width 0.508)
		(layer "B.Cu")
		(net "PV_VDDR")
	)
	(segment
		(start 203.6826 -39.4462)
		(end 203.6826 -39.751)
		(width 0.508)
		(layer "B.Cu")
		(net "PV_VDDR")
	)
	(segment
		(start 151.150066 -69.423534)
		(end 151.150066 -69.402706)
		(width 0.3048)
		(layer "B.Cu")
		(net "PV_VDDR")
	)
	(segment
		(start 203.3016 -40.132)
		(end 203.3016 -40.259)
		(width 0.508)
		(layer "B.Cu")
		(net "PV_VDDR")
	)
	(segment
		(start 158.649924 -2.9972)
		(end 158.496 -3.151124)
		(width 0.3048)
		(layer "B.Cu")
		(net "PV_VDDR")
	)
	(segment
		(start 151.150066 -69.402706)
		(end 151.228044 -69.324728)
		(width 0.3048)
		(layer "B.Cu")
		(net "PV_VDDR")
	)
	(segment
		(start 157.450028 -69.48043)
		(end 157.590998 -69.33946)
		(width 0.3048)
		(layer "B.Cu")
		(net "PV_VDDR")
	)
	(segment
		(start 167.649906 -1.690624)
		(end 167.649906 -2.631948)
		(width 0.3048)
		(layer "B.Cu")
		(net "PV_VDDR")
	)
	(segment
		(start 156.249878 -1.690624)
		(end 156.249878 -2.791968)
		(width 0.3048)
		(layer "B.Cu")
		(net "PV_VDDR")
	)
	(segment
		(start 155.049982 -69.895974)
		(end 155.421584 -69.524372)
		(width 0.3048)
		(layer "B.Cu")
		(net "PV_VDDR")
	)
	(segment
		(start 156.249878 -2.791968)
		(end 156.1084 -2.933446)
		(width 0.3048)
		(layer "B.Cu")
		(net "PV_VDDR")
	)
	(segment
		(start 147.849844 -9.066022)
		(end 147.574 -8.790178)
		(width 0.1778)
		(layer "F.Cu")
		(net "M_B_DQ26")
	)
	(segment
		(start 147.574 -8.790178)
		(end 147.574 -8.434578)
		(width 0.1778)
		(layer "F.Cu")
		(net "M_B_DQ26")
	)
	(segment
		(start 96.529652 -32.112458)
		(end 96.9264 -32.112458)
		(width 0.1016)
		(layer "F.Cu")
		(net "M_B_DQ26")
	)
	(segment
		(start 147.574 -8.434578)
		(end 147.7518 -8.256778)
		(width 0.1778)
		(layer "F.Cu")
		(net "M_B_DQ26")
	)
	(segment
		(start 96.319848 -31.902654)
		(end 96.529652 -32.112458)
		(width 0.1016)
		(layer "F.Cu")
		(net "M_B_DQ26")
	)
	(segment
		(start 147.7518 -8.256778)
		(end 147.7518 -7.863078)
		(width 0.1778)
		(layer "F.Cu")
		(net "M_B_DQ26")
	)
	(segment
		(start 147.7518 -7.863078)
		(end 147.6883 -7.799578)
		(width 0.1778)
		(layer "F.Cu")
		(net "M_B_DQ26")
	)
	(segment
		(start 147.849844 -9.897364)
		(end 147.849844 -9.066022)
		(width 0.1778)
		(layer "F.Cu")
		(net "M_B_DQ26")
	)
	(via
		(at 96.9264 -32.112458)
		(size 0.4318)
		(drill 0.2032)
		(layers "F.Cu" "B.Cu")
		(net "M_B_DQ26")
	)
	(via
		(at 147.6883 -7.799578)
		(size 0.4318)
		(drill 0.2032)
		(layers "F.Cu" "B.Cu")
		(net "M_B_DQ26")
	)
	(segment
		(start 146.949922 -9.89076)
		(end 146.949922 -9.186164)
		(width 0.1778)
		(layer "B.Cu")
		(net "M_B_DQ26")
	)
	(segment
		(start 146.95043 -9.185656)
		(end 146.951192 -9.185656)
		(width 0.1778)
		(layer "B.Cu")
		(net "M_B_DQ26")
	)
	(segment
		(start 146.951192 -9.185656)
		(end 147.6883 -8.448548)
		(width 0.1778)
		(layer "B.Cu")
		(net "M_B_DQ26")
	)
	(segment
		(start 147.6883 -8.448548)
		(end 147.6883 -7.799578)
		(width 0.1778)
		(layer "B.Cu")
		(net "M_B_DQ26")
	)
	(segment
		(start 146.949922 -9.186164)
		(end 146.95043 -9.185656)
		(width 0.1778)
		(layer "B.Cu")
		(net "M_B_DQ26")
	)
	(segment
		(start 106.863134 -26.9494)
		(end 105.593134 -28.2194)
		(width 0.1524)
		(layer "In4.Cu")
		(net "M_B_DQ26")
	)
	(segment
		(start 124.22505 -22.733)
		(end 123.698 -22.733)
		(width 0.1524)
		(layer "In4.Cu")
		(net "M_B_DQ26")
	)
	(segment
		(start 124.37745 -23.241)
		(end 124.37745 -22.8854)
		(width 0.1524)
		(layer "In4.Cu")
		(net "M_B_DQ26")
	)
	(segment
		(start 147.6883 -7.799578)
		(end 147.6883 -7.829042)
		(width 0.1524)
		(layer "In4.Cu")
		(net "M_B_DQ26")
	)
	(segment
		(start 101.787452 -29.971492)
		(end 101.448108 -29.971492)
		(width 0.1016)
		(layer "In4.Cu")
		(net "M_B_DQ26")
	)
	(segment
		(start 119.433594 -22.7584)
		(end 119.128794 -22.7584)
		(width 0.1524)
		(layer "In4.Cu")
		(net "M_B_DQ26")
	)
	(segment
		(start 102.337362 -29.77007)
		(end 102.147116 -29.960316)
		(width 0.1524)
		(layer "In4.Cu")
		(net "M_B_DQ26")
	)
	(segment
		(start 123.5456 -23.241)
		(end 123.3932 -23.3934)
		(width 0.1524)
		(layer "In4.Cu")
		(net "M_B_DQ26")
	)
	(segment
		(start 113.627662 -24.5872)
		(end 110.085378 -24.5872)
		(width 0.1524)
		(layer "In4.Cu")
		(net "M_B_DQ26")
	)
	(segment
		(start 125.90145 -23.1394)
		(end 125.90145 -22.9362)
		(width 0.1524)
		(layer "In4.Cu")
		(net "M_B_DQ26")
	)
	(segment
		(start 123.698 -22.733)
		(end 123.5456 -22.8854)
		(width 0.1524)
		(layer "In4.Cu")
		(net "M_B_DQ26")
	)
	(segment
		(start 97.076768 -32.262826)
		(end 96.9264 -32.112458)
		(width 0.1016)
		(layer "In4.Cu")
		(net "M_B_DQ26")
	)
	(segment
		(start 119.128794 -22.7584)
		(end 118.976394 -22.9108)
		(width 0.1524)
		(layer "In4.Cu")
		(net "M_B_DQ26")
	)
	(segment
		(start 125.13945 -22.9362)
		(end 125.13945 -23.241)
		(width 0.1524)
		(layer "In4.Cu")
		(net "M_B_DQ26")
	)
	(segment
		(start 103.378 -28.2194)
		(end 102.337362 -29.260038)
		(width 0.1524)
		(layer "In4.Cu")
		(net "M_B_DQ26")
	)
	(segment
		(start 108.313728 -25.908)
		(end 107.272074 -26.9494)
		(width 0.1524)
		(layer "In4.Cu")
		(net "M_B_DQ26")
	)
	(segment
		(start 105.593134 -28.2194)
		(end 103.378 -28.2194)
		(width 0.1524)
		(layer "In4.Cu")
		(net "M_B_DQ26")
	)
	(segment
		(start 118.823994 -23.3934)
		(end 114.821462 -23.3934)
		(width 0.1524)
		(layer "In4.Cu")
		(net "M_B_DQ26")
	)
	(segment
		(start 147.8534 -8.928608)
		(end 147.955 -9.030208)
		(width 0.1524)
		(layer "In4.Cu")
		(net "M_B_DQ26")
	)
	(segment
		(start 101.448108 -29.971492)
		(end 101.079554 -30.340046)
		(width 0.1016)
		(layer "In4.Cu")
		(net "M_B_DQ26")
	)
	(segment
		(start 124.37745 -22.8854)
		(end 124.22505 -22.733)
		(width 0.1524)
		(layer "In4.Cu")
		(net "M_B_DQ26")
	)
	(segment
		(start 102.337362 -29.260038)
		(end 102.337362 -29.77007)
		(width 0.1524)
		(layer "In4.Cu")
		(net "M_B_DQ26")
	)
	(segment
		(start 126.141226 -23.379176)
		(end 125.90145 -23.1394)
		(width 0.1524)
		(layer "In4.Cu")
		(net "M_B_DQ26")
	)
	(segment
		(start 119.738394 -23.3934)
		(end 119.585994 -23.241)
		(width 0.1524)
		(layer "In4.Cu")
		(net "M_B_DQ26")
	)
	(segment
		(start 124.98705 -23.3934)
		(end 124.52985 -23.3934)
		(width 0.1524)
		(layer "In4.Cu")
		(net "M_B_DQ26")
	)
	(segment
		(start 124.52985 -23.3934)
		(end 124.37745 -23.241)
		(width 0.1524)
		(layer "In4.Cu")
		(net "M_B_DQ26")
	)
	(segment
		(start 108.764578 -25.908)
		(end 108.313728 -25.908)
		(width 0.1524)
		(layer "In4.Cu")
		(net "M_B_DQ26")
	)
	(segment
		(start 147.8534 -7.994142)
		(end 147.8534 -8.928608)
		(width 0.1524)
		(layer "In4.Cu")
		(net "M_B_DQ26")
	)
	(segment
		(start 114.821462 -23.3934)
		(end 113.627662 -24.5872)
		(width 0.1524)
		(layer "In4.Cu")
		(net "M_B_DQ26")
	)
	(segment
		(start 107.272074 -26.9494)
		(end 106.863134 -26.9494)
		(width 0.1524)
		(layer "In4.Cu")
		(net "M_B_DQ26")
	)
	(segment
		(start 125.90145 -22.9362)
		(end 125.74905 -22.7838)
		(width 0.1524)
		(layer "In4.Cu")
		(net "M_B_DQ26")
	)
	(segment
		(start 123.5456 -22.8854)
		(end 123.5456 -23.241)
		(width 0.1524)
		(layer "In4.Cu")
		(net "M_B_DQ26")
	)
	(segment
		(start 119.585994 -23.241)
		(end 119.585994 -22.9108)
		(width 0.1524)
		(layer "In4.Cu")
		(net "M_B_DQ26")
	)
	(segment
		(start 102.132384 -29.975048)
		(end 101.791008 -29.975048)
		(width 0.1016)
		(layer "In4.Cu")
		(net "M_B_DQ26")
	)
	(segment
		(start 147.955 -22.272752)
		(end 146.848576 -23.379176)
		(width 0.1524)
		(layer "In4.Cu")
		(net "M_B_DQ26")
	)
	(segment
		(start 100.049838 -30.396688)
		(end 99.745292 -30.396688)
		(width 0.1016)
		(layer "In4.Cu")
		(net "M_B_DQ26")
	)
	(segment
		(start 123.3932 -23.3934)
		(end 119.738394 -23.3934)
		(width 0.1524)
		(layer "In4.Cu")
		(net "M_B_DQ26")
	)
	(segment
		(start 125.13945 -23.241)
		(end 124.98705 -23.3934)
		(width 0.1524)
		(layer "In4.Cu")
		(net "M_B_DQ26")
	)
	(segment
		(start 147.955 -9.030208)
		(end 147.955 -22.272752)
		(width 0.1524)
		(layer "In4.Cu")
		(net "M_B_DQ26")
	)
	(segment
		(start 101.791008 -29.975048)
		(end 101.787452 -29.971492)
		(width 0.1016)
		(layer "In4.Cu")
		(net "M_B_DQ26")
	)
	(segment
		(start 99.745292 -30.396688)
		(end 98.54819 -31.59379)
		(width 0.1016)
		(layer "In4.Cu")
		(net "M_B_DQ26")
	)
	(segment
		(start 100.10648 -30.340046)
		(end 100.049838 -30.396688)
		(width 0.1016)
		(layer "In4.Cu")
		(net "M_B_DQ26")
	)
	(segment
		(start 125.74905 -22.7838)
		(end 125.29185 -22.7838)
		(width 0.1524)
		(layer "In4.Cu")
		(net "M_B_DQ26")
	)
	(segment
		(start 110.085378 -24.5872)
		(end 108.764578 -25.908)
		(width 0.1524)
		(layer "In4.Cu")
		(net "M_B_DQ26")
	)
	(segment
		(start 146.848576 -23.379176)
		(end 126.141226 -23.379176)
		(width 0.1524)
		(layer "In4.Cu")
		(net "M_B_DQ26")
	)
	(segment
		(start 147.6883 -7.829042)
		(end 147.8534 -7.994142)
		(width 0.1524)
		(layer "In4.Cu")
		(net "M_B_DQ26")
	)
	(segment
		(start 98.06432 -32.262826)
		(end 97.076768 -32.262826)
		(width 0.1016)
		(layer "In4.Cu")
		(net "M_B_DQ26")
	)
	(segment
		(start 101.079554 -30.340046)
		(end 100.10648 -30.340046)
		(width 0.1016)
		(layer "In4.Cu")
		(net "M_B_DQ26")
	)
	(segment
		(start 102.147116 -29.960316)
		(end 102.132384 -29.975048)
		(width 0.1016)
		(layer "In4.Cu")
		(net "M_B_DQ26")
	)
	(segment
		(start 118.976394 -23.241)
		(end 118.823994 -23.3934)
		(width 0.1524)
		(layer "In4.Cu")
		(net "M_B_DQ26")
	)
	(segment
		(start 125.29185 -22.7838)
		(end 125.13945 -22.9362)
		(width 0.1524)
		(layer "In4.Cu")
		(net "M_B_DQ26")
	)
	(segment
		(start 119.585994 -22.9108)
		(end 119.433594 -22.7584)
		(width 0.1524)
		(layer "In4.Cu")
		(net "M_B_DQ26")
	)
	(segment
		(start 118.976394 -22.9108)
		(end 118.976394 -23.241)
		(width 0.1524)
		(layer "In4.Cu")
		(net "M_B_DQ26")
	)
	(arc
		(start 98.425762 -32.004254)
		(mid 98.286503 -32.191476)
		(end 98.06432 -32.262826)
		(width 0.1016)
		(layer "In4.Cu")
		(net "M_B_DQ26")
	)
	(arc
		(start 98.466656 -31.875222)
		(mid 98.450214 -31.941008)
		(end 98.425762 -32.004254)
		(width 0.1016)
		(layer "In4.Cu")
		(net "M_B_DQ26")
	)
	(arc
		(start 98.54819 -31.59379)
		(mid 98.487457 -31.728721)
		(end 98.466656 -31.875222)
		(width 0.1016)
		(layer "In4.Cu")
		(net "M_B_DQ26")
	)
	(segment
		(start 32.258 -38.3032)
		(end 32.258 -37.5158)
		(width 0.1143)
		(layer "F.Cu")
		(net "XDP_SOC_CPU_TMS")
	)
	(segment
		(start 85.7504 -38.3286)
		(end 85.2043 -38.3286)
		(width 0.1143)
		(layer "F.Cu")
		(net "XDP_SOC_CPU_TMS")
	)
	(segment
		(start 33.931098 -36.249102)
		(end 32.893 -37.2872)
		(width 0.1143)
		(layer "F.Cu")
		(net "XDP_SOC_CPU_TMS")
	)
	(segment
		(start 161.3027 -49.8729)
		(end 160.8074 -50.3682)
		(width 0.1143)
		(layer "F.Cu")
		(net "XDP_SOC_CPU_TMS")
	)
	(segment
		(start 32.258 -37.5158)
		(end 32.3088 -37.465)
		(width 0.1143)
		(layer "F.Cu")
		(net "XDP_SOC_CPU_TMS")
	)
	(segment
		(start 162.5092 -48.9966)
		(end 162.5092 -49.53)
		(width 0.1143)
		(layer "F.Cu")
		(net "XDP_SOC_CPU_TMS")
	)
	(segment
		(start 35.185604 -34.05505)
		(end 34.972244 -34.26841)
		(width 0.1143)
		(layer "F.Cu")
		(net "XDP_SOC_CPU_TMS")
	)
	(segment
		(start 34.972244 -34.26841)
		(end 34.972244 -34.66973)
		(width 0.1143)
		(layer "F.Cu")
		(net "XDP_SOC_CPU_TMS")
	)
	(segment
		(start 32.893 -37.2872)
		(end 32.4866 -37.2872)
		(width 0.1143)
		(layer "F.Cu")
		(net "XDP_SOC_CPU_TMS")
	)
	(segment
		(start 32.4866 -37.2872)
		(end 32.3088 -37.465)
		(width 0.1143)
		(layer "F.Cu")
		(net "XDP_SOC_CPU_TMS")
	)
	(segment
		(start 34.583624 -35.05835)
		(end 33.931098 -35.710876)
		(width 0.1143)
		(layer "F.Cu")
		(net "XDP_SOC_CPU_TMS")
	)
	(segment
		(start 162.5092 -49.53)
		(end 162.1663 -49.8729)
		(width 0.1143)
		(layer "F.Cu")
		(net "XDP_SOC_CPU_TMS")
	)
	(segment
		(start 86.31682 -37.126926)
		(end 86.31682 -37.76218)
		(width 0.1143)
		(layer "F.Cu")
		(net "XDP_SOC_CPU_TMS")
	)
	(segment
		(start 85.933788 -36.743894)
		(end 86.31682 -37.126926)
		(width 0.1143)
		(layer "F.Cu")
		(net "XDP_SOC_CPU_TMS")
	)
	(segment
		(start 34.972244 -34.66973)
		(end 34.583624 -35.05835)
		(width 0.1143)
		(layer "F.Cu")
		(net "XDP_SOC_CPU_TMS")
	)
	(segment
		(start 36.37788 -34.05505)
		(end 35.185604 -34.05505)
		(width 0.1143)
		(layer "F.Cu")
		(net "XDP_SOC_CPU_TMS")
	)
	(segment
		(start 162.1663 -49.8729)
		(end 161.3027 -49.8729)
		(width 0.1143)
		(layer "F.Cu")
		(net "XDP_SOC_CPU_TMS")
	)
	(segment
		(start 86.31682 -37.76218)
		(end 85.7504 -38.3286)
		(width 0.1143)
		(layer "F.Cu")
		(net "XDP_SOC_CPU_TMS")
	)
	(segment
		(start 33.931098 -35.710876)
		(end 33.931098 -36.249102)
		(width 0.1143)
		(layer "F.Cu")
		(net "XDP_SOC_CPU_TMS")
	)
	(via
		(at 118.491 -69.2912)
		(size 0.508)
		(drill 0.254)
		(layers "F.Cu" "B.Cu")
		(net "XDP_SOC_CPU_TMS")
	)
	(via
		(at 187.9092 -54.9402)
		(size 0.508)
		(drill 0.254)
		(layers "F.Cu" "B.Cu")
		(net "XDP_SOC_CPU_TMS")
	)
	(via
		(at 57.912 -27.509216)
		(size 0.508)
		(drill 0.254)
		(layers "F.Cu" "B.Cu")
		(net "XDP_SOC_CPU_TMS")
	)
	(via
		(at 85.2043 -38.3286)
		(size 0.4318)
		(drill 0.2032)
		(layers "F.Cu" "B.Cu")
		(net "XDP_SOC_CPU_TMS")
	)
	(via
		(at 160.8074 -50.3682)
		(size 0.508)
		(drill 0.254)
		(layers "F.Cu" "B.Cu")
		(net "XDP_SOC_CPU_TMS")
	)
	(via
		(at 34.583624 -35.05835)
		(size 0.508)
		(drill 0.254)
		(layers "F.Cu" "B.Cu")
		(net "XDP_SOC_CPU_TMS")
	)
	(segment
		(start 116.4463 -69.695314)
		(end 116.850414 -69.2912)
		(width 0.1143)
		(layer "B.Cu")
		(net "XDP_SOC_CPU_TMS")
	)
	(segment
		(start 115.9002 -70.866)
		(end 116.4463 -70.3199)
		(width 0.1143)
		(layer "B.Cu")
		(net "XDP_SOC_CPU_TMS")
	)
	(segment
		(start 116.850414 -69.2912)
		(end 118.491 -69.2912)
		(width 0.1143)
		(layer "B.Cu")
		(net "XDP_SOC_CPU_TMS")
	)
	(segment
		(start 111.379 -70.866)
		(end 115.9002 -70.866)
		(width 0.1143)
		(layer "B.Cu")
		(net "XDP_SOC_CPU_TMS")
	)
	(segment
		(start 116.4463 -70.3199)
		(end 116.4463 -69.695314)
		(width 0.1143)
		(layer "B.Cu")
		(net "XDP_SOC_CPU_TMS")
	)
	(segment
		(start 31.75 -38.832282)
		(end 33.016698 -37.565584)
		(width 0.0889)
		(layer "In2.Cu")
		(net "XDP_SOC_CPU_TMS")
	)
	(segment
		(start 53.88356 -55.245)
		(end 53.236114 -54.597554)
		(width 0.0889)
		(layer "In2.Cu")
		(net "XDP_SOC_CPU_TMS")
	)
	(segment
		(start 118.491 -69.2912)
		(end 116.913406 -69.2912)
		(width 0.0889)
		(layer "In2.Cu")
		(net "XDP_SOC_CPU_TMS")
	)
	(segment
		(start 116.49075 -70.148196)
		(end 113.7666 -72.8726)
		(width 0.0889)
		(layer "In2.Cu")
		(net "XDP_SOC_CPU_TMS")
	)
	(segment
		(start 41.53916 -54.597554)
		(end 38.370256 -51.42865)
		(width 0.0889)
		(layer "In2.Cu")
		(net "XDP_SOC_CPU_TMS")
	)
	(segment
		(start 53.236114 -54.597554)
		(end 41.53916 -54.597554)
		(width 0.0889)
		(layer "In2.Cu")
		(net "XDP_SOC_CPU_TMS")
	)
	(segment
		(start 116.913406 -69.2912)
		(end 116.49075 -69.713856)
		(width 0.0889)
		(layer "In2.Cu")
		(net "XDP_SOC_CPU_TMS")
	)
	(segment
		(start 59.137296 -64.516)
		(end 56.642 -62.020704)
		(width 0.0889)
		(layer "In2.Cu")
		(net "XDP_SOC_CPU_TMS")
	)
	(segment
		(start 56.642 -56.893206)
		(end 54.993794 -55.245)
		(width 0.0889)
		(layer "In2.Cu")
		(net "XDP_SOC_CPU_TMS")
	)
	(segment
		(start 56.642 -62.020704)
		(end 56.642 -56.893206)
		(width 0.0889)
		(layer "In2.Cu")
		(net "XDP_SOC_CPU_TMS")
	)
	(segment
		(start 113.7666 -72.8726)
		(end 79.502 -72.8726)
		(width 0.0889)
		(layer "In2.Cu")
		(net "XDP_SOC_CPU_TMS")
	)
	(segment
		(start 33.016698 -37.565584)
		(end 33.016698 -35.82924)
		(width 0.0889)
		(layer "In2.Cu")
		(net "XDP_SOC_CPU_TMS")
	)
	(segment
		(start 33.016698 -35.82924)
		(end 33.280604 -35.565334)
		(width 0.0889)
		(layer "In2.Cu")
		(net "XDP_SOC_CPU_TMS")
	)
	(segment
		(start 33.17875 -48.554894)
		(end 33.17875 -43.74515)
		(width 0.0889)
		(layer "In2.Cu")
		(net "XDP_SOC_CPU_TMS")
	)
	(segment
		(start 79.502 -72.8726)
		(end 77.9018 -71.2724)
		(width 0.0889)
		(layer "In2.Cu")
		(net "XDP_SOC_CPU_TMS")
	)
	(segment
		(start 62.4078 -67.472814)
		(end 62.4078 -64.90335)
		(width 0.0889)
		(layer "In2.Cu")
		(net "XDP_SOC_CPU_TMS")
	)
	(segment
		(start 62.02045 -64.516)
		(end 59.137296 -64.516)
		(width 0.0889)
		(layer "In2.Cu")
		(net "XDP_SOC_CPU_TMS")
	)
	(segment
		(start 77.06614 -69.738748)
		(end 64.673734 -69.738748)
		(width 0.0889)
		(layer "In2.Cu")
		(net "XDP_SOC_CPU_TMS")
	)
	(segment
		(start 64.673734 -69.738748)
		(end 62.4078 -67.472814)
		(width 0.0889)
		(layer "In2.Cu")
		(net "XDP_SOC_CPU_TMS")
	)
	(segment
		(start 38.370256 -51.42865)
		(end 36.052506 -51.42865)
		(width 0.0889)
		(layer "In2.Cu")
		(net "XDP_SOC_CPU_TMS")
	)
	(segment
		(start 33.280604 -35.565334)
		(end 34.07664 -35.565334)
		(width 0.0889)
		(layer "In2.Cu")
		(net "XDP_SOC_CPU_TMS")
	)
	(segment
		(start 33.17875 -43.74515)
		(end 31.75 -42.3164)
		(width 0.0889)
		(layer "In2.Cu")
		(net "XDP_SOC_CPU_TMS")
	)
	(segment
		(start 116.49075 -69.713856)
		(end 116.49075 -70.148196)
		(width 0.0889)
		(layer "In2.Cu")
		(net "XDP_SOC_CPU_TMS")
	)
	(segment
		(start 31.75 -42.3164)
		(end 31.75 -38.832282)
		(width 0.0889)
		(layer "In2.Cu")
		(net "XDP_SOC_CPU_TMS")
	)
	(segment
		(start 77.9018 -71.2724)
		(end 77.9018 -70.574408)
		(width 0.0889)
		(layer "In2.Cu")
		(net "XDP_SOC_CPU_TMS")
	)
	(segment
		(start 36.052506 -51.42865)
		(end 33.17875 -48.554894)
		(width 0.0889)
		(layer "In2.Cu")
		(net "XDP_SOC_CPU_TMS")
	)
	(segment
		(start 54.993794 -55.245)
		(end 53.88356 -55.245)
		(width 0.0889)
		(layer "In2.Cu")
		(net "XDP_SOC_CPU_TMS")
	)
	(segment
		(start 62.4078 -64.90335)
		(end 62.02045 -64.516)
		(width 0.0889)
		(layer "In2.Cu")
		(net "XDP_SOC_CPU_TMS")
	)
	(segment
		(start 77.9018 -70.574408)
		(end 77.06614 -69.738748)
		(width 0.0889)
		(layer "In2.Cu")
		(net "XDP_SOC_CPU_TMS")
	)
	(segment
		(start 34.07664 -35.565334)
		(end 34.583624 -35.05835)
		(width 0.0889)
		(layer "In2.Cu")
		(net "XDP_SOC_CPU_TMS")
	)
	(segment
		(start 51.11115 -28.69565)
		(end 51.406044 -28.69565)
		(width 0.0889)
		(layer "In4.Cu")
		(net "XDP_SOC_CPU_TMS")
	)
	(segment
		(start 187.325 -55.5244)
		(end 187.9092 -54.9402)
		(width 0.0889)
		(layer "In4.Cu")
		(net "XDP_SOC_CPU_TMS")
	)
	(segment
		(start 57.862216 -27.559)
		(end 57.912 -27.509216)
		(width 0.0889)
		(layer "In4.Cu")
		(net "XDP_SOC_CPU_TMS")
	)
	(segment
		(start 34.583624 -35.05835)
		(end 35.179254 -35.65398)
		(width 0.0889)
		(layer "In4.Cu")
		(net "XDP_SOC_CPU_TMS")
	)
	(segment
		(start 191.2366 -64.062356)
		(end 191.2366 -61.3156)
		(width 0.0889)
		(layer "In4.Cu")
		(net "XDP_SOC_CPU_TMS")
	)
	(segment
		(start 55.203344 -27.74315)
		(end 55.387494 -27.559)
		(width 0.0889)
		(layer "In4.Cu")
		(net "XDP_SOC_CPU_TMS")
	)
	(segment
		(start 187.325 -57.404)
		(end 187.325 -55.5244)
		(width 0.0889)
		(layer "In4.Cu")
		(net "XDP_SOC_CPU_TMS")
	)
	(segment
		(start 118.491 -69.2912)
		(end 126.8222 -69.2912)
		(width 0.0889)
		(layer "In4.Cu")
		(net "XDP_SOC_CPU_TMS")
	)
	(segment
		(start 52.358544 -27.74315)
		(end 55.203344 -27.74315)
		(width 0.0889)
		(layer "In4.Cu")
		(net "XDP_SOC_CPU_TMS")
	)
	(segment
		(start 51.406044 -28.69565)
		(end 52.358544 -27.74315)
		(width 0.0889)
		(layer "In4.Cu")
		(net "XDP_SOC_CPU_TMS")
	)
	(segment
		(start 191.2366 -61.3156)
		(end 187.325 -57.404)
		(width 0.0889)
		(layer "In4.Cu")
		(net "XDP_SOC_CPU_TMS")
	)
	(segment
		(start 189.69609 -70.01891)
		(end 190.246 -69.469)
		(width 0.0889)
		(layer "In4.Cu")
		(net "XDP_SOC_CPU_TMS")
	)
	(segment
		(start 190.246 -69.469)
		(end 190.246 -65.052956)
		(width 0.0889)
		(layer "In4.Cu")
		(net "XDP_SOC_CPU_TMS")
	)
	(segment
		(start 35.179254 -35.65398)
		(end 44.15282 -35.65398)
		(width 0.0889)
		(layer "In4.Cu")
		(net "XDP_SOC_CPU_TMS")
	)
	(segment
		(start 190.246 -65.052956)
		(end 191.2366 -64.062356)
		(width 0.0889)
		(layer "In4.Cu")
		(net "XDP_SOC_CPU_TMS")
	)
	(segment
		(start 44.15282 -35.65398)
		(end 51.11115 -28.69565)
		(width 0.0889)
		(layer "In4.Cu")
		(net "XDP_SOC_CPU_TMS")
	)
	(segment
		(start 55.387494 -27.559)
		(end 57.862216 -27.559)
		(width 0.0889)
		(layer "In4.Cu")
		(net "XDP_SOC_CPU_TMS")
	)
	(segment
		(start 127.54991 -70.01891)
		(end 189.69609 -70.01891)
		(width 0.0889)
		(layer "In4.Cu")
		(net "XDP_SOC_CPU_TMS")
	)
	(segment
		(start 126.8222 -69.2912)
		(end 127.54991 -70.01891)
		(width 0.0889)
		(layer "In4.Cu")
		(net "XDP_SOC_CPU_TMS")
	)
	(segment
		(start 74.578972 -31.112714)
		(end 73.470008 -30.00375)
		(width 0.0889)
		(layer "In7.Cu")
		(net "XDP_SOC_CPU_TMS")
	)
	(segment
		(start 72.270366 -30.00375)
		(end 71.844916 -30.4292)
		(width 0.0889)
		(layer "In7.Cu")
		(net "XDP_SOC_CPU_TMS")
	)
	(segment
		(start 64.816228 -28.03525)
		(end 58.438034 -28.03525)
		(width 0.0889)
		(layer "In7.Cu")
		(net "XDP_SOC_CPU_TMS")
	)
	(segment
		(start 83.253072 -38.288976)
		(end 82.307176 -38.288976)
		(width 0.0889)
		(layer "In7.Cu")
		(net "XDP_SOC_CPU_TMS")
	)
	(segment
		(start 79.19847 -37.11448)
		(end 76.3016 -34.21761)
		(width 0.0889)
		(layer "In7.Cu")
		(net "XDP_SOC_CPU_TMS")
	)
	(segment
		(start 58.438034 -28.03525)
		(end 57.912 -27.509216)
		(width 0.0889)
		(layer "In7.Cu")
		(net "XDP_SOC_CPU_TMS")
	)
	(segment
		(start 76.3016 -32.639)
		(end 74.775314 -31.112714)
		(width 0.0889)
		(layer "In7.Cu")
		(net "XDP_SOC_CPU_TMS")
	)
	(segment
		(start 81.13268 -37.11448)
		(end 79.19847 -37.11448)
		(width 0.0889)
		(layer "In7.Cu")
		(net "XDP_SOC_CPU_TMS")
	)
	(segment
		(start 74.775314 -31.112714)
		(end 74.578972 -31.112714)
		(width 0.0889)
		(layer "In7.Cu")
		(net "XDP_SOC_CPU_TMS")
	)
	(segment
		(start 85.09 -38.3286)
		(end 84.70265 -37.94125)
		(width 0.0889)
		(layer "In7.Cu")
		(net "XDP_SOC_CPU_TMS")
	)
	(segment
		(start 73.470008 -30.00375)
		(end 72.270366 -30.00375)
		(width 0.0889)
		(layer "In7.Cu")
		(net "XDP_SOC_CPU_TMS")
	)
	(segment
		(start 71.844916 -30.4292)
		(end 67.210178 -30.4292)
		(width 0.0889)
		(layer "In7.Cu")
		(net "XDP_SOC_CPU_TMS")
	)
	(segment
		(start 82.307176 -38.288976)
		(end 81.13268 -37.11448)
		(width 0.0889)
		(layer "In7.Cu")
		(net "XDP_SOC_CPU_TMS")
	)
	(segment
		(start 83.600798 -37.94125)
		(end 83.253072 -38.288976)
		(width 0.0889)
		(layer "In7.Cu")
		(net "XDP_SOC_CPU_TMS")
	)
	(segment
		(start 85.2043 -38.3286)
		(end 85.09 -38.3286)
		(width 0.0889)
		(layer "In7.Cu")
		(net "XDP_SOC_CPU_TMS")
	)
	(segment
		(start 84.70265 -37.94125)
		(end 83.600798 -37.94125)
		(width 0.0889)
		(layer "In7.Cu")
		(net "XDP_SOC_CPU_TMS")
	)
	(segment
		(start 76.3016 -34.21761)
		(end 76.3016 -32.639)
		(width 0.0889)
		(layer "In7.Cu")
		(net "XDP_SOC_CPU_TMS")
	)
	(segment
		(start 67.210178 -30.4292)
		(end 64.816228 -28.03525)
		(width 0.0889)
		(layer "In7.Cu")
		(net "XDP_SOC_CPU_TMS")
	)
	(segment
		(start 160.8074 -50.3682)
		(end 165.0746 -54.6354)
		(width 0.0889)
		(layer "In9.Cu")
		(net "XDP_SOC_CPU_TMS")
	)
	(segment
		(start 165.0746 -54.6354)
		(end 187.6044 -54.6354)
		(width 0.0889)
		(layer "In9.Cu")
		(net "XDP_SOC_CPU_TMS")
	)
	(segment
		(start 187.6044 -54.6354)
		(end 187.9092 -54.9402)
		(width 0.0889)
		(layer "In9.Cu")
		(net "XDP_SOC_CPU_TMS")
	)
	(segment
		(start 140.843 -56.0578)
		(end 140.52042 -55.73522)
		(width 0.254)
		(layer "F.Cu")
		(net "PV_VTT_DDR_EN")
	)
	(segment
		(start 138.86434 -55.960264)
		(end 139.707366 -55.960264)
		(width 0.254)
		(layer "F.Cu")
		(net "PV_VTT_DDR_EN")
	)
	(segment
		(start 140.52042 -55.73522)
		(end 139.93241 -55.73522)
		(width 0.254)
		(layer "F.Cu")
		(net "PV_VTT_DDR_EN")
	)
	(segment
		(start 139.707366 -55.960264)
		(end 139.93241 -55.73522)
		(width 0.254)
		(layer "F.Cu")
		(net "PV_VTT_DDR_EN")
	)
	(via
		(at 139.93241 -55.73522)
		(size 0.7112)
		(drill 0.3556)
		(layers "F.Cu" "B.Cu")
		(net "PV_VTT_DDR_EN")
	)
	(segment
		(start 99.701858 -46.148244)
		(end 99.720146 -46.148244)
		(width 0.1016)
		(layer "F.Cu")
		(net "M_A_ODT1")
	)
	(segment
		(start 99.352608 -46.497494)
		(end 99.701858 -46.148244)
		(width 0.1016)
		(layer "F.Cu")
		(net "M_A_ODT1")
	)
	(via
		(at 150.241 -68.6054)
		(size 0.4318)
		(drill 0.2032)
		(layers "F.Cu" "B.Cu")
		(net "M_A_ODT1")
	)
	(via
		(at 99.720146 -46.148244)
		(size 0.4318)
		(drill 0.2032)
		(layers "F.Cu" "B.Cu")
		(net "M_A_ODT1")
	)
	(segment
		(start 149.649942 -70.79996)
		(end 149.649942 -69.729858)
		(width 0.1778)
		(layer "B.Cu")
		(net "M_A_ODT1")
	)
	(segment
		(start 149.805644 -69.040756)
		(end 150.241 -68.6054)
		(width 0.1778)
		(layer "B.Cu")
		(net "M_A_ODT1")
	)
	(segment
		(start 149.649942 -69.729858)
		(end 149.805644 -69.574156)
		(width 0.1778)
		(layer "B.Cu")
		(net "M_A_ODT1")
	)
	(segment
		(start 149.805644 -69.574156)
		(end 149.805644 -69.040756)
		(width 0.1778)
		(layer "B.Cu")
		(net "M_A_ODT1")
	)
	(segment
		(start 120.874028 -54.864)
		(end 119.330978 -56.40705)
		(width 0.1524)
		(layer "In7.Cu")
		(net "M_A_ODT1")
	)
	(segment
		(start 108.43895 -56.40705)
		(end 108.1024 -56.0705)
		(width 0.1524)
		(layer "In7.Cu")
		(net "M_A_ODT1")
	)
	(segment
		(start 145.0848 -57.3786)
		(end 143.106648 -57.3786)
		(width 0.1524)
		(layer "In7.Cu")
		(net "M_A_ODT1")
	)
	(segment
		(start 151.456898 -67.662298)
		(end 151.456898 -65.862962)
		(width 0.1524)
		(layer "In7.Cu")
		(net "M_A_ODT1")
	)
	(segment
		(start 142.078964 -57.1246)
		(end 140.199364 -55.245)
		(width 0.1524)
		(layer "In7.Cu")
		(net "M_A_ODT1")
	)
	(segment
		(start 125.664468 -55.09006)
		(end 122.787664 -55.09006)
		(width 0.1524)
		(layer "In7.Cu")
		(net "M_A_ODT1")
	)
	(segment
		(start 101.2825 -47.16526)
		(end 101.284278 -47.167038)
		(width 0.1016)
		(layer "In7.Cu")
		(net "M_A_ODT1")
	)
	(segment
		(start 104.8512 -54.2036)
		(end 105.791 -54.2036)
		(width 0.1016)
		(layer "In7.Cu")
		(net "M_A_ODT1")
	)
	(segment
		(start 125.890528 -54.864)
		(end 125.664468 -55.09006)
		(width 0.1524)
		(layer "In7.Cu")
		(net "M_A_ODT1")
	)
	(segment
		(start 127.4318 -54.864)
		(end 125.890528 -54.864)
		(width 0.1524)
		(layer "In7.Cu")
		(net "M_A_ODT1")
	)
	(segment
		(start 150.876 -69.8246)
		(end 152.4508 -69.8246)
		(width 0.1524)
		(layer "In7.Cu")
		(net "M_A_ODT1")
	)
	(segment
		(start 106.2863 -56.0705)
		(end 106.0831 -55.8673)
		(width 0.1524)
		(layer "In7.Cu")
		(net "M_A_ODT1")
	)
	(segment
		(start 152.6032 -69.6722)
		(end 152.6032 -68.0466)
		(width 0.1524)
		(layer "In7.Cu")
		(net "M_A_ODT1")
	)
	(segment
		(start 142.852648 -57.1246)
		(end 142.078964 -57.1246)
		(width 0.1524)
		(layer "In7.Cu")
		(net "M_A_ODT1")
	)
	(segment
		(start 145.8468 -58.1406)
		(end 145.0848 -57.3786)
		(width 0.1524)
		(layer "In7.Cu")
		(net "M_A_ODT1")
	)
	(segment
		(start 152.6032 -68.0466)
		(end 152.4254 -67.8688)
		(width 0.1524)
		(layer "In7.Cu")
		(net "M_A_ODT1")
	)
	(segment
		(start 105.791 -54.2036)
		(end 105.9053 -54.3179)
		(width 0.1016)
		(layer "In7.Cu")
		(net "M_A_ODT1")
	)
	(segment
		(start 143.106648 -57.3786)
		(end 142.852648 -57.1246)
		(width 0.1524)
		(layer "In7.Cu")
		(net "M_A_ODT1")
	)
	(segment
		(start 150.7236 -68.8848)
		(end 150.7236 -69.6722)
		(width 0.1524)
		(layer "In7.Cu")
		(net "M_A_ODT1")
	)
	(segment
		(start 152.4508 -69.8246)
		(end 152.6032 -69.6722)
		(width 0.1524)
		(layer "In7.Cu")
		(net "M_A_ODT1")
	)
	(segment
		(start 122.787664 -55.09006)
		(end 122.561604 -54.864)
		(width 0.1524)
		(layer "In7.Cu")
		(net "M_A_ODT1")
	)
	(segment
		(start 108.1024 -56.0705)
		(end 106.2863 -56.0705)
		(width 0.1524)
		(layer "In7.Cu")
		(net "M_A_ODT1")
	)
	(segment
		(start 150.7236 -69.6722)
		(end 150.876 -69.8246)
		(width 0.1524)
		(layer "In7.Cu")
		(net "M_A_ODT1")
	)
	(segment
		(start 127.8128 -55.245)
		(end 127.4318 -54.864)
		(width 0.1524)
		(layer "In7.Cu")
		(net "M_A_ODT1")
	)
	(segment
		(start 101.284278 -47.167038)
		(end 101.284278 -47.451518)
		(width 0.1016)
		(layer "In7.Cu")
		(net "M_A_ODT1")
	)
	(segment
		(start 106.0831 -54.4957)
		(end 105.9053 -54.3179)
		(width 0.1524)
		(layer "In7.Cu")
		(net "M_A_ODT1")
	)
	(segment
		(start 146.466814 -58.1406)
		(end 145.8468 -58.1406)
		(width 0.1524)
		(layer "In7.Cu")
		(net "M_A_ODT1")
	)
	(segment
		(start 152.4254 -67.8688)
		(end 151.6634 -67.8688)
		(width 0.1524)
		(layer "In7.Cu")
		(net "M_A_ODT1")
	)
	(segment
		(start 151.6634 -67.8688)
		(end 151.456898 -67.662298)
		(width 0.1524)
		(layer "In7.Cu")
		(net "M_A_ODT1")
	)
	(segment
		(start 101.284278 -47.451518)
		(end 101.854 -48.02124)
		(width 0.1016)
		(layer "In7.Cu")
		(net "M_A_ODT1")
	)
	(segment
		(start 106.0831 -55.8673)
		(end 106.0831 -54.4957)
		(width 0.1524)
		(layer "In7.Cu")
		(net "M_A_ODT1")
	)
	(segment
		(start 99.720146 -46.148244)
		(end 100.117402 -46.148244)
		(width 0.1016)
		(layer "In7.Cu")
		(net "M_A_ODT1")
	)
	(segment
		(start 100.67798 -46.3804)
		(end 101.154992 -46.857412)
		(width 0.1016)
		(layer "In7.Cu")
		(net "M_A_ODT1")
	)
	(segment
		(start 151.456898 -65.862962)
		(end 151.13 -65.536064)
		(width 0.1524)
		(layer "In7.Cu")
		(net "M_A_ODT1")
	)
	(segment
		(start 119.330978 -56.40705)
		(end 108.43895 -56.40705)
		(width 0.1524)
		(layer "In7.Cu")
		(net "M_A_ODT1")
	)
	(segment
		(start 150.241 -68.6054)
		(end 150.4442 -68.6054)
		(width 0.1524)
		(layer "In7.Cu")
		(net "M_A_ODT1")
	)
	(segment
		(start 101.854 -51.2064)
		(end 104.8512 -54.2036)
		(width 0.1016)
		(layer "In7.Cu")
		(net "M_A_ODT1")
	)
	(segment
		(start 151.13 -65.536064)
		(end 151.13 -62.803786)
		(width 0.1524)
		(layer "In7.Cu")
		(net "M_A_ODT1")
	)
	(segment
		(start 150.4442 -68.6054)
		(end 150.7236 -68.8848)
		(width 0.1524)
		(layer "In7.Cu")
		(net "M_A_ODT1")
	)
	(segment
		(start 151.13 -62.803786)
		(end 146.466814 -58.1406)
		(width 0.1524)
		(layer "In7.Cu")
		(net "M_A_ODT1")
	)
	(segment
		(start 122.561604 -54.864)
		(end 120.874028 -54.864)
		(width 0.1524)
		(layer "In7.Cu")
		(net "M_A_ODT1")
	)
	(segment
		(start 101.854 -48.02124)
		(end 101.854 -51.2064)
		(width 0.1016)
		(layer "In7.Cu")
		(net "M_A_ODT1")
	)
	(segment
		(start 140.199364 -55.245)
		(end 127.8128 -55.245)
		(width 0.1524)
		(layer "In7.Cu")
		(net "M_A_ODT1")
	)
	(arc
		(start 100.117402 -46.148244)
		(mid 100.420768 -46.208587)
		(end 100.67798 -46.3804)
		(width 0.1016)
		(layer "In7.Cu")
		(net "M_A_ODT1")
	)
	(arc
		(start 101.154992 -46.857412)
		(mid 101.249367 -46.998654)
		(end 101.2825 -47.16526)
		(width 0.1016)
		(layer "In7.Cu")
		(net "M_A_ODT1")
	)
	(segment
		(start 103.404924 -26.275284)
		(end 103.618284 -26.275284)
		(width 0.1016)
		(layer "F.Cu")
		(net "M_B_ECC4")
	)
	(segment
		(start 103.1494 -24.9174)
		(end 103.1494 -26.01976)
		(width 0.1016)
		(layer "F.Cu")
		(net "M_B_ECC4")
	)
	(segment
		(start 148.75002 -2.567178)
		(end 149.33676 -3.153918)
		(width 0.1778)
		(layer "F.Cu")
		(net "M_B_ECC4")
	)
	(segment
		(start 103.618284 -26.275284)
		(end 104.1908 -26.8478)
		(width 0.1016)
		(layer "F.Cu")
		(net "M_B_ECC4")
	)
	(segment
		(start 148.75002 -1.68402)
		(end 148.75002 -2.567178)
		(width 0.1778)
		(layer "F.Cu")
		(net "M_B_ECC4")
	)
	(segment
		(start 103.4796 -23.114)
		(end 103.4796 -24.5872)
		(width 0.1016)
		(layer "F.Cu")
		(net "M_B_ECC4")
	)
	(segment
		(start 104.1908 -26.8478)
		(end 104.290368 -27.404314)
		(width 0.1016)
		(layer "F.Cu")
		(net "M_B_ECC4")
	)
	(segment
		(start 103.4796 -24.5872)
		(end 103.1494 -24.9174)
		(width 0.1016)
		(layer "F.Cu")
		(net "M_B_ECC4")
	)
	(segment
		(start 103.1494 -26.01976)
		(end 103.404924 -26.275284)
		(width 0.1016)
		(layer "F.Cu")
		(net "M_B_ECC4")
	)
	(via
		(at 149.33676 -3.153918)
		(size 0.4318)
		(drill 0.2032)
		(layers "F.Cu" "B.Cu")
		(net "M_B_ECC4")
	)
	(via
		(at 103.4796 -23.114)
		(size 0.4318)
		(drill 0.2032)
		(layers "F.Cu" "B.Cu")
		(net "M_B_ECC4")
	)
	(segment
		(start 149.649942 -1.690624)
		(end 149.649942 -2.955036)
		(width 0.1778)
		(layer "B.Cu")
		(net "M_B_ECC4")
	)
	(segment
		(start 149.45106 -3.153918)
		(end 149.33676 -3.153918)
		(width 0.1778)
		(layer "B.Cu")
		(net "M_B_ECC4")
	)
	(segment
		(start 149.649942 -2.955036)
		(end 149.45106 -3.153918)
		(width 0.1778)
		(layer "B.Cu")
		(net "M_B_ECC4")
	)
	(segment
		(start 120.8532 -18.490946)
		(end 110.287054 -18.490946)
		(width 0.1524)
		(layer "In2.Cu")
		(net "M_B_ECC4")
	)
	(segment
		(start 146.6088 -7.38124)
		(end 146.6088 -8.917178)
		(width 0.1524)
		(layer "In2.Cu")
		(net "M_B_ECC4")
	)
	(segment
		(start 103.4796 -23.0886)
		(end 103.4796 -23.114)
		(width 0.1016)
		(layer "In2.Cu")
		(net "M_B_ECC4")
	)
	(segment
		(start 110.287054 -18.490946)
		(end 108.4072 -20.3708)
		(width 0.1524)
		(layer "In2.Cu")
		(net "M_B_ECC4")
	)
	(segment
		(start 137.9474 -17.0942)
		(end 121.158 -17.0942)
		(width 0.1524)
		(layer "In2.Cu")
		(net "M_B_ECC4")
	)
	(segment
		(start 149.33676 -3.153918)
		(end 149.33676 -4.65328)
		(width 0.1524)
		(layer "In2.Cu")
		(net "M_B_ECC4")
	)
	(segment
		(start 108.4072 -20.3708)
		(end 104.0384 -20.3708)
		(width 0.1524)
		(layer "In2.Cu")
		(net "M_B_ECC4")
	)
	(segment
		(start 149.33676 -4.65328)
		(end 146.6088 -7.38124)
		(width 0.1524)
		(layer "In2.Cu")
		(net "M_B_ECC4")
	)
	(segment
		(start 138.4808 -16.5608)
		(end 137.9474 -17.0942)
		(width 0.1524)
		(layer "In2.Cu")
		(net "M_B_ECC4")
	)
	(segment
		(start 103.0224 -22.6314)
		(end 103.4796 -23.0886)
		(width 0.1016)
		(layer "In2.Cu")
		(net "M_B_ECC4")
	)
	(segment
		(start 103.632 -20.3708)
		(end 103.0224 -20.9804)
		(width 0.1016)
		(layer "In2.Cu")
		(net "M_B_ECC4")
	)
	(segment
		(start 104.0384 -20.3708)
		(end 103.632 -20.3708)
		(width 0.1016)
		(layer "In2.Cu")
		(net "M_B_ECC4")
	)
	(segment
		(start 147.8534 -15.33017)
		(end 146.62277 -16.5608)
		(width 0.1524)
		(layer "In2.Cu")
		(net "M_B_ECC4")
	)
	(segment
		(start 146.6088 -8.917178)
		(end 147.8534 -10.161778)
		(width 0.1524)
		(layer "In2.Cu")
		(net "M_B_ECC4")
	)
	(segment
		(start 147.8534 -10.161778)
		(end 147.8534 -15.33017)
		(width 0.1524)
		(layer "In2.Cu")
		(net "M_B_ECC4")
	)
	(segment
		(start 121.0056 -18.338546)
		(end 120.8532 -18.490946)
		(width 0.1524)
		(layer "In2.Cu")
		(net "M_B_ECC4")
	)
	(segment
		(start 121.158 -17.0942)
		(end 121.0056 -17.2466)
		(width 0.1524)
		(layer "In2.Cu")
		(net "M_B_ECC4")
	)
	(segment
		(start 146.62277 -16.5608)
		(end 138.4808 -16.5608)
		(width 0.1524)
		(layer "In2.Cu")
		(net "M_B_ECC4")
	)
	(segment
		(start 103.0224 -20.9804)
		(end 103.0224 -22.6314)
		(width 0.1016)
		(layer "In2.Cu")
		(net "M_B_ECC4")
	)
	(segment
		(start 121.0056 -17.2466)
		(end 121.0056 -18.338546)
		(width 0.1524)
		(layer "In2.Cu")
		(net "M_B_ECC4")
	)
	(segment
		(start 80.096868 -44.320714)
		(end 79.962248 -44.320714)
		(width 0.1143)
		(layer "F.Cu")
		(net "XDP_DFX_PORT_CLK1")
	)
	(segment
		(start 77.879448 -43.664632)
		(end 77.879448 -43.658028)
		(width 0.1143)
		(layer "F.Cu")
		(net "XDP_DFX_PORT_CLK1")
	)
	(segment
		(start 32.893 -21.5138)
		(end 32.893 -20.6248)
		(width 0.1143)
		(layer "F.Cu")
		(net "XDP_DFX_PORT_CLK1")
	)
	(segment
		(start 78.53426 -44.319444)
		(end 77.879448 -43.664632)
		(width 0.1143)
		(layer "F.Cu")
		(net "XDP_DFX_PORT_CLK1")
	)
	(segment
		(start 32.8422 -21.5646)
		(end 32.893 -21.5138)
		(width 0.1143)
		(layer "F.Cu")
		(net "XDP_DFX_PORT_CLK1")
	)
	(segment
		(start 79.962248 -44.320714)
		(end 79.960978 -44.319444)
		(width 0.1143)
		(layer "F.Cu")
		(net "XDP_DFX_PORT_CLK1")
	)
	(segment
		(start 79.960978 -44.319444)
		(end 78.53426 -44.319444)
		(width 0.1143)
		(layer "F.Cu")
		(net "XDP_DFX_PORT_CLK1")
	)
	(via
		(at 32.600392 -20.778216)
		(size 0.7112)
		(drill 0.3556)
		(layers "F.Cu" "B.Cu")
		(net "XDP_DFX_PORT_CLK1")
	)
	(via
		(at 32.8422 -21.5646)
		(size 0.508)
		(drill 0.254)
		(layers "F.Cu" "B.Cu")
		(net "XDP_DFX_PORT_CLK1")
	)
	(via
		(at 77.879448 -43.658028)
		(size 0.508)
		(drill 0.254)
		(layers "F.Cu" "B.Cu")
		(net "XDP_DFX_PORT_CLK1")
	)
	(segment
		(start 32.600392 -20.778216)
		(end 32.600392 -21.322792)
		(width 0.1143)
		(layer "B.Cu")
		(net "XDP_DFX_PORT_CLK1")
	)
	(segment
		(start 32.600392 -21.322792)
		(end 32.8422 -21.5646)
		(width 0.1143)
		(layer "B.Cu")
		(net "XDP_DFX_PORT_CLK1")
	)
	(segment
		(start 58.391552 -37.64915)
		(end 65.78092 -37.64915)
		(width 0.0889)
		(layer "In7.Cu")
		(net "XDP_DFX_PORT_CLK1")
	)
	(segment
		(start 69.351144 -38.52545)
		(end 69.821044 -38.05555)
		(width 0.0889)
		(layer "In7.Cu")
		(net "XDP_DFX_PORT_CLK1")
	)
	(segment
		(start 57.233058 -36.490656)
		(end 58.391552 -37.64915)
		(width 0.0889)
		(layer "In7.Cu")
		(net "XDP_DFX_PORT_CLK1")
	)
	(segment
		(start 46.668436 -32.258)
		(end 50.901092 -36.490656)
		(width 0.0889)
		(layer "In7.Cu")
		(net "XDP_DFX_PORT_CLK1")
	)
	(segment
		(start 32.8422 -21.5646)
		(end 33.0327 -21.3741)
		(width 0.0889)
		(layer "In7.Cu")
		(net "XDP_DFX_PORT_CLK1")
	)
	(segment
		(start 50.901092 -36.490656)
		(end 57.233058 -36.490656)
		(width 0.0889)
		(layer "In7.Cu")
		(net "XDP_DFX_PORT_CLK1")
	)
	(segment
		(start 72.8726 -40.043354)
		(end 76.136246 -43.307)
		(width 0.0889)
		(layer "In7.Cu")
		(net "XDP_DFX_PORT_CLK1")
	)
	(segment
		(start 72.8726 -38.646608)
		(end 72.8726 -40.043354)
		(width 0.0889)
		(layer "In7.Cu")
		(net "XDP_DFX_PORT_CLK1")
	)
	(segment
		(start 39.19347 -25.411176)
		(end 46.040294 -32.258)
		(width 0.0889)
		(layer "In7.Cu")
		(net "XDP_DFX_PORT_CLK1")
	)
	(segment
		(start 39.19347 -24.893778)
		(end 39.19347 -25.411176)
		(width 0.0889)
		(layer "In7.Cu")
		(net "XDP_DFX_PORT_CLK1")
	)
	(segment
		(start 77.52842 -43.307)
		(end 77.879448 -43.658028)
		(width 0.0889)
		(layer "In7.Cu")
		(net "XDP_DFX_PORT_CLK1")
	)
	(segment
		(start 69.821044 -38.05555)
		(end 72.281542 -38.05555)
		(width 0.0889)
		(layer "In7.Cu")
		(net "XDP_DFX_PORT_CLK1")
	)
	(segment
		(start 72.281542 -38.05555)
		(end 72.8726 -38.646608)
		(width 0.0889)
		(layer "In7.Cu")
		(net "XDP_DFX_PORT_CLK1")
	)
	(segment
		(start 35.673792 -21.3741)
		(end 39.19347 -24.893778)
		(width 0.0889)
		(layer "In7.Cu")
		(net "XDP_DFX_PORT_CLK1")
	)
	(segment
		(start 46.040294 -32.258)
		(end 46.668436 -32.258)
		(width 0.0889)
		(layer "In7.Cu")
		(net "XDP_DFX_PORT_CLK1")
	)
	(segment
		(start 65.78092 -37.64915)
		(end 66.65722 -38.52545)
		(width 0.0889)
		(layer "In7.Cu")
		(net "XDP_DFX_PORT_CLK1")
	)
	(segment
		(start 33.0327 -21.3741)
		(end 35.673792 -21.3741)
		(width 0.0889)
		(layer "In7.Cu")
		(net "XDP_DFX_PORT_CLK1")
	)
	(segment
		(start 66.65722 -38.52545)
		(end 69.351144 -38.52545)
		(width 0.0889)
		(layer "In7.Cu")
		(net "XDP_DFX_PORT_CLK1")
	)
	(segment
		(start 76.136246 -43.307)
		(end 77.52842 -43.307)
		(width 0.0889)
		(layer "In7.Cu")
		(net "XDP_DFX_PORT_CLK1")
	)
	(via
		(at 54.6354 -49.3268)
		(size 0.508)
		(drill 0.254)
		(layers "F.Cu" "B.Cu")
		(net "P1V5_STBY_PG")
	)
	(via
		(at 29.1846 -52.6542)
		(size 0.7112)
		(drill 0.3556)
		(layers "F.Cu" "B.Cu")
		(net "P1V5_STBY_PG")
	)
	(via
		(at 28.4226 -53.086)
		(size 0.508)
		(drill 0.254)
		(layers "F.Cu" "B.Cu")
		(net "P1V5_STBY_PG")
	)
	(segment
		(start 28.8544 -52.6542)
		(end 29.1846 -52.6542)
		(width 0.254)
		(layer "B.Cu")
		(net "P1V5_STBY_PG")
	)
	(segment
		(start 30.734 -52.07)
		(end 30.734 -53.1622)
		(width 0.254)
		(layer "B.Cu")
		(net "P1V5_STBY_PG")
	)
	(segment
		(start 31.069026 -51.734974)
		(end 30.734 -52.07)
		(width 0.254)
		(layer "B.Cu")
		(net "P1V5_STBY_PG")
	)
	(segment
		(start 30.226 -53.1622)
		(end 29.718 -52.6542)
		(width 0.254)
		(layer "B.Cu")
		(net "P1V5_STBY_PG")
	)
	(segment
		(start 31.069026 -50.968148)
		(end 31.069026 -51.734974)
		(width 0.254)
		(layer "B.Cu")
		(net "P1V5_STBY_PG")
	)
	(segment
		(start 30.734 -53.1622)
		(end 30.226 -53.1622)
		(width 0.254)
		(layer "B.Cu")
		(net "P1V5_STBY_PG")
	)
	(segment
		(start 28.4226 -53.086)
		(end 28.8544 -52.6542)
		(width 0.254)
		(layer "B.Cu")
		(net "P1V5_STBY_PG")
	)
	(segment
		(start 55.3974 -49.53)
		(end 54.8386 -49.53)
		(width 0.254)
		(layer "B.Cu")
		(net "P1V5_STBY_PG")
	)
	(segment
		(start 54.8386 -49.53)
		(end 54.6354 -49.3268)
		(width 0.254)
		(layer "B.Cu")
		(net "P1V5_STBY_PG")
	)
	(segment
		(start 29.718 -52.6542)
		(end 29.1846 -52.6542)
		(width 0.254)
		(layer "B.Cu")
		(net "P1V5_STBY_PG")
	)
	(segment
		(start 41.590722 -52.2097)
		(end 41.603422 -52.2224)
		(width 0.254)
		(layer "In4.Cu")
		(net "P1V5_STBY_PG")
	)
	(segment
		(start 34.1503 -52.2097)
		(end 41.590722 -52.2097)
		(width 0.254)
		(layer "In4.Cu")
		(net "P1V5_STBY_PG")
	)
	(segment
		(start 42.954194 -51.660806)
		(end 50.577496 -51.660806)
		(width 0.254)
		(layer "In4.Cu")
		(net "P1V5_STBY_PG")
	)
	(segment
		(start 28.4226 -53.086)
		(end 28.4226 -52.812442)
		(width 0.254)
		(layer "In4.Cu")
		(net "P1V5_STBY_PG")
	)
	(segment
		(start 33.0454 -51.1048)
		(end 34.1503 -52.2097)
		(width 0.254)
		(layer "In4.Cu")
		(net "P1V5_STBY_PG")
	)
	(segment
		(start 30.130242 -51.1048)
		(end 33.0454 -51.1048)
		(width 0.254)
		(layer "In4.Cu")
		(net "P1V5_STBY_PG")
	)
	(segment
		(start 28.4226 -52.812442)
		(end 30.130242 -51.1048)
		(width 0.254)
		(layer "In4.Cu")
		(net "P1V5_STBY_PG")
	)
	(segment
		(start 50.816002 -51.4223)
		(end 52.441602 -51.4223)
		(width 0.254)
		(layer "In4.Cu")
		(net "P1V5_STBY_PG")
	)
	(segment
		(start 54.219856 -49.644046)
		(end 54.318154 -49.644046)
		(width 0.254)
		(layer "In4.Cu")
		(net "P1V5_STBY_PG")
	)
	(segment
		(start 52.441602 -51.4223)
		(end 54.219856 -49.644046)
		(width 0.254)
		(layer "In4.Cu")
		(net "P1V5_STBY_PG")
	)
	(segment
		(start 54.318154 -49.644046)
		(end 54.6354 -49.3268)
		(width 0.254)
		(layer "In4.Cu")
		(net "P1V5_STBY_PG")
	)
	(segment
		(start 42.3926 -52.2224)
		(end 42.954194 -51.660806)
		(width 0.254)
		(layer "In4.Cu")
		(net "P1V5_STBY_PG")
	)
	(segment
		(start 50.577496 -51.660806)
		(end 50.816002 -51.4223)
		(width 0.254)
		(layer "In4.Cu")
		(net "P1V5_STBY_PG")
	)
	(segment
		(start 41.603422 -52.2224)
		(end 42.3926 -52.2224)
		(width 0.254)
		(layer "In4.Cu")
		(net "P1V5_STBY_PG")
	)
	(segment
		(start 142.24 -56.8198)
		(end 142.494 -56.5658)
		(width 0.254)
		(layer "F.Cu")
		(net "PWRGD_PVTT_PG")
	)
	(segment
		(start 141.7066 -56.8198)
		(end 142.24 -56.8198)
		(width 0.254)
		(layer "F.Cu")
		(net "PWRGD_PVTT_PG")
	)
	(segment
		(start 15.4178 -57.6072)
		(end 14.6812 -57.6072)
		(width 0.254)
		(layer "F.Cu")
		(net "PWRGD_PVTT_PG")
	)
	(segment
		(start 184.6072 -23.622)
		(end 184.6072 -24.257)
		(width 0.254)
		(layer "F.Cu")
		(net "PWRGD_PVTT_PG")
	)
	(segment
		(start 184.912 -23.3172)
		(end 184.6072 -23.622)
		(width 0.254)
		(layer "F.Cu")
		(net "PWRGD_PVTT_PG")
	)
	(segment
		(start 14.6812 -57.6072)
		(end 14.6304 -57.5564)
		(width 0.254)
		(layer "F.Cu")
		(net "PWRGD_PVTT_PG")
	)
	(via
		(at 182.6006 -42.2148)
		(size 0.7112)
		(drill 0.3556)
		(layers "F.Cu" "B.Cu")
		(net "PWRGD_PVTT_PG")
	)
	(via
		(at 14.6304 -57.5564)
		(size 0.508)
		(drill 0.254)
		(layers "F.Cu" "B.Cu")
		(net "PWRGD_PVTT_PG")
	)
	(via
		(at 142.494 -56.5658)
		(size 0.508)
		(drill 0.254)
		(layers "F.Cu" "B.Cu")
		(net "PWRGD_PVTT_PG")
	)
	(via
		(at 11.8872 -69.723)
		(size 0.508)
		(drill 0.254)
		(layers "F.Cu" "B.Cu")
		(net "PWRGD_PVTT_PG")
	)
	(via
		(at 184.6072 -24.257)
		(size 0.508)
		(drill 0.254)
		(layers "F.Cu" "B.Cu")
		(net "PWRGD_PVTT_PG")
	)
	(via
		(at 57.658 -69.977)
		(size 0.508)
		(drill 0.254)
		(layers "F.Cu" "B.Cu")
		(net "PWRGD_PVTT_PG")
	)
	(segment
		(start 183.222138 -34.385758)
		(end 181.80558 -32.9692)
		(width 0.254)
		(layer "B.Cu")
		(net "PWRGD_PVTT_PG")
	)
	(segment
		(start 172.71365 -54.3306)
		(end 180.6829 -46.36135)
		(width 0.254)
		(layer "B.Cu")
		(net "PWRGD_PVTT_PG")
	)
	(segment
		(start 11.8872 -69.723)
		(end 12.7127 -70.5485)
		(width 0.254)
		(layer "B.Cu")
		(net "PWRGD_PVTT_PG")
	)
	(segment
		(start 181.589172 -32.9692)
		(end 180.2638 -31.643828)
		(width 0.254)
		(layer "B.Cu")
		(net "PWRGD_PVTT_PG")
	)
	(segment
		(start 180.6829 -44.1325)
		(end 182.6006 -42.2148)
		(width 0.254)
		(layer "B.Cu")
		(net "PWRGD_PVTT_PG")
	)
	(segment
		(start 29.9466 -71.590154)
		(end 42.865294 -71.590154)
		(width 0.254)
		(layer "B.Cu")
		(net "PWRGD_PVTT_PG")
	)
	(segment
		(start 142.494 -56.5658)
		(end 143.4338 -55.626)
		(width 0.254)
		(layer "B.Cu")
		(net "PWRGD_PVTT_PG")
	)
	(segment
		(start 42.865294 -71.590154)
		(end 46.30039 -68.155058)
		(width 0.254)
		(layer "B.Cu")
		(net "PWRGD_PVTT_PG")
	)
	(segment
		(start 184.47766 -24.257)
		(end 184.6072 -24.257)
		(width 0.254)
		(layer "B.Cu")
		(net "PWRGD_PVTT_PG")
	)
	(segment
		(start 181.80558 -32.9692)
		(end 181.589172 -32.9692)
		(width 0.254)
		(layer "B.Cu")
		(net "PWRGD_PVTT_PG")
	)
	(segment
		(start 180.2638 -31.643828)
		(end 180.2638 -28.47086)
		(width 0.254)
		(layer "B.Cu")
		(net "PWRGD_PVTT_PG")
	)
	(segment
		(start 46.30039 -68.155058)
		(end 55.836058 -68.155058)
		(width 0.254)
		(layer "B.Cu")
		(net "PWRGD_PVTT_PG")
	)
	(segment
		(start 143.4338 -55.626)
		(end 154.427682 -55.626)
		(width 0.254)
		(layer "B.Cu")
		(net "PWRGD_PVTT_PG")
	)
	(segment
		(start 12.7127 -70.5485)
		(end 28.90266 -70.5485)
		(width 0.254)
		(layer "B.Cu")
		(net "PWRGD_PVTT_PG")
	)
	(segment
		(start 183.222138 -41.593262)
		(end 183.222138 -34.385758)
		(width 0.254)
		(layer "B.Cu")
		(net "PWRGD_PVTT_PG")
	)
	(segment
		(start 55.836058 -68.155058)
		(end 57.658 -69.977)
		(width 0.254)
		(layer "B.Cu")
		(net "PWRGD_PVTT_PG")
	)
	(segment
		(start 29.588714 -71.234554)
		(end 29.9466 -71.590154)
		(width 0.254)
		(layer "B.Cu")
		(net "PWRGD_PVTT_PG")
	)
	(segment
		(start 154.427682 -55.626)
		(end 155.723082 -54.3306)
		(width 0.254)
		(layer "B.Cu")
		(net "PWRGD_PVTT_PG")
	)
	(segment
		(start 182.6006 -42.2148)
		(end 183.222138 -41.593262)
		(width 0.254)
		(layer "B.Cu")
		(net "PWRGD_PVTT_PG")
	)
	(segment
		(start 180.2638 -28.47086)
		(end 184.47766 -24.257)
		(width 0.254)
		(layer "B.Cu")
		(net "PWRGD_PVTT_PG")
	)
	(segment
		(start 180.6829 -46.36135)
		(end 180.6829 -44.1325)
		(width 0.254)
		(layer "B.Cu")
		(net "PWRGD_PVTT_PG")
	)
	(segment
		(start 28.90266 -70.5485)
		(end 29.588714 -71.234554)
		(width 0.254)
		(layer "B.Cu")
		(net "PWRGD_PVTT_PG")
	)
	(segment
		(start 155.723082 -54.3306)
		(end 172.71365 -54.3306)
		(width 0.254)
		(layer "B.Cu")
		(net "PWRGD_PVTT_PG")
	)
	(segment
		(start 11.8872 -69.723)
		(end 11.8872 -59.8932)
		(width 0.254)
		(layer "In4.Cu")
		(net "PWRGD_PVTT_PG")
	)
	(segment
		(start 11.8872 -59.8932)
		(end 14.224 -57.5564)
		(width 0.254)
		(layer "In4.Cu")
		(net "PWRGD_PVTT_PG")
	)
	(segment
		(start 14.224 -57.5564)
		(end 14.6304 -57.5564)
		(width 0.254)
		(layer "In4.Cu")
		(net "PWRGD_PVTT_PG")
	)
	(segment
		(start 186.609228 -41.8846)
		(end 191.262 -46.537372)
		(width 0.254)
		(layer "In7.Cu")
		(net "PWRGD_PVTT_PG")
	)
	(segment
		(start 60.579 -72.898)
		(end 57.658 -69.977)
		(width 0.254)
		(layer "In7.Cu")
		(net "PWRGD_PVTT_PG")
	)
	(segment
		(start 182.537608 -41.8846)
		(end 186.609228 -41.8846)
		(width 0.254)
		(layer "In7.Cu")
		(net "PWRGD_PVTT_PG")
	)
	(segment
		(start 191.262 -58.801)
		(end 194.7672 -62.3062)
		(width 0.254)
		(layer "In7.Cu")
		(net "PWRGD_PVTT_PG")
	)
	(segment
		(start 190.487046 -72.910954)
		(end 80.5688 -72.910954)
		(width 0.254)
		(layer "In7.Cu")
		(net "PWRGD_PVTT_PG")
	)
	(segment
		(start 179.6796 -29.13253)
		(end 179.6796 -39.026592)
		(width 0.254)
		(layer "In7.Cu")
		(net "PWRGD_PVTT_PG")
	)
	(segment
		(start 184.6072 -24.257)
		(end 184.6072 -24.2824)
		(width 0.254)
		(layer "In7.Cu")
		(net "PWRGD_PVTT_PG")
	)
	(segment
		(start 71.6788 -72.898)
		(end 60.579 -72.898)
		(width 0.254)
		(layer "In7.Cu")
		(net "PWRGD_PVTT_PG")
	)
	(segment
		(start 184.4294 -24.4602)
		(end 184.35193 -24.4602)
		(width 0.254)
		(layer "In7.Cu")
		(net "PWRGD_PVTT_PG")
	)
	(segment
		(start 184.6072 -24.2824)
		(end 184.4294 -24.4602)
		(width 0.254)
		(layer "In7.Cu")
		(net "PWRGD_PVTT_PG")
	)
	(segment
		(start 194.7672 -62.3062)
		(end 194.7672 -68.6308)
		(width 0.254)
		(layer "In7.Cu")
		(net "PWRGD_PVTT_PG")
	)
	(segment
		(start 184.35193 -24.4602)
		(end 179.6796 -29.13253)
		(width 0.254)
		(layer "In7.Cu")
		(net "PWRGD_PVTT_PG")
	)
	(segment
		(start 194.7672 -68.6308)
		(end 190.487046 -72.910954)
		(width 0.254)
		(layer "In7.Cu")
		(net "PWRGD_PVTT_PG")
	)
	(segment
		(start 77.314044 -69.656198)
		(end 74.920602 -69.656198)
		(width 0.254)
		(layer "In7.Cu")
		(net "PWRGD_PVTT_PG")
	)
	(segment
		(start 74.920602 -69.656198)
		(end 71.6788 -72.898)
		(width 0.254)
		(layer "In7.Cu")
		(net "PWRGD_PVTT_PG")
	)
	(segment
		(start 179.6796 -39.026592)
		(end 182.537608 -41.8846)
		(width 0.254)
		(layer "In7.Cu")
		(net "PWRGD_PVTT_PG")
	)
	(segment
		(start 191.262 -46.537372)
		(end 191.262 -58.801)
		(width 0.254)
		(layer "In7.Cu")
		(net "PWRGD_PVTT_PG")
	)
	(segment
		(start 80.5688 -72.910954)
		(end 77.314044 -69.656198)
		(width 0.254)
		(layer "In7.Cu")
		(net "PWRGD_PVTT_PG")
	)
	(segment
		(start 100.4824 -48.3362)
		(end 100.457 -48.3108)
		(width 0.1016)
		(layer "F.Cu")
		(net "M_A_CS_N0")
	)
	(segment
		(start 100.343208 -48.3108)
		(end 100.053648 -48.021494)
		(width 0.1016)
		(layer "F.Cu")
		(net "M_A_CS_N0")
	)
	(segment
		(start 100.457 -48.3108)
		(end 100.343208 -48.3108)
		(width 0.1016)
		(layer "F.Cu")
		(net "M_A_CS_N0")
	)
	(via
		(at 100.4824 -48.3362)
		(size 0.4318)
		(drill 0.2032)
		(layers "F.Cu" "B.Cu")
		(net "M_A_CS_N0")
	)
	(via
		(at 150.200868 -64.060324)
		(size 0.4318)
		(drill 0.2032)
		(layers "F.Cu" "B.Cu")
		(net "M_A_CS_N0")
	)
	(segment
		(start 149.95017 -63.809626)
		(end 150.200868 -64.060324)
		(width 0.1778)
		(layer "B.Cu")
		(net "M_A_CS_N0")
	)
	(segment
		(start 149.95017 -62.599824)
		(end 149.95017 -63.809626)
		(width 0.1778)
		(layer "B.Cu")
		(net "M_A_CS_N0")
	)
	(segment
		(start 150.200868 -63.527178)
		(end 150.200868 -64.060324)
		(width 0.1524)
		(layer "In7.Cu")
		(net "M_A_CS_N0")
	)
	(segment
		(start 141.299438 -58.5978)
		(end 141.451838 -58.7502)
		(width 0.1524)
		(layer "In7.Cu")
		(net "M_A_CS_N0")
	)
	(segment
		(start 100.4824 -48.3362)
		(end 100.4824 -48.3616)
		(width 0.1016)
		(layer "In7.Cu")
		(net "M_A_CS_N0")
	)
	(segment
		(start 125.782324 -57.3278)
		(end 125.934724 -57.1754)
		(width 0.1524)
		(layer "In7.Cu")
		(net "M_A_CS_N0")
	)
	(segment
		(start 138.862562 -56.654954)
		(end 139.077954 -56.654954)
		(width 0.1524)
		(layer "In7.Cu")
		(net "M_A_CS_N0")
	)
	(segment
		(start 130.811524 -57.1754)
		(end 130.811524 -56.6166)
		(width 0.1524)
		(layer "In7.Cu")
		(net "M_A_CS_N0")
	)
	(segment
		(start 127.763524 -56.6166)
		(end 127.763524 -57.1754)
		(width 0.1524)
		(layer "In7.Cu")
		(net "M_A_CS_N0")
	)
	(segment
		(start 125.325124 -57.1754)
		(end 125.477524 -57.3278)
		(width 0.1524)
		(layer "In7.Cu")
		(net "M_A_CS_N0")
	)
	(segment
		(start 128.982724 -56.6166)
		(end 128.982724 -57.1754)
		(width 0.1524)
		(layer "In7.Cu")
		(net "M_A_CS_N0")
	)
	(segment
		(start 138.183112 -57.334658)
		(end 138.862562 -56.654954)
		(width 0.1524)
		(layer "In7.Cu")
		(net "M_A_CS_N0")
	)
	(segment
		(start 133.2484 -56.9214)
		(end 133.7056 -56.4642)
		(width 0.1524)
		(layer "In7.Cu")
		(net "M_A_CS_N0")
	)
	(segment
		(start 127.306324 -56.4642)
		(end 127.611124 -56.4642)
		(width 0.1524)
		(layer "In7.Cu")
		(net "M_A_CS_N0")
	)
	(segment
		(start 132.6134 -56.4642)
		(end 133.0706 -56.9214)
		(width 0.1524)
		(layer "In7.Cu")
		(net "M_A_CS_N0")
	)
	(segment
		(start 127.611124 -56.4642)
		(end 127.763524 -56.6166)
		(width 0.1524)
		(layer "In7.Cu")
		(net "M_A_CS_N0")
	)
	(segment
		(start 103.21925 -53.54955)
		(end 104.2162 -54.5465)
		(width 0.1524)
		(layer "In7.Cu")
		(net "M_A_CS_N0")
	)
	(segment
		(start 132.030724 -56.6166)
		(end 132.183124 -56.4642)
		(width 0.1524)
		(layer "In7.Cu")
		(net "M_A_CS_N0")
	)
	(segment
		(start 131.878324 -57.3278)
		(end 132.030724 -57.1754)
		(width 0.1524)
		(layer "In7.Cu")
		(net "M_A_CS_N0")
	)
	(segment
		(start 139.045696 -58.197242)
		(end 139.725146 -57.517538)
		(width 0.1524)
		(layer "In7.Cu")
		(net "M_A_CS_N0")
	)
	(segment
		(start 139.725146 -57.517538)
		(end 139.940538 -57.517538)
		(width 0.1524)
		(layer "In7.Cu")
		(net "M_A_CS_N0")
	)
	(segment
		(start 126.544324 -56.6166)
		(end 126.544324 -57.1754)
		(width 0.1524)
		(layer "In7.Cu")
		(net "M_A_CS_N0")
	)
	(segment
		(start 128.373124 -57.1754)
		(end 128.373124 -56.6166)
		(width 0.1524)
		(layer "In7.Cu")
		(net "M_A_CS_N0")
	)
	(segment
		(start 129.135124 -57.3278)
		(end 129.439924 -57.3278)
		(width 0.1524)
		(layer "In7.Cu")
		(net "M_A_CS_N0")
	)
	(segment
		(start 126.391924 -56.4642)
		(end 126.544324 -56.6166)
		(width 0.1524)
		(layer "In7.Cu")
		(net "M_A_CS_N0")
	)
	(segment
		(start 140.994638 -58.5978)
		(end 141.299438 -58.5978)
		(width 0.1524)
		(layer "In7.Cu")
		(net "M_A_CS_N0")
	)
	(segment
		(start 131.268724 -56.4642)
		(end 131.421124 -56.6166)
		(width 0.1524)
		(layer "In7.Cu")
		(net "M_A_CS_N0")
	)
	(segment
		(start 125.477524 -57.3278)
		(end 125.782324 -57.3278)
		(width 0.1524)
		(layer "In7.Cu")
		(net "M_A_CS_N0")
	)
	(segment
		(start 141.451838 -59.436)
		(end 141.604238 -59.5884)
		(width 0.1524)
		(layer "In7.Cu")
		(net "M_A_CS_N0")
	)
	(segment
		(start 126.544324 -57.1754)
		(end 126.696724 -57.3278)
		(width 0.1524)
		(layer "In7.Cu")
		(net "M_A_CS_N0")
	)
	(segment
		(start 130.354324 -57.3278)
		(end 130.659124 -57.3278)
		(width 0.1524)
		(layer "In7.Cu")
		(net "M_A_CS_N0")
	)
	(segment
		(start 135.824214 -56.4388)
		(end 137.071862 -56.4388)
		(width 0.1524)
		(layer "In7.Cu")
		(net "M_A_CS_N0")
	)
	(segment
		(start 133.7056 -56.4642)
		(end 134.203186 -56.4642)
		(width 0.1524)
		(layer "In7.Cu")
		(net "M_A_CS_N0")
	)
	(segment
		(start 128.982724 -57.1754)
		(end 129.135124 -57.3278)
		(width 0.1524)
		(layer "In7.Cu")
		(net "M_A_CS_N0")
	)
	(segment
		(start 139.476988 -58.843926)
		(end 139.942062 -59.309)
		(width 0.1524)
		(layer "In7.Cu")
		(net "M_A_CS_N0")
	)
	(segment
		(start 132.030724 -57.1754)
		(end 132.030724 -56.6166)
		(width 0.1524)
		(layer "In7.Cu")
		(net "M_A_CS_N0")
	)
	(segment
		(start 104.2162 -54.5465)
		(end 104.2162 -57.3532)
		(width 0.1524)
		(layer "In7.Cu")
		(net "M_A_CS_N0")
	)
	(segment
		(start 139.077954 -56.654954)
		(end 139.293854 -56.870854)
		(width 0.1524)
		(layer "In7.Cu")
		(net "M_A_CS_N0")
	)
	(segment
		(start 129.592324 -57.1754)
		(end 129.592324 -56.6166)
		(width 0.1524)
		(layer "In7.Cu")
		(net "M_A_CS_N0")
	)
	(segment
		(start 139.942062 -59.309)
		(end 140.689838 -59.309)
		(width 0.1524)
		(layer "In7.Cu")
		(net "M_A_CS_N0")
	)
	(segment
		(start 140.842238 -59.1566)
		(end 140.842238 -58.7502)
		(width 0.1524)
		(layer "In7.Cu")
		(net "M_A_CS_N0")
	)
	(segment
		(start 126.087124 -56.4642)
		(end 126.391924 -56.4642)
		(width 0.1524)
		(layer "In7.Cu")
		(net "M_A_CS_N0")
	)
	(segment
		(start 130.201924 -56.6166)
		(end 130.201924 -57.1754)
		(width 0.1524)
		(layer "In7.Cu")
		(net "M_A_CS_N0")
	)
	(segment
		(start 140.842238 -58.7502)
		(end 140.994638 -58.5978)
		(width 0.1524)
		(layer "In7.Cu")
		(net "M_A_CS_N0")
	)
	(segment
		(start 125.934724 -57.1754)
		(end 125.934724 -56.6166)
		(width 0.1524)
		(layer "In7.Cu")
		(net "M_A_CS_N0")
	)
	(segment
		(start 101.1428 -49.415446)
		(end 101.1428 -51.4731)
		(width 0.1016)
		(layer "In7.Cu")
		(net "M_A_CS_N0")
	)
	(segment
		(start 146.26209 -59.5884)
		(end 150.200868 -63.527178)
		(width 0.1524)
		(layer "In7.Cu")
		(net "M_A_CS_N0")
	)
	(segment
		(start 104.2162 -57.3532)
		(end 104.4702 -57.6072)
		(width 0.1524)
		(layer "In7.Cu")
		(net "M_A_CS_N0")
	)
	(segment
		(start 130.811524 -56.6166)
		(end 130.963924 -56.4642)
		(width 0.1524)
		(layer "In7.Cu")
		(net "M_A_CS_N0")
	)
	(segment
		(start 128.830324 -56.4642)
		(end 128.982724 -56.6166)
		(width 0.1524)
		(layer "In7.Cu")
		(net "M_A_CS_N0")
	)
	(segment
		(start 139.476988 -58.628534)
		(end 139.476988 -58.843926)
		(width 0.1524)
		(layer "In7.Cu")
		(net "M_A_CS_N0")
	)
	(segment
		(start 127.915924 -57.3278)
		(end 128.220724 -57.3278)
		(width 0.1524)
		(layer "In7.Cu")
		(net "M_A_CS_N0")
	)
	(segment
		(start 125.172724 -56.4642)
		(end 125.325124 -56.6166)
		(width 0.1524)
		(layer "In7.Cu")
		(net "M_A_CS_N0")
	)
	(segment
		(start 100.5332 -48.4124)
		(end 100.5332 -48.805846)
		(width 0.1016)
		(layer "In7.Cu")
		(net "M_A_CS_N0")
	)
	(segment
		(start 132.183124 -56.4642)
		(end 132.6134 -56.4642)
		(width 0.1524)
		(layer "In7.Cu")
		(net "M_A_CS_N0")
	)
	(segment
		(start 131.421124 -57.1754)
		(end 131.573524 -57.3278)
		(width 0.1524)
		(layer "In7.Cu")
		(net "M_A_CS_N0")
	)
	(segment
		(start 100.5332 -48.805846)
		(end 101.1428 -49.415446)
		(width 0.1016)
		(layer "In7.Cu")
		(net "M_A_CS_N0")
	)
	(segment
		(start 104.4702 -57.6072)
		(end 107.919774 -57.6072)
		(width 0.1524)
		(layer "In7.Cu")
		(net "M_A_CS_N0")
	)
	(segment
		(start 140.156438 -57.94883)
		(end 139.476988 -58.628534)
		(width 0.1524)
		(layer "In7.Cu")
		(net "M_A_CS_N0")
	)
	(segment
		(start 138.614404 -57.76595)
		(end 138.614404 -57.981342)
		(width 0.1524)
		(layer "In7.Cu")
		(net "M_A_CS_N0")
	)
	(segment
		(start 130.201924 -57.1754)
		(end 130.354324 -57.3278)
		(width 0.1524)
		(layer "In7.Cu")
		(net "M_A_CS_N0")
	)
	(segment
		(start 134.203186 -56.4642)
		(end 134.558786 -56.8198)
		(width 0.1524)
		(layer "In7.Cu")
		(net "M_A_CS_N0")
	)
	(segment
		(start 129.592324 -56.6166)
		(end 129.744724 -56.4642)
		(width 0.1524)
		(layer "In7.Cu")
		(net "M_A_CS_N0")
	)
	(segment
		(start 130.049524 -56.4642)
		(end 130.201924 -56.6166)
		(width 0.1524)
		(layer "In7.Cu")
		(net "M_A_CS_N0")
	)
	(segment
		(start 138.830304 -58.197242)
		(end 139.045696 -58.197242)
		(width 0.1524)
		(layer "In7.Cu")
		(net "M_A_CS_N0")
	)
	(segment
		(start 140.689838 -59.309)
		(end 140.842238 -59.1566)
		(width 0.1524)
		(layer "In7.Cu")
		(net "M_A_CS_N0")
	)
	(segment
		(start 120.926352 -56.4642)
		(end 125.172724 -56.4642)
		(width 0.1524)
		(layer "In7.Cu")
		(net "M_A_CS_N0")
	)
	(segment
		(start 137.071862 -56.4388)
		(end 137.96772 -57.334658)
		(width 0.1524)
		(layer "In7.Cu")
		(net "M_A_CS_N0")
	)
	(segment
		(start 131.573524 -57.3278)
		(end 131.878324 -57.3278)
		(width 0.1524)
		(layer "In7.Cu")
		(net "M_A_CS_N0")
	)
	(segment
		(start 141.604238 -59.5884)
		(end 146.26209 -59.5884)
		(width 0.1524)
		(layer "In7.Cu")
		(net "M_A_CS_N0")
	)
	(segment
		(start 134.558786 -56.8198)
		(end 135.443214 -56.8198)
		(width 0.1524)
		(layer "In7.Cu")
		(net "M_A_CS_N0")
	)
	(segment
		(start 128.525524 -56.4642)
		(end 128.830324 -56.4642)
		(width 0.1524)
		(layer "In7.Cu")
		(net "M_A_CS_N0")
	)
	(segment
		(start 137.96772 -57.334658)
		(end 138.183112 -57.334658)
		(width 0.1524)
		(layer "In7.Cu")
		(net "M_A_CS_N0")
	)
	(segment
		(start 128.373124 -56.6166)
		(end 128.525524 -56.4642)
		(width 0.1524)
		(layer "In7.Cu")
		(net "M_A_CS_N0")
	)
	(segment
		(start 107.919774 -57.6072)
		(end 107.951524 -57.57545)
		(width 0.1524)
		(layer "In7.Cu")
		(net "M_A_CS_N0")
	)
	(segment
		(start 130.659124 -57.3278)
		(end 130.811524 -57.1754)
		(width 0.1524)
		(layer "In7.Cu")
		(net "M_A_CS_N0")
	)
	(segment
		(start 125.934724 -56.6166)
		(end 126.087124 -56.4642)
		(width 0.1524)
		(layer "In7.Cu")
		(net "M_A_CS_N0")
	)
	(segment
		(start 141.451838 -58.7502)
		(end 141.451838 -59.436)
		(width 0.1524)
		(layer "In7.Cu")
		(net "M_A_CS_N0")
	)
	(segment
		(start 127.153924 -56.6166)
		(end 127.306324 -56.4642)
		(width 0.1524)
		(layer "In7.Cu")
		(net "M_A_CS_N0")
	)
	(segment
		(start 127.153924 -57.1754)
		(end 127.153924 -56.6166)
		(width 0.1524)
		(layer "In7.Cu")
		(net "M_A_CS_N0")
	)
	(segment
		(start 101.1428 -51.4731)
		(end 103.21925 -53.54955)
		(width 0.1016)
		(layer "In7.Cu")
		(net "M_A_CS_N0")
	)
	(segment
		(start 127.763524 -57.1754)
		(end 127.915924 -57.3278)
		(width 0.1524)
		(layer "In7.Cu")
		(net "M_A_CS_N0")
	)
	(segment
		(start 135.443214 -56.8198)
		(end 135.824214 -56.4388)
		(width 0.1524)
		(layer "In7.Cu")
		(net "M_A_CS_N0")
	)
	(segment
		(start 140.156438 -57.733438)
		(end 140.156438 -57.94883)
		(width 0.1524)
		(layer "In7.Cu")
		(net "M_A_CS_N0")
	)
	(segment
		(start 128.220724 -57.3278)
		(end 128.373124 -57.1754)
		(width 0.1524)
		(layer "In7.Cu")
		(net "M_A_CS_N0")
	)
	(segment
		(start 130.963924 -56.4642)
		(end 131.268724 -56.4642)
		(width 0.1524)
		(layer "In7.Cu")
		(net "M_A_CS_N0")
	)
	(segment
		(start 100.4824 -48.3616)
		(end 100.5332 -48.4124)
		(width 0.1016)
		(layer "In7.Cu")
		(net "M_A_CS_N0")
	)
	(segment
		(start 139.293854 -57.086246)
		(end 138.614404 -57.76595)
		(width 0.1524)
		(layer "In7.Cu")
		(net "M_A_CS_N0")
	)
	(segment
		(start 107.951524 -57.57545)
		(end 119.815102 -57.57545)
		(width 0.1524)
		(layer "In7.Cu")
		(net "M_A_CS_N0")
	)
	(segment
		(start 139.940538 -57.517538)
		(end 140.156438 -57.733438)
		(width 0.1524)
		(layer "In7.Cu")
		(net "M_A_CS_N0")
	)
	(segment
		(start 129.744724 -56.4642)
		(end 130.049524 -56.4642)
		(width 0.1524)
		(layer "In7.Cu")
		(net "M_A_CS_N0")
	)
	(segment
		(start 125.325124 -56.6166)
		(end 125.325124 -57.1754)
		(width 0.1524)
		(layer "In7.Cu")
		(net "M_A_CS_N0")
	)
	(segment
		(start 139.293854 -56.870854)
		(end 139.293854 -57.086246)
		(width 0.1524)
		(layer "In7.Cu")
		(net "M_A_CS_N0")
	)
	(segment
		(start 131.421124 -56.6166)
		(end 131.421124 -57.1754)
		(width 0.1524)
		(layer "In7.Cu")
		(net "M_A_CS_N0")
	)
	(segment
		(start 119.815102 -57.57545)
		(end 120.926352 -56.4642)
		(width 0.1524)
		(layer "In7.Cu")
		(net "M_A_CS_N0")
	)
	(segment
		(start 133.0706 -56.9214)
		(end 133.2484 -56.9214)
		(width 0.1524)
		(layer "In7.Cu")
		(net "M_A_CS_N0")
	)
	(segment
		(start 129.439924 -57.3278)
		(end 129.592324 -57.1754)
		(width 0.1524)
		(layer "In7.Cu")
		(net "M_A_CS_N0")
	)
	(segment
		(start 127.001524 -57.3278)
		(end 127.153924 -57.1754)
		(width 0.1524)
		(layer "In7.Cu")
		(net "M_A_CS_N0")
	)
	(segment
		(start 138.614404 -57.981342)
		(end 138.830304 -58.197242)
		(width 0.1524)
		(layer "In7.Cu")
		(net "M_A_CS_N0")
	)
	(segment
		(start 126.696724 -57.3278)
		(end 127.001524 -57.3278)
		(width 0.1524)
		(layer "In7.Cu")
		(net "M_A_CS_N0")
	)
	(segment
		(start 185.949844 -1.68402)
		(end 185.949844 -2.423414)
		(width 0.1778)
		(layer "F.Cu")
		(net "M_B_DQ61")
	)
	(segment
		(start 185.52414 -3.484118)
		(end 185.716926 -3.676904)
		(width 0.1778)
		(layer "F.Cu")
		(net "M_B_DQ61")
	)
	(segment
		(start 185.949844 -2.423414)
		(end 185.52414 -2.849118)
		(width 0.1778)
		(layer "F.Cu")
		(net "M_B_DQ61")
	)
	(segment
		(start 185.52414 -2.849118)
		(end 185.52414 -3.484118)
		(width 0.1778)
		(layer "F.Cu")
		(net "M_B_DQ61")
	)
	(segment
		(start 185.716926 -3.676904)
		(end 185.716926 -3.704336)
		(width 0.1778)
		(layer "F.Cu")
		(net "M_B_DQ61")
	)
	(segment
		(start 108.6104 -36.535614)
		(end 108.499148 -36.535614)
		(width 0.1016)
		(layer "F.Cu")
		(net "M_B_DQ61")
	)
	(segment
		(start 108.499148 -36.535614)
		(end 108.052108 -36.982654)
		(width 0.1016)
		(layer "F.Cu")
		(net "M_B_DQ61")
	)
	(via
		(at 108.6104 -36.535614)
		(size 0.4318)
		(drill 0.2032)
		(layers "F.Cu" "B.Cu")
		(net "M_B_DQ61")
	)
	(via
		(at 185.716926 -3.704336)
		(size 0.4318)
		(drill 0.2032)
		(layers "F.Cu" "B.Cu")
		(net "M_B_DQ61")
	)
	(segment
		(start 185.049922 -2.79019)
		(end 185.4454 -3.185668)
		(width 0.1778)
		(layer "B.Cu")
		(net "M_B_DQ61")
	)
	(segment
		(start 185.4454 -3.185668)
		(end 185.4454 -3.43281)
		(width 0.1778)
		(layer "B.Cu")
		(net "M_B_DQ61")
	)
	(segment
		(start 185.049922 -1.690624)
		(end 185.049922 -2.79019)
		(width 0.1778)
		(layer "B.Cu")
		(net "M_B_DQ61")
	)
	(segment
		(start 185.4454 -3.43281)
		(end 185.716926 -3.704336)
		(width 0.1778)
		(layer "B.Cu")
		(net "M_B_DQ61")
	)
	(segment
		(start 141.26083 -32.7152)
		(end 141.26083 -33.139634)
		(width 0.1524)
		(layer "In2.Cu")
		(net "M_B_DQ61")
	)
	(segment
		(start 144.919446 -33.0708)
		(end 145.391378 -33.0708)
		(width 0.1524)
		(layer "In2.Cu")
		(net "M_B_DQ61")
	)
	(segment
		(start 131.482338 -34.2392)
		(end 132.066538 -34.2392)
		(width 0.1524)
		(layer "In2.Cu")
		(net "M_B_DQ61")
	)
	(segment
		(start 134.4422 -34.0614)
		(end 135.001 -34.0614)
		(width 0.1524)
		(layer "In2.Cu")
		(net "M_B_DQ61")
	)
	(segment
		(start 108.6358 -34.8742)
		(end 108.3564 -35.1536)
		(width 0.1016)
		(layer "In2.Cu")
		(net "M_B_DQ61")
	)
	(segment
		(start 132.828538 -33.909)
		(end 132.980938 -34.0614)
		(width 0.1524)
		(layer "In2.Cu")
		(net "M_B_DQ61")
	)
	(segment
		(start 185.716926 -3.921252)
		(end 185.716926 -3.704336)
		(width 0.1524)
		(layer "In2.Cu")
		(net "M_B_DQ61")
	)
	(segment
		(start 132.980938 -34.0614)
		(end 133.4262 -34.0614)
		(width 0.1524)
		(layer "In2.Cu")
		(net "M_B_DQ61")
	)
	(segment
		(start 108.3564 -36.260278)
		(end 108.6104 -36.514278)
		(width 0.1016)
		(layer "In2.Cu")
		(net "M_B_DQ61")
	)
	(segment
		(start 110.6678 -34.925)
		(end 118.842282 -34.925)
		(width 0.1524)
		(layer "In2.Cu")
		(net "M_B_DQ61")
	)
	(segment
		(start 145.391378 -33.0708)
		(end 145.612612 -33.292034)
		(width 0.1524)
		(layer "In2.Cu")
		(net "M_B_DQ61")
	)
	(segment
		(start 132.218938 -34.0868)
		(end 132.218938 -33.444434)
		(width 0.1524)
		(layer "In2.Cu")
		(net "M_B_DQ61")
	)
	(segment
		(start 133.5786 -33.909)
		(end 133.5786 -33.444434)
		(width 0.1524)
		(layer "In2.Cu")
		(net "M_B_DQ61")
	)
	(segment
		(start 143.631412 -32.7152)
		(end 143.783812 -32.5628)
		(width 0.1524)
		(layer "In2.Cu")
		(net "M_B_DQ61")
	)
	(segment
		(start 135.3058 -33.292034)
		(end 140.49883 -33.292034)
		(width 0.1524)
		(layer "In2.Cu")
		(net "M_B_DQ61")
	)
	(segment
		(start 131.014724 -34.706814)
		(end 131.482338 -34.2392)
		(width 0.1524)
		(layer "In2.Cu")
		(net "M_B_DQ61")
	)
	(segment
		(start 110.6678 -34.925)
		(end 110.452408 -35.140392)
		(width 0.1016)
		(layer "In2.Cu")
		(net "M_B_DQ61")
	)
	(segment
		(start 135.1534 -33.909)
		(end 135.1534 -33.444434)
		(width 0.1524)
		(layer "In2.Cu")
		(net "M_B_DQ61")
	)
	(segment
		(start 143.783812 -32.5628)
		(end 144.088612 -32.5628)
		(width 0.1524)
		(layer "In2.Cu")
		(net "M_B_DQ61")
	)
	(segment
		(start 140.80363 -32.5628)
		(end 141.10843 -32.5628)
		(width 0.1524)
		(layer "In2.Cu")
		(net "M_B_DQ61")
	)
	(segment
		(start 132.066538 -34.2392)
		(end 132.218938 -34.0868)
		(width 0.1524)
		(layer "In2.Cu")
		(net "M_B_DQ61")
	)
	(segment
		(start 183.76392 -5.132578)
		(end 184.5056 -5.132578)
		(width 0.1524)
		(layer "In2.Cu")
		(net "M_B_DQ61")
	)
	(segment
		(start 134.2898 -33.444434)
		(end 134.2898 -33.909)
		(width 0.1524)
		(layer "In2.Cu")
		(net "M_B_DQ61")
	)
	(segment
		(start 141.41323 -33.292034)
		(end 143.479012 -33.292034)
		(width 0.1524)
		(layer "In2.Cu")
		(net "M_B_DQ61")
	)
	(segment
		(start 157.747208 -33.292034)
		(end 181.4576 -9.581642)
		(width 0.1524)
		(layer "In2.Cu")
		(net "M_B_DQ61")
	)
	(segment
		(start 133.731 -33.292034)
		(end 134.1374 -33.292034)
		(width 0.1524)
		(layer "In2.Cu")
		(net "M_B_DQ61")
	)
	(segment
		(start 145.612612 -33.292034)
		(end 157.747208 -33.292034)
		(width 0.1524)
		(layer "In2.Cu")
		(net "M_B_DQ61")
	)
	(segment
		(start 143.631412 -33.139634)
		(end 143.631412 -32.7152)
		(width 0.1524)
		(layer "In2.Cu")
		(net "M_B_DQ61")
	)
	(segment
		(start 135.001 -34.0614)
		(end 135.1534 -33.909)
		(width 0.1524)
		(layer "In2.Cu")
		(net "M_B_DQ61")
	)
	(segment
		(start 132.828538 -33.444434)
		(end 132.828538 -33.909)
		(width 0.1524)
		(layer "In2.Cu")
		(net "M_B_DQ61")
	)
	(segment
		(start 135.1534 -33.444434)
		(end 135.3058 -33.292034)
		(width 0.1524)
		(layer "In2.Cu")
		(net "M_B_DQ61")
	)
	(segment
		(start 118.842282 -34.925)
		(end 119.060468 -34.706814)
		(width 0.1524)
		(layer "In2.Cu")
		(net "M_B_DQ61")
	)
	(segment
		(start 141.26083 -33.139634)
		(end 141.41323 -33.292034)
		(width 0.1524)
		(layer "In2.Cu")
		(net "M_B_DQ61")
	)
	(segment
		(start 143.479012 -33.292034)
		(end 143.631412 -33.139634)
		(width 0.1524)
		(layer "In2.Cu")
		(net "M_B_DQ61")
	)
	(segment
		(start 109.446822 -34.8742)
		(end 108.6358 -34.8742)
		(width 0.1016)
		(layer "In2.Cu")
		(net "M_B_DQ61")
	)
	(segment
		(start 134.2898 -33.909)
		(end 134.4422 -34.0614)
		(width 0.1524)
		(layer "In2.Cu")
		(net "M_B_DQ61")
	)
	(segment
		(start 108.6104 -36.514278)
		(end 108.6104 -36.535614)
		(width 0.1016)
		(layer "In2.Cu")
		(net "M_B_DQ61")
	)
	(segment
		(start 144.393412 -33.292034)
		(end 144.698212 -33.292034)
		(width 0.1524)
		(layer "In2.Cu")
		(net "M_B_DQ61")
	)
	(segment
		(start 109.713014 -35.140392)
		(end 109.446822 -34.8742)
		(width 0.1016)
		(layer "In2.Cu")
		(net "M_B_DQ61")
	)
	(segment
		(start 144.698212 -33.292034)
		(end 144.919446 -33.0708)
		(width 0.1524)
		(layer "In2.Cu")
		(net "M_B_DQ61")
	)
	(segment
		(start 132.676138 -33.292034)
		(end 132.828538 -33.444434)
		(width 0.1524)
		(layer "In2.Cu")
		(net "M_B_DQ61")
	)
	(segment
		(start 144.241012 -32.7152)
		(end 144.241012 -33.139634)
		(width 0.1524)
		(layer "In2.Cu")
		(net "M_B_DQ61")
	)
	(segment
		(start 133.4262 -34.0614)
		(end 133.5786 -33.909)
		(width 0.1524)
		(layer "In2.Cu")
		(net "M_B_DQ61")
	)
	(segment
		(start 144.241012 -33.139634)
		(end 144.393412 -33.292034)
		(width 0.1524)
		(layer "In2.Cu")
		(net "M_B_DQ61")
	)
	(segment
		(start 181.4576 -9.581642)
		(end 181.4576 -7.438898)
		(width 0.1524)
		(layer "In2.Cu")
		(net "M_B_DQ61")
	)
	(segment
		(start 133.5786 -33.444434)
		(end 133.731 -33.292034)
		(width 0.1524)
		(layer "In2.Cu")
		(net "M_B_DQ61")
	)
	(segment
		(start 141.10843 -32.5628)
		(end 141.26083 -32.7152)
		(width 0.1524)
		(layer "In2.Cu")
		(net "M_B_DQ61")
	)
	(segment
		(start 132.218938 -33.444434)
		(end 132.371338 -33.292034)
		(width 0.1524)
		(layer "In2.Cu")
		(net "M_B_DQ61")
	)
	(segment
		(start 108.3564 -35.1536)
		(end 108.3564 -36.260278)
		(width 0.1016)
		(layer "In2.Cu")
		(net "M_B_DQ61")
	)
	(segment
		(start 184.5056 -5.132578)
		(end 185.716926 -3.921252)
		(width 0.1524)
		(layer "In2.Cu")
		(net "M_B_DQ61")
	)
	(segment
		(start 140.49883 -33.292034)
		(end 140.65123 -33.139634)
		(width 0.1524)
		(layer "In2.Cu")
		(net "M_B_DQ61")
	)
	(segment
		(start 181.4576 -7.438898)
		(end 183.76392 -5.132578)
		(width 0.1524)
		(layer "In2.Cu")
		(net "M_B_DQ61")
	)
	(segment
		(start 140.65123 -32.7152)
		(end 140.80363 -32.5628)
		(width 0.1524)
		(layer "In2.Cu")
		(net "M_B_DQ61")
	)
	(segment
		(start 110.452408 -35.140392)
		(end 109.713014 -35.140392)
		(width 0.1016)
		(layer "In2.Cu")
		(net "M_B_DQ61")
	)
	(segment
		(start 140.65123 -33.139634)
		(end 140.65123 -32.7152)
		(width 0.1524)
		(layer "In2.Cu")
		(net "M_B_DQ61")
	)
	(segment
		(start 132.371338 -33.292034)
		(end 132.676138 -33.292034)
		(width 0.1524)
		(layer "In2.Cu")
		(net "M_B_DQ61")
	)
	(segment
		(start 119.060468 -34.706814)
		(end 131.014724 -34.706814)
		(width 0.1524)
		(layer "In2.Cu")
		(net "M_B_DQ61")
	)
	(segment
		(start 134.1374 -33.292034)
		(end 134.2898 -33.444434)
		(width 0.1524)
		(layer "In2.Cu")
		(net "M_B_DQ61")
	)
	(segment
		(start 144.088612 -32.5628)
		(end 144.241012 -32.7152)
		(width 0.1524)
		(layer "In2.Cu")
		(net "M_B_DQ61")
	)
	(segment
		(start 38.36035 -23.28545)
		(end 39.17569 -23.28545)
		(width 0.1397)
		(layer "B.Cu")
		(net "CLK_100M_CLKBUFF_NGFF_R_DP")
	)
	(segment
		(start 39.17569 -23.28545)
		(end 40.78224 -21.6789)
		(width 0.1397)
		(layer "B.Cu")
		(net "CLK_100M_CLKBUFF_NGFF_R_DP")
	)
	(segment
		(start 46.24324 -21.6789)
		(end 47.9552 -19.96694)
		(width 0.1397)
		(layer "B.Cu")
		(net "CLK_100M_CLKBUFF_NGFF_R_DP")
	)
	(segment
		(start 47.9552 -19.3548)
		(end 48.02251 -19.28749)
		(width 0.1397)
		(layer "B.Cu")
		(net "CLK_100M_CLKBUFF_NGFF_R_DP")
	)
	(segment
		(start 38.1508 -23.495)
		(end 38.36035 -23.28545)
		(width 0.1397)
		(layer "B.Cu")
		(net "CLK_100M_CLKBUFF_NGFF_R_DP")
	)
	(segment
		(start 40.78224 -21.6789)
		(end 46.24324 -21.6789)
		(width 0.1397)
		(layer "B.Cu")
		(net "CLK_100M_CLKBUFF_NGFF_R_DP")
	)
	(segment
		(start 47.9552 -19.96694)
		(end 47.9552 -19.3548)
		(width 0.1397)
		(layer "B.Cu")
		(net "CLK_100M_CLKBUFF_NGFF_R_DP")
	)
	(segment
		(start 48.02251 -19.28749)
		(end 48.02251 -18.6563)
		(width 0.1397)
		(layer "B.Cu")
		(net "CLK_100M_CLKBUFF_NGFF_R_DP")
	)
	(segment
		(start 138.86434 -58.417968)
		(end 139.1158 -58.669428)
		(width 0.508)
		(layer "F.Cu")
		(net "PV_VTT_DDR_VIN")
	)
	(segment
		(start 138.86434 -57.460388)
		(end 138.86434 -58.039)
		(width 0.3048)
		(layer "F.Cu")
		(net "PV_VTT_DDR_VIN")
	)
	(segment
		(start 140.17752 -59.93892)
		(end 140.17752 -58.669428)
		(width 0.508)
		(layer "F.Cu")
		(net "PV_VTT_DDR_VIN")
	)
	(segment
		(start 140.1826 -59.944)
		(end 140.17752 -59.93892)
		(width 0.508)
		(layer "F.Cu")
		(net "PV_VTT_DDR_VIN")
	)
	(segment
		(start 139.1158 -58.669428)
		(end 140.17752 -58.669428)
		(width 0.508)
		(layer "F.Cu")
		(net "PV_VTT_DDR_VIN")
	)
	(segment
		(start 138.86434 -58.039)
		(end 138.86434 -58.417968)
		(width 0.508)
		(layer "F.Cu")
		(net "PV_VTT_DDR_VIN")
	)
	(via
		(at 139.1158 -58.669428)
		(size 0.7112)
		(drill 0.3556)
		(layers "F.Cu" "B.Cu")
		(net "PV_VTT_DDR_VIN")
	)
	(segment
		(start 110.61573 -49.522634)
		(end 110.653068 -49.485296)
		(width 0.1778)
		(layer "F.Cu")
		(net "M_A_CKE1")
	)
	(segment
		(start 109.863128 -49.522634)
		(end 110.61573 -49.522634)
		(width 0.1778)
		(layer "F.Cu")
		(net "M_A_CKE1")
	)
	(via
		(at 161.300922 -64.034924)
		(size 0.4318)
		(drill 0.2032)
		(layers "F.Cu" "B.Cu")
		(net "M_A_CKE1")
	)
	(via
		(at 110.653068 -49.485296)
		(size 0.4318)
		(drill 0.2032)
		(layers "F.Cu" "B.Cu")
		(net "M_A_CKE1")
	)
	(segment
		(start 161.349944 -62.599824)
		(end 161.349944 -63.985902)
		(width 0.1778)
		(layer "B.Cu")
		(net "M_A_CKE1")
	)
	(segment
		(start 161.349944 -63.985902)
		(end 161.300922 -64.034924)
		(width 0.1778)
		(layer "B.Cu")
		(net "M_A_CKE1")
	)
	(segment
		(start 136.100058 -48.50765)
		(end 135.882634 -48.290226)
		(width 0.1524)
		(layer "In7.Cu")
		(net "M_A_CKE1")
	)
	(segment
		(start 160.7566 -60.402724)
		(end 161.1884 -60.402724)
		(width 0.1524)
		(layer "In7.Cu")
		(net "M_A_CKE1")
	)
	(segment
		(start 138.930634 -48.50765)
		(end 138.538458 -48.50765)
		(width 0.1524)
		(layer "In7.Cu")
		(net "M_A_CKE1")
	)
	(segment
		(start 155.666694 -52.783486)
		(end 155.666694 -52.568094)
		(width 0.1524)
		(layer "In7.Cu")
		(net "M_A_CKE1")
	)
	(segment
		(start 160.801304 -57.702704)
		(end 160.585912 -57.702704)
		(width 0.1524)
		(layer "In7.Cu")
		(net "M_A_CKE1")
	)
	(segment
		(start 120.85955 -48.35525)
		(end 120.70715 -48.50765)
		(width 0.1524)
		(layer "In7.Cu")
		(net "M_A_CKE1")
	)
	(segment
		(start 161.1884 -59.793124)
		(end 160.782 -59.793124)
		(width 0.1524)
		(layer "In7.Cu")
		(net "M_A_CKE1")
	)
	(segment
		(start 123.75515 -48.50765)
		(end 123.29795 -48.50765)
		(width 0.1524)
		(layer "In7.Cu")
		(net "M_A_CKE1")
	)
	(segment
		(start 157.602428 -54.71922)
		(end 157.50286 -54.818788)
		(width 0.1524)
		(layer "In7.Cu")
		(net "M_A_CKE1")
	)
	(segment
		(start 155.55214 -53.113686)
		(end 155.55214 -52.898294)
		(width 0.1524)
		(layer "In7.Cu")
		(net "M_A_CKE1")
	)
	(segment
		(start 161.300922 -58.202322)
		(end 160.801304 -57.702704)
		(width 0.1524)
		(layer "In7.Cu")
		(net "M_A_CKE1")
	)
	(segment
		(start 155.120594 -52.467002)
		(end 154.905456 -52.467002)
		(width 0.1524)
		(layer "In7.Cu")
		(net "M_A_CKE1")
	)
	(segment
		(start 155.235402 -52.352194)
		(end 155.120594 -52.467002)
		(width 0.1524)
		(layer "In7.Cu")
		(net "M_A_CKE1")
	)
	(segment
		(start 120.70715 -48.50765)
		(end 112.356646 -48.50765)
		(width 0.1524)
		(layer "In7.Cu")
		(net "M_A_CKE1")
	)
	(segment
		(start 121.46915 -47.9552)
		(end 121.01195 -47.9552)
		(width 0.1524)
		(layer "In7.Cu")
		(net "M_A_CKE1")
	)
	(segment
		(start 143.671036 -48.50765)
		(end 142.196058 -48.50765)
		(width 0.1524)
		(layer "In7.Cu")
		(net "M_A_CKE1")
	)
	(segment
		(start 158.150052 -55.681372)
		(end 157.934152 -55.465472)
		(width 0.1524)
		(layer "In7.Cu")
		(net "M_A_CKE1")
	)
	(segment
		(start 138.321034 -48.290226)
		(end 137.928858 -48.290226)
		(width 0.1524)
		(layer "In7.Cu")
		(net "M_A_CKE1")
	)
	(segment
		(start 123.14555 -48.35525)
		(end 123.14555 -48.1076)
		(width 0.1524)
		(layer "In7.Cu")
		(net "M_A_CKE1")
	)
	(segment
		(start 140.976858 -48.50765)
		(end 140.759434 -48.290226)
		(width 0.1524)
		(layer "In7.Cu")
		(net "M_A_CKE1")
	)
	(segment
		(start 161.300922 -62.445646)
		(end 161.0868 -62.231524)
		(width 0.1524)
		(layer "In7.Cu")
		(net "M_A_CKE1")
	)
	(segment
		(start 160.15462 -57.05602)
		(end 159.740854 -56.642254)
		(width 0.1524)
		(layer "In7.Cu")
		(net "M_A_CKE1")
	)
	(segment
		(start 136.492234 -48.50765)
		(end 136.100058 -48.50765)
		(width 0.1524)
		(layer "In7.Cu")
		(net "M_A_CKE1")
	)
	(segment
		(start 112.356646 -48.50765)
		(end 111.379 -49.485296)
		(width 0.1524)
		(layer "In7.Cu")
		(net "M_A_CKE1")
	)
	(segment
		(start 141.369034 -48.50765)
		(end 140.976858 -48.50765)
		(width 0.1524)
		(layer "In7.Cu")
		(net "M_A_CKE1")
	)
	(segment
		(start 154.905456 -52.467002)
		(end 154.689556 -52.251102)
		(width 0.1524)
		(layer "In7.Cu")
		(net "M_A_CKE1")
	)
	(segment
		(start 160.782 -59.183524)
		(end 161.148522 -59.183524)
		(width 0.1524)
		(layer "In7.Cu")
		(net "M_A_CKE1")
	)
	(segment
		(start 157.50286 -54.818788)
		(end 157.287468 -54.818788)
		(width 0.1524)
		(layer "In7.Cu")
		(net "M_A_CKE1")
	)
	(segment
		(start 161.300922 -64.034924)
		(end 161.300922 -62.445646)
		(width 0.1524)
		(layer "In7.Cu")
		(net "M_A_CKE1")
	)
	(segment
		(start 160.15462 -57.271412)
		(end 160.15462 -57.05602)
		(width 0.1524)
		(layer "In7.Cu")
		(net "M_A_CKE1")
	)
	(segment
		(start 140.367258 -48.290226)
		(end 140.149834 -48.50765)
		(width 0.1524)
		(layer "In7.Cu")
		(net "M_A_CKE1")
	)
	(segment
		(start 151.49322 -50.8762)
		(end 149.65807 -49.04105)
		(width 0.1524)
		(layer "In7.Cu")
		(net "M_A_CKE1")
	)
	(segment
		(start 161.3662 -61.164724)
		(end 161.2138 -61.012324)
		(width 0.1524)
		(layer "In7.Cu")
		(net "M_A_CKE1")
	)
	(segment
		(start 154.361896 -51.263296)
		(end 153.574496 -51.263296)
		(width 0.1524)
		(layer "In7.Cu")
		(net "M_A_CKE1")
	)
	(segment
		(start 158.680404 -55.581804)
		(end 158.465012 -55.581804)
		(width 0.1524)
		(layer "In7.Cu")
		(net "M_A_CKE1")
	)
	(segment
		(start 138.538458 -48.50765)
		(end 138.321034 -48.290226)
		(width 0.1524)
		(layer "In7.Cu")
		(net "M_A_CKE1")
	)
	(segment
		(start 158.852362 -56.45277)
		(end 159.09417 -56.210962)
		(width 0.1524)
		(layer "In7.Cu")
		(net "M_A_CKE1")
	)
	(segment
		(start 161.3408 -59.945524)
		(end 161.1884 -59.793124)
		(width 0.1524)
		(layer "In7.Cu")
		(net "M_A_CKE1")
	)
	(segment
		(start 154.80411 -51.70551)
		(end 154.361896 -51.263296)
		(width 0.1524)
		(layer "In7.Cu")
		(net "M_A_CKE1")
	)
	(segment
		(start 144.204436 -49.04105)
		(end 143.671036 -48.50765)
		(width 0.1524)
		(layer "In7.Cu")
		(net "M_A_CKE1")
	)
	(segment
		(start 135.882634 -48.290226)
		(end 135.490458 -48.290226)
		(width 0.1524)
		(layer "In7.Cu")
		(net "M_A_CKE1")
	)
	(segment
		(start 161.0868 -62.231524)
		(end 160.655 -62.231524)
		(width 0.1524)
		(layer "In7.Cu")
		(net "M_A_CKE1")
	)
	(segment
		(start 160.318704 -57.969912)
		(end 160.103312 -57.969912)
		(width 0.1524)
		(layer "In7.Cu")
		(net "M_A_CKE1")
	)
	(segment
		(start 124.66955 -48.1076)
		(end 124.51715 -47.9552)
		(width 0.1524)
		(layer "In7.Cu")
		(net "M_A_CKE1")
	)
	(segment
		(start 160.585912 -57.702704)
		(end 160.318704 -57.969912)
		(width 0.1524)
		(layer "In7.Cu")
		(net "M_A_CKE1")
	)
	(segment
		(start 139.540234 -48.290226)
		(end 139.148058 -48.290226)
		(width 0.1524)
		(layer "In7.Cu")
		(net "M_A_CKE1")
	)
	(segment
		(start 157.171136 -54.287928)
		(end 157.171136 -54.072536)
		(width 0.1524)
		(layer "In7.Cu")
		(net "M_A_CKE1")
	)
	(segment
		(start 159.09417 -55.99557)
		(end 158.680404 -55.581804)
		(width 0.1524)
		(layer "In7.Cu")
		(net "M_A_CKE1")
	)
	(segment
		(start 158.03372 -55.150512)
		(end 158.03372 -54.93512)
		(width 0.1524)
		(layer "In7.Cu")
		(net "M_A_CKE1")
	)
	(segment
		(start 134.053834 -48.50765)
		(end 126.226824 -48.50765)
		(width 0.1524)
		(layer "In7.Cu")
		(net "M_A_CKE1")
	)
	(segment
		(start 120.85955 -48.1076)
		(end 120.85955 -48.35525)
		(width 0.1524)
		(layer "In7.Cu")
		(net "M_A_CKE1")
	)
	(segment
		(start 123.14555 -48.1076)
		(end 122.99315 -47.9552)
		(width 0.1524)
		(layer "In7.Cu")
		(net "M_A_CKE1")
	)
	(segment
		(start 124.66955 -48.35525)
		(end 124.66955 -48.1076)
		(width 0.1524)
		(layer "In7.Cu")
		(net "M_A_CKE1")
	)
	(segment
		(start 124.51715 -47.9552)
		(end 124.05995 -47.9552)
		(width 0.1524)
		(layer "In7.Cu")
		(net "M_A_CKE1")
	)
	(segment
		(start 157.934152 -55.25008)
		(end 158.03372 -55.150512)
		(width 0.1524)
		(layer "In7.Cu")
		(net "M_A_CKE1")
	)
	(segment
		(start 160.655 -61.621924)
		(end 161.2138 -61.621924)
		(width 0.1524)
		(layer "In7.Cu")
		(net "M_A_CKE1")
	)
	(segment
		(start 122.38355 -48.1076)
		(end 122.38355 -48.35525)
		(width 0.1524)
		(layer "In7.Cu")
		(net "M_A_CKE1")
	)
	(segment
		(start 153.574496 -51.263296)
		(end 153.1874 -50.8762)
		(width 0.1524)
		(layer "In7.Cu")
		(net "M_A_CKE1")
	)
	(segment
		(start 160.103312 -57.969912)
		(end 159.887412 -57.754012)
		(width 0.1524)
		(layer "In7.Cu")
		(net "M_A_CKE1")
	)
	(segment
		(start 157.171136 -54.072536)
		(end 156.313378 -53.214778)
		(width 0.1524)
		(layer "In7.Cu")
		(net "M_A_CKE1")
	)
	(segment
		(start 158.852362 -56.668162)
		(end 158.852362 -56.45277)
		(width 0.1524)
		(layer "In7.Cu")
		(net "M_A_CKE1")
	)
	(segment
		(start 137.711434 -48.50765)
		(end 137.319258 -48.50765)
		(width 0.1524)
		(layer "In7.Cu")
		(net "M_A_CKE1")
	)
	(segment
		(start 135.490458 -48.290226)
		(end 135.273034 -48.50765)
		(width 0.1524)
		(layer "In7.Cu")
		(net "M_A_CKE1")
	)
	(segment
		(start 157.071568 -54.602888)
		(end 157.071568 -54.387496)
		(width 0.1524)
		(layer "In7.Cu")
		(net "M_A_CKE1")
	)
	(segment
		(start 156.097986 -53.214778)
		(end 155.983178 -53.329586)
		(width 0.1524)
		(layer "In7.Cu")
		(net "M_A_CKE1")
	)
	(segment
		(start 141.586458 -48.290226)
		(end 141.369034 -48.50765)
		(width 0.1524)
		(layer "In7.Cu")
		(net "M_A_CKE1")
	)
	(segment
		(start 159.887412 -57.754012)
		(end 159.887412 -57.53862)
		(width 0.1524)
		(layer "In7.Cu")
		(net "M_A_CKE1")
	)
	(segment
		(start 123.29795 -48.50765)
		(end 123.14555 -48.35525)
		(width 0.1524)
		(layer "In7.Cu")
		(net "M_A_CKE1")
	)
	(segment
		(start 149.65807 -49.04105)
		(end 144.204436 -49.04105)
		(width 0.1524)
		(layer "In7.Cu")
		(net "M_A_CKE1")
	)
	(segment
		(start 160.6296 -59.640724)
		(end 160.6296 -59.335924)
		(width 0.1524)
		(layer "In7.Cu")
		(net "M_A_CKE1")
	)
	(segment
		(start 122.99315 -47.9552)
		(end 122.53595 -47.9552)
		(width 0.1524)
		(layer "In7.Cu")
		(net "M_A_CKE1")
	)
	(segment
		(start 155.76804 -53.329586)
		(end 155.55214 -53.113686)
		(width 0.1524)
		(layer "In7.Cu")
		(net "M_A_CKE1")
	)
	(segment
		(start 154.689556 -52.03571)
		(end 154.80411 -51.920902)
		(width 0.1524)
		(layer "In7.Cu")
		(net "M_A_CKE1")
	)
	(segment
		(start 126.226824 -48.50765)
		(end 126.0094 -48.290226)
		(width 0.1524)
		(layer "In7.Cu")
		(net "M_A_CKE1")
	)
	(segment
		(start 161.3662 -61.469524)
		(end 161.3662 -61.164724)
		(width 0.1524)
		(layer "In7.Cu")
		(net "M_A_CKE1")
	)
	(segment
		(start 154.689556 -52.251102)
		(end 154.689556 -52.03571)
		(width 0.1524)
		(layer "In7.Cu")
		(net "M_A_CKE1")
	)
	(segment
		(start 160.6042 -60.555124)
		(end 160.7566 -60.402724)
		(width 0.1524)
		(layer "In7.Cu")
		(net "M_A_CKE1")
	)
	(segment
		(start 161.2138 -61.012324)
		(end 160.7566 -61.012324)
		(width 0.1524)
		(layer "In7.Cu")
		(net "M_A_CKE1")
	)
	(segment
		(start 142.196058 -48.50765)
		(end 141.978634 -48.290226)
		(width 0.1524)
		(layer "In7.Cu")
		(net "M_A_CKE1")
	)
	(segment
		(start 153.1874 -50.8762)
		(end 151.49322 -50.8762)
		(width 0.1524)
		(layer "In7.Cu")
		(net "M_A_CKE1")
	)
	(segment
		(start 159.068262 -56.884062)
		(end 158.852362 -56.668162)
		(width 0.1524)
		(layer "In7.Cu")
		(net "M_A_CKE1")
	)
	(segment
		(start 125.40615 -48.50765)
		(end 124.82195 -48.50765)
		(width 0.1524)
		(layer "In7.Cu")
		(net "M_A_CKE1")
	)
	(segment
		(start 122.53595 -47.9552)
		(end 122.38355 -48.1076)
		(width 0.1524)
		(layer "In7.Cu")
		(net "M_A_CKE1")
	)
	(segment
		(start 157.81782 -54.71922)
		(end 157.602428 -54.71922)
		(width 0.1524)
		(layer "In7.Cu")
		(net "M_A_CKE1")
	)
	(segment
		(start 155.55214 -52.898294)
		(end 155.666694 -52.783486)
		(width 0.1524)
		(layer "In7.Cu")
		(net "M_A_CKE1")
	)
	(segment
		(start 136.709658 -48.290226)
		(end 136.492234 -48.50765)
		(width 0.1524)
		(layer "In7.Cu")
		(net "M_A_CKE1")
	)
	(segment
		(start 159.09417 -56.210962)
		(end 159.09417 -55.99557)
		(width 0.1524)
		(layer "In7.Cu")
		(net "M_A_CKE1")
	)
	(segment
		(start 160.6296 -59.335924)
		(end 160.782 -59.183524)
		(width 0.1524)
		(layer "In7.Cu")
		(net "M_A_CKE1")
	)
	(segment
		(start 139.148058 -48.290226)
		(end 138.930634 -48.50765)
		(width 0.1524)
		(layer "In7.Cu")
		(net "M_A_CKE1")
	)
	(segment
		(start 134.271258 -48.290226)
		(end 134.053834 -48.50765)
		(width 0.1524)
		(layer "In7.Cu")
		(net "M_A_CKE1")
	)
	(segment
		(start 161.300922 -59.031124)
		(end 161.300922 -58.202322)
		(width 0.1524)
		(layer "In7.Cu")
		(net "M_A_CKE1")
	)
	(segment
		(start 161.3408 -60.250324)
		(end 161.3408 -59.945524)
		(width 0.1524)
		(layer "In7.Cu")
		(net "M_A_CKE1")
	)
	(segment
		(start 121.62155 -48.35525)
		(end 121.62155 -48.1076)
		(width 0.1524)
		(layer "In7.Cu")
		(net "M_A_CKE1")
	)
	(segment
		(start 134.663434 -48.290226)
		(end 134.271258 -48.290226)
		(width 0.1524)
		(layer "In7.Cu")
		(net "M_A_CKE1")
	)
	(segment
		(start 139.757658 -48.50765)
		(end 139.540234 -48.290226)
		(width 0.1524)
		(layer "In7.Cu")
		(net "M_A_CKE1")
	)
	(segment
		(start 160.6042 -60.859924)
		(end 160.6042 -60.555124)
		(width 0.1524)
		(layer "In7.Cu")
		(net "M_A_CKE1")
	)
	(segment
		(start 124.82195 -48.50765)
		(end 124.66955 -48.35525)
		(width 0.1524)
		(layer "In7.Cu")
		(net "M_A_CKE1")
	)
	(segment
		(start 137.101834 -48.290226)
		(end 136.709658 -48.290226)
		(width 0.1524)
		(layer "In7.Cu")
		(net "M_A_CKE1")
	)
	(segment
		(start 121.77395 -48.50765)
		(end 121.62155 -48.35525)
		(width 0.1524)
		(layer "In7.Cu")
		(net "M_A_CKE1")
	)
	(segment
		(start 155.983178 -53.329586)
		(end 155.76804 -53.329586)
		(width 0.1524)
		(layer "In7.Cu")
		(net "M_A_CKE1")
	)
	(segment
		(start 154.80411 -51.920902)
		(end 154.80411 -51.70551)
		(width 0.1524)
		(layer "In7.Cu")
		(net "M_A_CKE1")
	)
	(segment
		(start 140.759434 -48.290226)
		(end 140.367258 -48.290226)
		(width 0.1524)
		(layer "In7.Cu")
		(net "M_A_CKE1")
	)
	(segment
		(start 161.1884 -60.402724)
		(end 161.3408 -60.250324)
		(width 0.1524)
		(layer "In7.Cu")
		(net "M_A_CKE1")
	)
	(segment
		(start 157.287468 -54.818788)
		(end 157.071568 -54.602888)
		(width 0.1524)
		(layer "In7.Cu")
		(net "M_A_CKE1")
	)
	(segment
		(start 160.5026 -62.079124)
		(end 160.5026 -61.774324)
		(width 0.1524)
		(layer "In7.Cu")
		(net "M_A_CKE1")
	)
	(segment
		(start 160.782 -59.793124)
		(end 160.6296 -59.640724)
		(width 0.1524)
		(layer "In7.Cu")
		(net "M_A_CKE1")
	)
	(segment
		(start 124.05995 -47.9552)
		(end 123.90755 -48.1076)
		(width 0.1524)
		(layer "In7.Cu")
		(net "M_A_CKE1")
	)
	(segment
		(start 135.273034 -48.50765)
		(end 134.880858 -48.50765)
		(width 0.1524)
		(layer "In7.Cu")
		(net "M_A_CKE1")
	)
	(segment
		(start 161.2138 -61.621924)
		(end 161.3662 -61.469524)
		(width 0.1524)
		(layer "In7.Cu")
		(net "M_A_CKE1")
	)
	(segment
		(start 137.319258 -48.50765)
		(end 137.101834 -48.290226)
		(width 0.1524)
		(layer "In7.Cu")
		(net "M_A_CKE1")
	)
	(segment
		(start 140.149834 -48.50765)
		(end 139.757658 -48.50765)
		(width 0.1524)
		(layer "In7.Cu")
		(net "M_A_CKE1")
	)
	(segment
		(start 158.365444 -55.681372)
		(end 158.150052 -55.681372)
		(width 0.1524)
		(layer "In7.Cu")
		(net "M_A_CKE1")
	)
	(segment
		(start 123.90755 -48.35525)
		(end 123.75515 -48.50765)
		(width 0.1524)
		(layer "In7.Cu")
		(net "M_A_CKE1")
	)
	(segment
		(start 125.623574 -48.290226)
		(end 125.40615 -48.50765)
		(width 0.1524)
		(layer "In7.Cu")
		(net "M_A_CKE1")
	)
	(segment
		(start 159.283654 -56.884062)
		(end 159.068262 -56.884062)
		(width 0.1524)
		(layer "In7.Cu")
		(net "M_A_CKE1")
	)
	(segment
		(start 161.148522 -59.183524)
		(end 161.300922 -59.031124)
		(width 0.1524)
		(layer "In7.Cu")
		(net "M_A_CKE1")
	)
	(segment
		(start 160.7566 -61.012324)
		(end 160.6042 -60.859924)
		(width 0.1524)
		(layer "In7.Cu")
		(net "M_A_CKE1")
	)
	(segment
		(start 157.934152 -55.465472)
		(end 157.934152 -55.25008)
		(width 0.1524)
		(layer "In7.Cu")
		(net "M_A_CKE1")
	)
	(segment
		(start 158.465012 -55.581804)
		(end 158.365444 -55.681372)
		(width 0.1524)
		(layer "In7.Cu")
		(net "M_A_CKE1")
	)
	(segment
		(start 160.5026 -61.774324)
		(end 160.655 -61.621924)
		(width 0.1524)
		(layer "In7.Cu")
		(net "M_A_CKE1")
	)
	(segment
		(start 121.01195 -47.9552)
		(end 120.85955 -48.1076)
		(width 0.1524)
		(layer "In7.Cu")
		(net "M_A_CKE1")
	)
	(segment
		(start 159.740854 -56.642254)
		(end 159.525462 -56.642254)
		(width 0.1524)
		(layer "In7.Cu")
		(net "M_A_CKE1")
	)
	(segment
		(start 111.379 -49.485296)
		(end 110.653068 -49.485296)
		(width 0.1524)
		(layer "In7.Cu")
		(net "M_A_CKE1")
	)
	(segment
		(start 126.0094 -48.290226)
		(end 125.623574 -48.290226)
		(width 0.1524)
		(layer "In7.Cu")
		(net "M_A_CKE1")
	)
	(segment
		(start 122.38355 -48.35525)
		(end 122.23115 -48.50765)
		(width 0.1524)
		(layer "In7.Cu")
		(net "M_A_CKE1")
	)
	(segment
		(start 137.928858 -48.290226)
		(end 137.711434 -48.50765)
		(width 0.1524)
		(layer "In7.Cu")
		(net "M_A_CKE1")
	)
	(segment
		(start 122.23115 -48.50765)
		(end 121.77395 -48.50765)
		(width 0.1524)
		(layer "In7.Cu")
		(net "M_A_CKE1")
	)
	(segment
		(start 155.450794 -52.352194)
		(end 155.235402 -52.352194)
		(width 0.1524)
		(layer "In7.Cu")
		(net "M_A_CKE1")
	)
	(segment
		(start 134.880858 -48.50765)
		(end 134.663434 -48.290226)
		(width 0.1524)
		(layer "In7.Cu")
		(net "M_A_CKE1")
	)
	(segment
		(start 160.655 -62.231524)
		(end 160.5026 -62.079124)
		(width 0.1524)
		(layer "In7.Cu")
		(net "M_A_CKE1")
	)
	(segment
		(start 121.62155 -48.1076)
		(end 121.46915 -47.9552)
		(width 0.1524)
		(layer "In7.Cu")
		(net "M_A_CKE1")
	)
	(segment
		(start 157.071568 -54.387496)
		(end 157.171136 -54.287928)
		(width 0.1524)
		(layer "In7.Cu")
		(net "M_A_CKE1")
	)
	(segment
		(start 159.525462 -56.642254)
		(end 159.283654 -56.884062)
		(width 0.1524)
		(layer "In7.Cu")
		(net "M_A_CKE1")
	)
	(segment
		(start 159.887412 -57.53862)
		(end 160.15462 -57.271412)
		(width 0.1524)
		(layer "In7.Cu")
		(net "M_A_CKE1")
	)
	(segment
		(start 158.03372 -54.93512)
		(end 157.81782 -54.71922)
		(width 0.1524)
		(layer "In7.Cu")
		(net "M_A_CKE1")
	)
	(segment
		(start 156.313378 -53.214778)
		(end 156.097986 -53.214778)
		(width 0.1524)
		(layer "In7.Cu")
		(net "M_A_CKE1")
	)
	(segment
		(start 141.978634 -48.290226)
		(end 141.586458 -48.290226)
		(width 0.1524)
		(layer "In7.Cu")
		(net "M_A_CKE1")
	)
	(segment
		(start 155.666694 -52.568094)
		(end 155.450794 -52.352194)
		(width 0.1524)
		(layer "In7.Cu")
		(net "M_A_CKE1")
	)
	(segment
		(start 123.90755 -48.1076)
		(end 123.90755 -48.35525)
		(width 0.1524)
		(layer "In7.Cu")
		(net "M_A_CKE1")
	)
	(segment
		(start 103.9368 -26.146506)
		(end 104.237028 -26.446734)
		(width 0.1016)
		(layer "F.Cu")
		(net "M_B_ECC5")
	)
	(segment
		(start 151.008842 -1.68402)
		(end 151.0284 -1.703578)
		(width 0.1778)
		(layer "F.Cu")
		(net "M_B_ECC5")
	)
	(segment
		(start 103.9368 -21.7678)
		(end 103.9368 -26.146506)
		(width 0.1016)
		(layer "F.Cu")
		(net "M_B_ECC5")
	)
	(segment
		(start 103.505 -21.336)
		(end 103.9368 -21.7678)
		(width 0.1016)
		(layer "F.Cu")
		(net "M_B_ECC5")
	)
	(segment
		(start 149.349968 -1.68402)
		(end 151.008842 -1.68402)
		(width 0.1778)
		(layer "F.Cu")
		(net "M_B_ECC5")
	)
	(via
		(at 151.0284 -1.703578)
		(size 0.4318)
		(drill 0.2032)
		(layers "F.Cu" "B.Cu")
		(net "M_B_ECC5")
	)
	(via
		(at 103.505 -21.336)
		(size 0.4318)
		(drill 0.2032)
		(layers "F.Cu" "B.Cu")
		(net "M_B_ECC5")
	)
	(segment
		(start 152.649936 -1.690624)
		(end 151.092154 -1.690624)
		(width 0.1778)
		(layer "B.Cu")
		(net "M_B_ECC5")
	)
	(segment
		(start 151.0792 -1.703578)
		(end 151.0284 -1.703578)
		(width 0.1778)
		(layer "B.Cu")
		(net "M_B_ECC5")
	)
	(segment
		(start 151.092154 -1.690624)
		(end 151.0792 -1.703578)
		(width 0.1778)
		(layer "B.Cu")
		(net "M_B_ECC5")
	)
	(segment
		(start 149.1488 -14.8844)
		(end 146.8882 -17.145)
		(width 0.1524)
		(layer "In2.Cu")
		(net "M_B_ECC5")
	)
	(segment
		(start 122.250708 -17.8054)
		(end 121.7422 -17.8054)
		(width 0.1524)
		(layer "In2.Cu")
		(net "M_B_ECC5")
	)
	(segment
		(start 121.361454 -19.075146)
		(end 110.529116 -19.075146)
		(width 0.1524)
		(layer "In2.Cu")
		(net "M_B_ECC5")
	)
	(segment
		(start 138.722862 -17.145)
		(end 138.189462 -17.6784)
		(width 0.1524)
		(layer "In2.Cu")
		(net "M_B_ECC5")
	)
	(segment
		(start 123.012708 -18.161)
		(end 122.860308 -18.3134)
		(width 0.1524)
		(layer "In2.Cu")
		(net "M_B_ECC5")
	)
	(segment
		(start 121.5898 -18.8468)
		(end 121.361454 -19.075146)
		(width 0.1524)
		(layer "In2.Cu")
		(net "M_B_ECC5")
	)
	(segment
		(start 122.403108 -18.161)
		(end 122.403108 -17.9578)
		(width 0.1524)
		(layer "In2.Cu")
		(net "M_B_ECC5")
	)
	(segment
		(start 103.505 -21.336)
		(end 104.14 -20.701)
		(width 0.1016)
		(layer "In2.Cu")
		(net "M_B_ECC5")
	)
	(segment
		(start 122.403108 -17.9578)
		(end 122.250708 -17.8054)
		(width 0.1524)
		(layer "In2.Cu")
		(net "M_B_ECC5")
	)
	(segment
		(start 122.555508 -18.3134)
		(end 122.403108 -18.161)
		(width 0.1524)
		(layer "In2.Cu")
		(net "M_B_ECC5")
	)
	(segment
		(start 110.529116 -19.075146)
		(end 109.030262 -20.574)
		(width 0.1524)
		(layer "In2.Cu")
		(net "M_B_ECC5")
	)
	(segment
		(start 123.012708 -17.8308)
		(end 123.012708 -18.161)
		(width 0.1524)
		(layer "In2.Cu")
		(net "M_B_ECC5")
	)
	(segment
		(start 146.8882 -17.145)
		(end 138.722862 -17.145)
		(width 0.1524)
		(layer "In2.Cu")
		(net "M_B_ECC5")
	)
	(segment
		(start 121.5898 -17.9578)
		(end 121.5898 -18.8468)
		(width 0.1524)
		(layer "In2.Cu")
		(net "M_B_ECC5")
	)
	(segment
		(start 123.165108 -17.6784)
		(end 123.012708 -17.8308)
		(width 0.1524)
		(layer "In2.Cu")
		(net "M_B_ECC5")
	)
	(segment
		(start 122.860308 -18.3134)
		(end 122.555508 -18.3134)
		(width 0.1524)
		(layer "In2.Cu")
		(net "M_B_ECC5")
	)
	(segment
		(start 121.7422 -17.8054)
		(end 121.5898 -17.9578)
		(width 0.1524)
		(layer "In2.Cu")
		(net "M_B_ECC5")
	)
	(segment
		(start 151.0284 -1.703578)
		(end 151.0284 -5.919978)
		(width 0.1524)
		(layer "In2.Cu")
		(net "M_B_ECC5")
	)
	(segment
		(start 138.189462 -17.6784)
		(end 123.165108 -17.6784)
		(width 0.1524)
		(layer "In2.Cu")
		(net "M_B_ECC5")
	)
	(segment
		(start 151.0284 -5.919978)
		(end 149.1488 -7.799578)
		(width 0.1524)
		(layer "In2.Cu")
		(net "M_B_ECC5")
	)
	(segment
		(start 149.1488 -7.799578)
		(end 149.1488 -14.8844)
		(width 0.1524)
		(layer "In2.Cu")
		(net "M_B_ECC5")
	)
	(segment
		(start 108.903262 -20.701)
		(end 109.030262 -20.574)
		(width 0.1016)
		(layer "In2.Cu")
		(net "M_B_ECC5")
	)
	(segment
		(start 104.14 -20.701)
		(end 108.903262 -20.701)
		(width 0.1016)
		(layer "In2.Cu")
		(net "M_B_ECC5")
	)
	(segment
		(start 40.64 -21.336)
		(end 46.101 -21.336)
		(width 0.1397)
		(layer "B.Cu")
		(net "CLK_100M_CLKBUFF_NGFF_R_DN")
	)
	(segment
		(start 47.6123 -19.3675)
		(end 47.52213 -19.27733)
		(width 0.1397)
		(layer "B.Cu")
		(net "CLK_100M_CLKBUFF_NGFF_R_DN")
	)
	(segment
		(start 47.52213 -19.27733)
		(end 47.52213 -18.6563)
		(width 0.1397)
		(layer "B.Cu")
		(net "CLK_100M_CLKBUFF_NGFF_R_DN")
	)
	(segment
		(start 46.101 -21.336)
		(end 47.6123 -19.8247)
		(width 0.1397)
		(layer "B.Cu")
		(net "CLK_100M_CLKBUFF_NGFF_R_DN")
	)
	(segment
		(start 39.03345 -22.94255)
		(end 40.64 -21.336)
		(width 0.1397)
		(layer "B.Cu")
		(net "CLK_100M_CLKBUFF_NGFF_R_DN")
	)
	(segment
		(start 47.6123 -19.8247)
		(end 47.6123 -19.3675)
		(width 0.1397)
		(layer "B.Cu")
		(net "CLK_100M_CLKBUFF_NGFF_R_DN")
	)
	(segment
		(start 38.36035 -22.94255)
		(end 39.03345 -22.94255)
		(width 0.1397)
		(layer "B.Cu")
		(net "CLK_100M_CLKBUFF_NGFF_R_DN")
	)
	(segment
		(start 38.1508 -22.733)
		(end 38.36035 -22.94255)
		(width 0.1397)
		(layer "B.Cu")
		(net "CLK_100M_CLKBUFF_NGFF_R_DN")
	)
	(segment
		(start 100.4824 -46.7614)
		(end 100.3046 -46.7614)
		(width 0.1016)
		(layer "F.Cu")
		(net "M_A_CS_N1")
	)
	(segment
		(start 100.3046 -46.7614)
		(end 100.053648 -46.510448)
		(width 0.1016)
		(layer "F.Cu")
		(net "M_A_CS_N1")
	)
	(segment
		(start 100.053648 -46.510448)
		(end 100.053648 -46.497494)
		(width 0.1016)
		(layer "F.Cu")
		(net "M_A_CS_N1")
	)
	(via
		(at 100.4824 -46.7614)
		(size 0.4318)
		(drill 0.2032)
		(layers "F.Cu" "B.Cu")
		(net "M_A_CS_N1")
	)
	(via
		(at 149.261068 -64.060324)
		(size 0.4318)
		(drill 0.2032)
		(layers "F.Cu" "B.Cu")
		(net "M_A_CS_N1")
	)
	(segment
		(start 149.261068 -63.895732)
		(end 149.261068 -64.060324)
		(width 0.1778)
		(layer "B.Cu")
		(net "M_A_CS_N1")
	)
	(segment
		(start 149.349968 -63.806832)
		(end 149.261068 -63.895732)
		(width 0.1778)
		(layer "B.Cu")
		(net "M_A_CS_N1")
	)
	(segment
		(start 149.349968 -62.599824)
		(end 149.349968 -63.806832)
		(width 0.1778)
		(layer "B.Cu")
		(net "M_A_CS_N1")
	)
	(segment
		(start 121.877836 -58.74385)
		(end 122.239786 -58.74385)
		(width 0.1524)
		(layer "In7.Cu")
		(net "M_A_CS_N1")
	)
	(segment
		(start 122.849386 -58.4962)
		(end 123.097036 -58.74385)
		(width 0.1524)
		(layer "In7.Cu")
		(net "M_A_CS_N1")
	)
	(segment
		(start 100.4824 -46.7614)
		(end 100.4824 -47.0408)
		(width 0.1016)
		(layer "In7.Cu")
		(net "M_A_CS_N1")
	)
	(segment
		(start 145.835116 -62.9412)
		(end 145.987516 -62.7888)
		(width 0.1524)
		(layer "In7.Cu")
		(net "M_A_CS_N1")
	)
	(segment
		(start 139.342622 -60.564014)
		(end 138.955526 -60.95111)
		(width 0.1524)
		(layer "In7.Cu")
		(net "M_A_CS_N1")
	)
	(segment
		(start 138.955526 -60.95111)
		(end 138.955526 -61.166502)
		(width 0.1524)
		(layer "In7.Cu")
		(net "M_A_CS_N1")
	)
	(segment
		(start 144.158716 -62.7888)
		(end 144.311116 -62.9412)
		(width 0.1524)
		(layer "In7.Cu")
		(net "M_A_CS_N1")
	)
	(segment
		(start 127.364236 -58.4962)
		(end 127.726186 -58.4962)
		(width 0.1524)
		(layer "In7.Cu")
		(net "M_A_CS_N1")
	)
	(segment
		(start 142.177516 -62.9412)
		(end 142.329916 -62.7888)
		(width 0.1524)
		(layer "In7.Cu")
		(net "M_A_CS_N1")
	)
	(segment
		(start 139.342622 -60.348622)
		(end 139.342622 -60.564014)
		(width 0.1524)
		(layer "In7.Cu")
		(net "M_A_CS_N1")
	)
	(segment
		(start 102.241096 -57.277)
		(end 102.241096 -58.248296)
		(width 0.1524)
		(layer "In7.Cu")
		(net "M_A_CS_N1")
	)
	(segment
		(start 139.126722 -60.132722)
		(end 139.342622 -60.348622)
		(width 0.1524)
		(layer "In7.Cu")
		(net "M_A_CS_N1")
	)
	(segment
		(start 145.987516 -62.1284)
		(end 146.139916 -61.976)
		(width 0.1524)
		(layer "In7.Cu")
		(net "M_A_CS_N1")
	)
	(segment
		(start 142.939516 -62.7888)
		(end 143.091916 -62.9412)
		(width 0.1524)
		(layer "In7.Cu")
		(net "M_A_CS_N1")
	)
	(segment
		(start 136.874504 -59.0042)
		(end 137.2108 -59.0042)
		(width 0.1524)
		(layer "In7.Cu")
		(net "M_A_CS_N1")
	)
	(segment
		(start 127.973836 -58.74385)
		(end 128.335786 -58.74385)
		(width 0.1524)
		(layer "In7.Cu")
		(net "M_A_CS_N1")
	)
	(segment
		(start 136.722104 -58.6486)
		(end 136.722104 -58.8518)
		(width 0.1524)
		(layer "In7.Cu")
		(net "M_A_CS_N1")
	)
	(segment
		(start 145.530316 -62.9412)
		(end 145.835116 -62.9412)
		(width 0.1524)
		(layer "In7.Cu")
		(net "M_A_CS_N1")
	)
	(segment
		(start 139.386818 -61.382402)
		(end 139.710414 -61.058806)
		(width 0.1524)
		(layer "In7.Cu")
		(net "M_A_CS_N1")
	)
	(segment
		(start 138.092942 -60.303918)
		(end 138.308842 -60.519818)
		(width 0.1524)
		(layer "In7.Cu")
		(net "M_A_CS_N1")
	)
	(segment
		(start 137.5156 -58.6994)
		(end 137.679938 -58.6994)
		(width 0.1524)
		(layer "In7.Cu")
		(net "M_A_CS_N1")
	)
	(segment
		(start 143.549116 -62.7888)
		(end 143.549116 -62.0522)
		(width 0.1524)
		(layer "In7.Cu")
		(net "M_A_CS_N1")
	)
	(segment
		(start 143.701516 -61.8998)
		(end 144.006316 -61.8998)
		(width 0.1524)
		(layer "In7.Cu")
		(net "M_A_CS_N1")
	)
	(segment
		(start 137.679938 -58.6994)
		(end 138.416538 -59.436)
		(width 0.1524)
		(layer "In7.Cu")
		(net "M_A_CS_N1")
	)
	(segment
		(start 138.308842 -60.519818)
		(end 138.524234 -60.519818)
		(width 0.1524)
		(layer "In7.Cu")
		(net "M_A_CS_N1")
	)
	(segment
		(start 137.2108 -59.0042)
		(end 137.5156 -58.6994)
		(width 0.1524)
		(layer "In7.Cu")
		(net "M_A_CS_N1")
	)
	(segment
		(start 123.458986 -58.74385)
		(end 123.706636 -58.4962)
		(width 0.1524)
		(layer "In7.Cu")
		(net "M_A_CS_N1")
	)
	(segment
		(start 144.920716 -61.8998)
		(end 145.225516 -61.8998)
		(width 0.1524)
		(layer "In7.Cu")
		(net "M_A_CS_N1")
	)
	(segment
		(start 124.068586 -58.4962)
		(end 124.316236 -58.74385)
		(width 0.1524)
		(layer "In7.Cu")
		(net "M_A_CS_N1")
	)
	(segment
		(start 143.549116 -62.0522)
		(end 143.701516 -61.8998)
		(width 0.1524)
		(layer "In7.Cu")
		(net "M_A_CS_N1")
	)
	(segment
		(start 145.377916 -62.7888)
		(end 145.530316 -62.9412)
		(width 0.1524)
		(layer "In7.Cu")
		(net "M_A_CS_N1")
	)
	(segment
		(start 102.73665 -58.74385)
		(end 120.798336 -58.74385)
		(width 0.1524)
		(layer "In7.Cu")
		(net "M_A_CS_N1")
	)
	(segment
		(start 143.396716 -62.9412)
		(end 143.549116 -62.7888)
		(width 0.1524)
		(layer "In7.Cu")
		(net "M_A_CS_N1")
	)
	(segment
		(start 146.139916 -61.976)
		(end 146.444716 -61.976)
		(width 0.1524)
		(layer "In7.Cu")
		(net "M_A_CS_N1")
	)
	(segment
		(start 142.329916 -62.7888)
		(end 142.329916 -62.0776)
		(width 0.1524)
		(layer "In7.Cu")
		(net "M_A_CS_N1")
	)
	(segment
		(start 123.706636 -58.4962)
		(end 124.068586 -58.4962)
		(width 0.1524)
		(layer "In7.Cu")
		(net "M_A_CS_N1")
	)
	(segment
		(start 124.925836 -58.4962)
		(end 125.287786 -58.4962)
		(width 0.1524)
		(layer "In7.Cu")
		(net "M_A_CS_N1")
	)
	(segment
		(start 100.1141 -49.7205)
		(end 100.33 -49.9364)
		(width 0.1016)
		(layer "In7.Cu")
		(net "M_A_CS_N1")
	)
	(segment
		(start 138.955526 -61.166502)
		(end 139.171426 -61.382402)
		(width 0.1524)
		(layer "In7.Cu")
		(net "M_A_CS_N1")
	)
	(segment
		(start 141.7066 -62.9412)
		(end 142.177516 -62.9412)
		(width 0.1524)
		(layer "In7.Cu")
		(net "M_A_CS_N1")
	)
	(segment
		(start 138.092942 -60.088526)
		(end 138.092942 -60.303918)
		(width 0.1524)
		(layer "In7.Cu")
		(net "M_A_CS_N1")
	)
	(segment
		(start 124.316236 -58.74385)
		(end 124.678186 -58.74385)
		(width 0.1524)
		(layer "In7.Cu")
		(net "M_A_CS_N1")
	)
	(segment
		(start 140.249402 -62.244986)
		(end 140.572998 -61.92139)
		(width 0.1524)
		(layer "In7.Cu")
		(net "M_A_CS_N1")
	)
	(segment
		(start 138.524234 -60.519818)
		(end 138.91133 -60.132722)
		(width 0.1524)
		(layer "In7.Cu")
		(net "M_A_CS_N1")
	)
	(segment
		(start 145.377916 -62.0522)
		(end 145.377916 -62.7888)
		(width 0.1524)
		(layer "In7.Cu")
		(net "M_A_CS_N1")
	)
	(segment
		(start 124.678186 -58.74385)
		(end 124.925836 -58.4962)
		(width 0.1524)
		(layer "In7.Cu")
		(net "M_A_CS_N1")
	)
	(segment
		(start 136.722104 -58.8518)
		(end 136.874504 -59.0042)
		(width 0.1524)
		(layer "In7.Cu")
		(net "M_A_CS_N1")
	)
	(segment
		(start 140.03401 -62.244986)
		(end 140.249402 -62.244986)
		(width 0.1524)
		(layer "In7.Cu")
		(net "M_A_CS_N1")
	)
	(segment
		(start 139.171426 -61.382402)
		(end 139.386818 -61.382402)
		(width 0.1524)
		(layer "In7.Cu")
		(net "M_A_CS_N1")
	)
	(segment
		(start 122.487436 -58.4962)
		(end 122.849386 -58.4962)
		(width 0.1524)
		(layer "In7.Cu")
		(net "M_A_CS_N1")
	)
	(segment
		(start 142.939516 -62.0776)
		(end 142.939516 -62.7888)
		(width 0.1524)
		(layer "In7.Cu")
		(net "M_A_CS_N1")
	)
	(segment
		(start 142.329916 -62.0776)
		(end 142.482316 -61.9252)
		(width 0.1524)
		(layer "In7.Cu")
		(net "M_A_CS_N1")
	)
	(segment
		(start 139.81811 -61.813694)
		(end 139.81811 -62.029086)
		(width 0.1524)
		(layer "In7.Cu")
		(net "M_A_CS_N1")
	)
	(segment
		(start 141.4018 -61.92139)
		(end 141.5542 -62.07379)
		(width 0.1524)
		(layer "In7.Cu")
		(net "M_A_CS_N1")
	)
	(segment
		(start 144.615916 -62.9412)
		(end 144.768316 -62.7888)
		(width 0.1524)
		(layer "In7.Cu")
		(net "M_A_CS_N1")
	)
	(segment
		(start 100.1141 -47.4091)
		(end 100.1141 -49.7205)
		(width 0.1016)
		(layer "In7.Cu")
		(net "M_A_CS_N1")
	)
	(segment
		(start 126.754636 -58.74385)
		(end 127.116586 -58.74385)
		(width 0.1524)
		(layer "In7.Cu")
		(net "M_A_CS_N1")
	)
	(segment
		(start 100.33 -49.9364)
		(end 100.33 -52.6542)
		(width 0.1016)
		(layer "In7.Cu")
		(net "M_A_CS_N1")
	)
	(segment
		(start 141.5542 -62.07379)
		(end 141.5542 -62.7888)
		(width 0.1524)
		(layer "In7.Cu")
		(net "M_A_CS_N1")
	)
	(segment
		(start 121.045986 -58.4962)
		(end 121.630186 -58.4962)
		(width 0.1524)
		(layer "In7.Cu")
		(net "M_A_CS_N1")
	)
	(segment
		(start 125.535436 -58.74385)
		(end 125.897386 -58.74385)
		(width 0.1524)
		(layer "In7.Cu")
		(net "M_A_CS_N1")
	)
	(segment
		(start 139.710414 -61.058806)
		(end 139.925806 -61.058806)
		(width 0.1524)
		(layer "In7.Cu")
		(net "M_A_CS_N1")
	)
	(segment
		(start 121.630186 -58.4962)
		(end 121.877836 -58.74385)
		(width 0.1524)
		(layer "In7.Cu")
		(net "M_A_CS_N1")
	)
	(segment
		(start 143.091916 -62.9412)
		(end 143.396716 -62.9412)
		(width 0.1524)
		(layer "In7.Cu")
		(net "M_A_CS_N1")
	)
	(segment
		(start 138.91133 -60.132722)
		(end 139.126722 -60.132722)
		(width 0.1524)
		(layer "In7.Cu")
		(net "M_A_CS_N1")
	)
	(segment
		(start 127.726186 -58.4962)
		(end 127.973836 -58.74385)
		(width 0.1524)
		(layer "In7.Cu")
		(net "M_A_CS_N1")
	)
	(segment
		(start 126.506986 -58.4962)
		(end 126.754636 -58.74385)
		(width 0.1524)
		(layer "In7.Cu")
		(net "M_A_CS_N1")
	)
	(segment
		(start 144.311116 -62.9412)
		(end 144.615916 -62.9412)
		(width 0.1524)
		(layer "In7.Cu")
		(net "M_A_CS_N1")
	)
	(segment
		(start 139.925806 -61.058806)
		(end 140.141706 -61.274706)
		(width 0.1524)
		(layer "In7.Cu")
		(net "M_A_CS_N1")
	)
	(segment
		(start 125.287786 -58.4962)
		(end 125.535436 -58.74385)
		(width 0.1524)
		(layer "In7.Cu")
		(net "M_A_CS_N1")
	)
	(segment
		(start 138.416538 -59.76493)
		(end 138.092942 -60.088526)
		(width 0.1524)
		(layer "In7.Cu")
		(net "M_A_CS_N1")
	)
	(segment
		(start 146.597116 -62.738)
		(end 146.749516 -62.8904)
		(width 0.1524)
		(layer "In7.Cu")
		(net "M_A_CS_N1")
	)
	(segment
		(start 144.006316 -61.8998)
		(end 144.158716 -62.0522)
		(width 0.1524)
		(layer "In7.Cu")
		(net "M_A_CS_N1")
	)
	(segment
		(start 146.597116 -62.1284)
		(end 146.597116 -62.738)
		(width 0.1524)
		(layer "In7.Cu")
		(net "M_A_CS_N1")
	)
	(segment
		(start 127.116586 -58.74385)
		(end 127.364236 -58.4962)
		(width 0.1524)
		(layer "In7.Cu")
		(net "M_A_CS_N1")
	)
	(segment
		(start 145.225516 -61.8998)
		(end 145.377916 -62.0522)
		(width 0.1524)
		(layer "In7.Cu")
		(net "M_A_CS_N1")
	)
	(segment
		(start 144.768316 -62.7888)
		(end 144.768316 -62.0522)
		(width 0.1524)
		(layer "In7.Cu")
		(net "M_A_CS_N1")
	)
	(segment
		(start 144.158716 -62.0522)
		(end 144.158716 -62.7888)
		(width 0.1524)
		(layer "In7.Cu")
		(net "M_A_CS_N1")
	)
	(segment
		(start 140.141706 -61.490098)
		(end 139.81811 -61.813694)
		(width 0.1524)
		(layer "In7.Cu")
		(net "M_A_CS_N1")
	)
	(segment
		(start 138.416538 -59.436)
		(end 138.416538 -59.76493)
		(width 0.1524)
		(layer "In7.Cu")
		(net "M_A_CS_N1")
	)
	(segment
		(start 120.798336 -58.74385)
		(end 121.045986 -58.4962)
		(width 0.1524)
		(layer "In7.Cu")
		(net "M_A_CS_N1")
	)
	(segment
		(start 145.987516 -62.7888)
		(end 145.987516 -62.1284)
		(width 0.1524)
		(layer "In7.Cu")
		(net "M_A_CS_N1")
	)
	(segment
		(start 144.768316 -62.0522)
		(end 144.920716 -61.8998)
		(width 0.1524)
		(layer "In7.Cu")
		(net "M_A_CS_N1")
	)
	(segment
		(start 102.241096 -58.248296)
		(end 102.73665 -58.74385)
		(width 0.1524)
		(layer "In7.Cu")
		(net "M_A_CS_N1")
	)
	(segment
		(start 142.787116 -61.9252)
		(end 142.939516 -62.0776)
		(width 0.1524)
		(layer "In7.Cu")
		(net "M_A_CS_N1")
	)
	(segment
		(start 128.335786 -58.74385)
		(end 128.583436 -58.4962)
		(width 0.1524)
		(layer "In7.Cu")
		(net "M_A_CS_N1")
	)
	(segment
		(start 139.81811 -62.029086)
		(end 140.03401 -62.244986)
		(width 0.1524)
		(layer "In7.Cu")
		(net "M_A_CS_N1")
	)
	(segment
		(start 100.33 -52.6542)
		(end 102.241096 -54.565296)
		(width 0.1016)
		(layer "In7.Cu")
		(net "M_A_CS_N1")
	)
	(segment
		(start 123.097036 -58.74385)
		(end 123.458986 -58.74385)
		(width 0.1524)
		(layer "In7.Cu")
		(net "M_A_CS_N1")
	)
	(segment
		(start 125.897386 -58.74385)
		(end 126.145036 -58.4962)
		(width 0.1524)
		(layer "In7.Cu")
		(net "M_A_CS_N1")
	)
	(segment
		(start 146.749516 -62.8904)
		(end 148.091144 -62.8904)
		(width 0.1524)
		(layer "In7.Cu")
		(net "M_A_CS_N1")
	)
	(segment
		(start 100.4824 -47.0408)
		(end 100.1141 -47.4091)
		(width 0.1016)
		(layer "In7.Cu")
		(net "M_A_CS_N1")
	)
	(segment
		(start 128.583436 -58.4962)
		(end 136.569704 -58.4962)
		(width 0.1524)
		(layer "In7.Cu")
		(net "M_A_CS_N1")
	)
	(segment
		(start 136.569704 -58.4962)
		(end 136.722104 -58.6486)
		(width 0.1524)
		(layer "In7.Cu")
		(net "M_A_CS_N1")
	)
	(segment
		(start 146.444716 -61.976)
		(end 146.597116 -62.1284)
		(width 0.1524)
		(layer "In7.Cu")
		(net "M_A_CS_N1")
	)
	(segment
		(start 141.5542 -62.7888)
		(end 141.7066 -62.9412)
		(width 0.1524)
		(layer "In7.Cu")
		(net "M_A_CS_N1")
	)
	(segment
		(start 102.241096 -54.565296)
		(end 102.241096 -57.277)
		(width 0.1016)
		(layer "In7.Cu")
		(net "M_A_CS_N1")
	)
	(segment
		(start 140.141706 -61.274706)
		(end 140.141706 -61.490098)
		(width 0.1524)
		(layer "In7.Cu")
		(net "M_A_CS_N1")
	)
	(segment
		(start 122.239786 -58.74385)
		(end 122.487436 -58.4962)
		(width 0.1524)
		(layer "In7.Cu")
		(net "M_A_CS_N1")
	)
	(segment
		(start 148.091144 -62.8904)
		(end 149.261068 -64.060324)
		(width 0.1524)
		(layer "In7.Cu")
		(net "M_A_CS_N1")
	)
	(segment
		(start 126.145036 -58.4962)
		(end 126.506986 -58.4962)
		(width 0.1524)
		(layer "In7.Cu")
		(net "M_A_CS_N1")
	)
	(segment
		(start 140.572998 -61.92139)
		(end 141.4018 -61.92139)
		(width 0.1524)
		(layer "In7.Cu")
		(net "M_A_CS_N1")
	)
	(segment
		(start 142.482316 -61.9252)
		(end 142.787116 -61.9252)
		(width 0.1524)
		(layer "In7.Cu")
		(net "M_A_CS_N1")
	)
	(segment
		(start 96.393 -21.158708)
		(end 96.8375 -21.603208)
		(width 0.1016)
		(layer "F.Cu")
		(net "M_B_DQS_DP1")
	)
	(segment
		(start 136.149842 -2.436876)
		(end 136.002268 -2.58445)
		(width 0.1778)
		(layer "F.Cu")
		(net "M_B_DQS_DP1")
	)
	(segment
		(start 97.945448 -26.3144)
		(end 98.047048 -26.416)
		(width 0.1016)
		(layer "F.Cu")
		(net "M_B_DQS_DP1")
	)
	(segment
		(start 96.8375 -21.603208)
		(end 96.8375 -24.655018)
		(width 0.1016)
		(layer "F.Cu")
		(net "M_B_DQS_DP1")
	)
	(segment
		(start 136.002268 -2.58445)
		(end 136.002268 -5.553456)
		(width 0.1778)
		(layer "F.Cu")
		(net "M_B_DQS_DP1")
	)
	(segment
		(start 96.8375 -24.655018)
		(end 97.945448 -25.762966)
		(width 0.1016)
		(layer "F.Cu")
		(net "M_B_DQS_DP1")
	)
	(segment
		(start 98.047048 -26.684986)
		(end 97.747328 -26.984706)
		(width 0.1016)
		(layer "F.Cu")
		(net "M_B_DQS_DP1")
	)
	(segment
		(start 136.149842 -1.68402)
		(end 136.149842 -2.436876)
		(width 0.1778)
		(layer "F.Cu")
		(net "M_B_DQS_DP1")
	)
	(segment
		(start 97.945448 -25.762966)
		(end 97.945448 -26.3144)
		(width 0.1016)
		(layer "F.Cu")
		(net "M_B_DQS_DP1")
	)
	(segment
		(start 136.002268 -5.553456)
		(end 136.26719 -5.818378)
		(width 0.1778)
		(layer "F.Cu")
		(net "M_B_DQS_DP1")
	)
	(segment
		(start 98.047048 -26.416)
		(end 98.047048 -26.684986)
		(width 0.1016)
		(layer "F.Cu")
		(net "M_B_DQS_DP1")
	)
	(segment
		(start 97.747328 -26.984706)
		(end 97.747328 -27.300174)
		(width 0.1016)
		(layer "F.Cu")
		(net "M_B_DQS_DP1")
	)
	(via
		(at 96.393 -21.158708)
		(size 0.4318)
		(drill 0.2032)
		(layers "F.Cu" "B.Cu")
		(net "M_B_DQS_DP1")
	)
	(via
		(at 136.26719 -5.818378)
		(size 0.4318)
		(drill 0.2032)
		(layers "F.Cu" "B.Cu")
		(net "M_B_DQS_DP1")
	)
	(segment
		(start 136.149842 -9.89076)
		(end 136.149842 -9.12622)
		(width 0.1778)
		(layer "B.Cu")
		(net "M_B_DQS_DP1")
	)
	(segment
		(start 136.149842 -9.12622)
		(end 136.002268 -8.978646)
		(width 0.1778)
		(layer "B.Cu")
		(net "M_B_DQS_DP1")
	)
	(segment
		(start 136.002268 -8.978646)
		(end 136.002268 -6.0833)
		(width 0.1778)
		(layer "B.Cu")
		(net "M_B_DQS_DP1")
	)
	(segment
		(start 136.002268 -6.0833)
		(end 136.26719 -5.818378)
		(width 0.1778)
		(layer "B.Cu")
		(net "M_B_DQS_DP1")
	)
	(segment
		(start 134.582662 -10.973562)
		(end 134.582662 -13.603224)
		(width 0.1524)
		(layer "In2.Cu")
		(net "M_B_DQS_DP1")
	)
	(segment
		(start 115.546378 -14.4653)
		(end 115.546378 -14.99997)
		(width 0.1524)
		(layer "In2.Cu")
		(net "M_B_DQS_DP1")
	)
	(segment
		(start 135.989568 -6.096)
		(end 135.989568 -9.566656)
		(width 0.1524)
		(layer "In2.Cu")
		(net "M_B_DQS_DP1")
	)
	(segment
		(start 117.729 -14.0716)
		(end 117.729 -14.847824)
		(width 0.1524)
		(layer "In2.Cu")
		(net "M_B_DQS_DP1")
	)
	(segment
		(start 117.8814 -13.9192)
		(end 117.729 -14.0716)
		(width 0.1524)
		(layer "In2.Cu")
		(net "M_B_DQS_DP1")
	)
	(segment
		(start 117.729 -14.847824)
		(end 117.413024 -15.1638)
		(width 0.1524)
		(layer "In2.Cu")
		(net "M_B_DQS_DP1")
	)
	(segment
		(start 101.664516 -17.475708)
		(end 99.594924 -19.5453)
		(width 0.1524)
		(layer "In2.Cu")
		(net "M_B_DQS_DP1")
	)
	(segment
		(start 136.26719 -5.818378)
		(end 135.989568 -6.096)
		(width 0.1524)
		(layer "In2.Cu")
		(net "M_B_DQS_DP1")
	)
	(segment
		(start 135.989568 -9.566656)
		(end 134.582662 -10.973562)
		(width 0.1524)
		(layer "In2.Cu")
		(net "M_B_DQS_DP1")
	)
	(segment
		(start 97.766124 -19.5453)
		(end 96.393 -20.918424)
		(width 0.1524)
		(layer "In2.Cu")
		(net "M_B_DQS_DP1")
	)
	(segment
		(start 106.811826 -17.475708)
		(end 101.664516 -17.475708)
		(width 0.1524)
		(layer "In2.Cu")
		(net "M_B_DQS_DP1")
	)
	(segment
		(start 116.155978 -14.847824)
		(end 116.155978 -14.4653)
		(width 0.1524)
		(layer "In2.Cu")
		(net "M_B_DQS_DP1")
	)
	(segment
		(start 99.594924 -19.5453)
		(end 97.766124 -19.5453)
		(width 0.1524)
		(layer "In2.Cu")
		(net "M_B_DQS_DP1")
	)
	(segment
		(start 116.471954 -15.1638)
		(end 116.155978 -14.847824)
		(width 0.1524)
		(layer "In2.Cu")
		(net "M_B_DQS_DP1")
	)
	(segment
		(start 115.698778 -14.3129)
		(end 115.546378 -14.4653)
		(width 0.1524)
		(layer "In2.Cu")
		(net "M_B_DQS_DP1")
	)
	(segment
		(start 134.266686 -13.9192)
		(end 117.8814 -13.9192)
		(width 0.1524)
		(layer "In2.Cu")
		(net "M_B_DQS_DP1")
	)
	(segment
		(start 115.230402 -15.315946)
		(end 108.971588 -15.315946)
		(width 0.1524)
		(layer "In2.Cu")
		(net "M_B_DQS_DP1")
	)
	(segment
		(start 116.155978 -14.4653)
		(end 116.003578 -14.3129)
		(width 0.1524)
		(layer "In2.Cu")
		(net "M_B_DQS_DP1")
	)
	(segment
		(start 108.971588 -15.315946)
		(end 106.811826 -17.475708)
		(width 0.1524)
		(layer "In2.Cu")
		(net "M_B_DQS_DP1")
	)
	(segment
		(start 117.413024 -15.1638)
		(end 116.471954 -15.1638)
		(width 0.1524)
		(layer "In2.Cu")
		(net "M_B_DQS_DP1")
	)
	(segment
		(start 134.582662 -13.603224)
		(end 134.266686 -13.9192)
		(width 0.1524)
		(layer "In2.Cu")
		(net "M_B_DQS_DP1")
	)
	(segment
		(start 96.393 -20.918424)
		(end 96.393 -21.158708)
		(width 0.1524)
		(layer "In2.Cu")
		(net "M_B_DQS_DP1")
	)
	(segment
		(start 116.003578 -14.3129)
		(end 115.698778 -14.3129)
		(width 0.1524)
		(layer "In2.Cu")
		(net "M_B_DQS_DP1")
	)
	(segment
		(start 115.546378 -14.99997)
		(end 115.230402 -15.315946)
		(width 0.1524)
		(layer "In2.Cu")
		(net "M_B_DQS_DP1")
	)
	(via
		(at 131.318 -27.94)
		(size 0.7112)
		(drill 0.3556)
		(layers "F.Cu" "B.Cu")
		(net "H_THERMTRIP_N_R")
	)
	(segment
		(start 130.302 -25.9334)
		(end 130.302 -27.178)
		(width 0.1143)
		(layer "B.Cu")
		(net "H_THERMTRIP_N_R")
	)
	(segment
		(start 132.2832 -28.067)
		(end 132.1562 -27.94)
		(width 0.1143)
		(layer "B.Cu")
		(net "H_THERMTRIP_N_R")
	)
	(segment
		(start 130.302 -27.178)
		(end 131.064 -27.94)
		(width 0.1143)
		(layer "B.Cu")
		(net "H_THERMTRIP_N_R")
	)
	(segment
		(start 131.064 -27.94)
		(end 131.318 -27.94)
		(width 0.1143)
		(layer "B.Cu")
		(net "H_THERMTRIP_N_R")
	)
	(segment
		(start 132.1562 -27.94)
		(end 131.318 -27.94)
		(width 0.1143)
		(layer "B.Cu")
		(net "H_THERMTRIP_N_R")
	)
	(segment
		(start 64.6938 -33.02)
		(end 65.659 -33.02)
		(width 0.3048)
		(layer "F.Cu")
		(net "P1V8")
	)
	(segment
		(start 62.44844 -30.4292)
		(end 62.0014 -29.98216)
		(width 0.3048)
		(layer "F.Cu")
		(net "P1V8")
	)
	(segment
		(start 92.197174 -40.800274)
		(end 91.8464 -40.4495)
		(width 0.3048)
		(layer "F.Cu")
		(net "P1V8")
	)
	(segment
		(start 64.6938 -32.258)
		(end 64.6938 -33.02)
		(width 0.3048)
		(layer "F.Cu")
		(net "P1V8")
	)
	(segment
		(start 66.99885 -34.35985)
		(end 65.659 -33.02)
		(width 0.3048)
		(layer "F.Cu")
		(net "P1V8")
	)
	(segment
		(start 69.2658 -54.5846)
		(end 69.2658 -55.5244)
		(width 0.3048)
		(layer "F.Cu")
		(net "P1V8")
	)
	(segment
		(start 68.666614 -53.80609)
		(end 69.2658 -54.405276)
		(width 0.3048)
		(layer "F.Cu")
		(net "P1V8")
	)
	(segment
		(start 64.6938 -32.258)
		(end 64.6938 -31.5468)
		(width 0.3048)
		(layer "F.Cu")
		(net "P1V8")
	)
	(segment
		(start 69.2658 -54.405276)
		(end 69.2658 -54.5846)
		(width 0.3048)
		(layer "F.Cu")
		(net "P1V8")
	)
	(segment
		(start 66.99885 -35.643058)
		(end 66.99885 -34.35985)
		(width 0.3048)
		(layer "F.Cu")
		(net "P1V8")
	)
	(segment
		(start 69.2658 -55.5244)
		(end 69.1642 -55.626)
		(width 0.3048)
		(layer "F.Cu")
		(net "P1V8")
	)
	(segment
		(start 63.119 -30.4292)
		(end 62.44844 -30.4292)
		(width 0.3048)
		(layer "F.Cu")
		(net "P1V8")
	)
	(segment
		(start 91.8464 -40.402002)
		(end 91.8464 -40.4495)
		(width 0.3048)
		(layer "F.Cu")
		(net "P1V8")
	)
	(segment
		(start 64.6938 -31.5468)
		(end 63.5762 -30.4292)
		(width 0.3048)
		(layer "F.Cu")
		(net "P1V8")
	)
	(segment
		(start 63.5762 -30.4292)
		(end 63.119 -30.4292)
		(width 0.3048)
		(layer "F.Cu")
		(net "P1V8")
	)
	(segment
		(start 92.248228 -40.000174)
		(end 91.8464 -40.402002)
		(width 0.3048)
		(layer "F.Cu")
		(net "P1V8")
	)
	(segment
		(start 92.248228 -40.800274)
		(end 92.197174 -40.800274)
		(width 0.3048)
		(layer "F.Cu")
		(net "P1V8")
	)
	(via
		(at 69.2658 -54.5846)
		(size 0.7112)
		(drill 0.3556)
		(layers "F.Cu" "B.Cu")
		(net "P1V8")
	)
	(via
		(at 66.99885 -35.643058)
		(size 0.508)
		(drill 0.254)
		(layers "F.Cu" "B.Cu")
		(net "P1V8")
	)
	(via
		(at 68.666614 -53.80609)
		(size 0.508)
		(drill 0.254)
		(layers "F.Cu" "B.Cu")
		(net "P1V8")
	)
	(via
		(at 66.167 -52.324)
		(size 0.7112)
		(drill 0.3556)
		(layers "F.Cu" "B.Cu")
		(net "P1V8")
	)
	(via
		(at 91.8464 -40.4495)
		(size 0.4318)
		(drill 0.2032)
		(layers "F.Cu" "B.Cu")
		(net "P1V8")
	)
	(via
		(at 66.3448 -53.2638)
		(size 0.508)
		(drill 0.254)
		(layers "F.Cu" "B.Cu")
		(net "P1V8")
	)
	(via
		(at 65.659 -33.02)
		(size 0.7112)
		(drill 0.3556)
		(layers "F.Cu" "B.Cu")
		(net "P1V8")
	)
	(segment
		(start 66.04 -41.232836)
		(end 66.04 -36.601908)
		(width 0.3048)
		(layer "B.Cu")
		(net "P1V8")
	)
	(segment
		(start 66.167 -49.975262)
		(end 65.2526 -49.060862)
		(width 0.3048)
		(layer "B.Cu")
		(net "P1V8")
	)
	(segment
		(start 65.2526 -49.060862)
		(end 65.2526 -44.182538)
		(width 0.3048)
		(layer "B.Cu")
		(net "P1V8")
	)
	(segment
		(start 66.167 -52.324)
		(end 66.167 -49.975262)
		(width 0.3048)
		(layer "B.Cu")
		(net "P1V8")
	)
	(segment
		(start 91.7702 -40.5257)
		(end 91.7702 -41.1226)
		(width 0.3048)
		(layer "B.Cu")
		(net "P1V8")
	)
	(segment
		(start 66.167 -53.086)
		(end 66.167 -52.324)
		(width 0.3048)
		(layer "B.Cu")
		(net "P1V8")
	)
	(segment
		(start 91.8464 -40.4495)
		(end 91.7702 -40.5257)
		(width 0.3048)
		(layer "B.Cu")
		(net "P1V8")
	)
	(segment
		(start 66.084958 -41.277794)
		(end 66.04 -41.232836)
		(width 0.3048)
		(layer "B.Cu")
		(net "P1V8")
	)
	(segment
		(start 66.3448 -53.2638)
		(end 66.167 -53.086)
		(width 0.3048)
		(layer "B.Cu")
		(net "P1V8")
	)
	(segment
		(start 65.2526 -44.182538)
		(end 65.729358 -43.70578)
		(width 0.3048)
		(layer "B.Cu")
		(net "P1V8")
	)
	(segment
		(start 66.084958 -43.349926)
		(end 66.084958 -41.277794)
		(width 0.3048)
		(layer "B.Cu")
		(net "P1V8")
	)
	(segment
		(start 66.04 -36.601908)
		(end 66.99885 -35.643058)
		(width 0.3048)
		(layer "B.Cu")
		(net "P1V8")
	)
	(segment
		(start 65.729358 -43.70578)
		(end 66.084958 -43.349926)
		(width 0.3048)
		(layer "B.Cu")
		(net "P1V8")
	)
	(segment
		(start 81.9531 -41.80332)
		(end 81.731866 -42.024554)
		(width 0.508)
		(layer "In4.Cu")
		(net "P1V8")
	)
	(segment
		(start 91.4019 -40.005)
		(end 90.845132 -40.005)
		(width 0.2794)
		(layer "In4.Cu")
		(net "P1V8")
	)
	(segment
		(start 89.978484 -40.005)
		(end 88.604344 -40.005)
		(width 0.3048)
		(layer "In4.Cu")
		(net "P1V8")
	)
	(segment
		(start 75.946 -46.009052)
		(end 75.946 -48.498506)
		(width 0.508)
		(layer "In4.Cu")
		(net "P1V8")
	)
	(segment
		(start 82.277712 -40.607488)
		(end 81.9531 -40.9321)
		(width 0.3048)
		(layer "In4.Cu")
		(net "P1V8")
	)
	(segment
		(start 81.731866 -42.245534)
		(end 78.74 -45.2374)
		(width 0.508)
		(layer "In4.Cu")
		(net "P1V8")
	)
	(segment
		(start 70.638416 -53.80609)
		(end 68.666614 -53.80609)
		(width 0.508)
		(layer "In4.Cu")
		(net "P1V8")
	)
	(segment
		(start 81.731866 -42.024554)
		(end 81.731866 -42.245534)
		(width 0.508)
		(layer "In4.Cu")
		(net "P1V8")
	)
	(segment
		(start 86.51875 -40.29075)
		(end 85.9663 -39.7383)
		(width 0.3048)
		(layer "In4.Cu")
		(net "P1V8")
	)
	(segment
		(start 88.318594 -40.29075)
		(end 86.51875 -40.29075)
		(width 0.3048)
		(layer "In4.Cu")
		(net "P1V8")
	)
	(segment
		(start 81.9531 -40.9321)
		(end 81.9531 -41.80332)
		(width 0.508)
		(layer "In4.Cu")
		(net "P1V8")
	)
	(segment
		(start 91.8464 -40.4495)
		(end 91.4019 -40.005)
		(width 0.2794)
		(layer "In4.Cu")
		(net "P1V8")
	)
	(segment
		(start 85.9663 -39.7383)
		(end 83.7184 -39.7383)
		(width 0.3048)
		(layer "In4.Cu")
		(net "P1V8")
	)
	(segment
		(start 68.124324 -53.2638)
		(end 66.3448 -53.2638)
		(width 0.508)
		(layer "In4.Cu")
		(net "P1V8")
	)
	(segment
		(start 68.666614 -53.80609)
		(end 68.124324 -53.2638)
		(width 0.508)
		(layer "In4.Cu")
		(net "P1V8")
	)
	(segment
		(start 88.604344 -40.005)
		(end 88.318594 -40.29075)
		(width 0.3048)
		(layer "In4.Cu")
		(net "P1V8")
	)
	(segment
		(start 90.845132 -40.005)
		(end 90.710766 -40.13962)
		(width 0.2794)
		(layer "In4.Cu")
		(net "P1V8")
	)
	(segment
		(start 78.74 -45.2374)
		(end 76.717652 -45.2374)
		(width 0.508)
		(layer "In4.Cu")
		(net "P1V8")
	)
	(segment
		(start 75.946 -48.498506)
		(end 70.638416 -53.80609)
		(width 0.508)
		(layer "In4.Cu")
		(net "P1V8")
	)
	(segment
		(start 90.710766 -40.13962)
		(end 90.113104 -40.13962)
		(width 0.3048)
		(layer "In4.Cu")
		(net "P1V8")
	)
	(segment
		(start 82.849212 -40.607488)
		(end 82.277712 -40.607488)
		(width 0.3048)
		(layer "In4.Cu")
		(net "P1V8")
	)
	(segment
		(start 76.717652 -45.2374)
		(end 75.946 -46.009052)
		(width 0.508)
		(layer "In4.Cu")
		(net "P1V8")
	)
	(segment
		(start 90.113104 -40.13962)
		(end 89.978484 -40.005)
		(width 0.3048)
		(layer "In4.Cu")
		(net "P1V8")
	)
	(segment
		(start 83.7184 -39.7383)
		(end 82.849212 -40.607488)
		(width 0.3048)
		(layer "In4.Cu")
		(net "P1V8")
	)
	(segment
		(start 138.86434 -54.91734)
		(end 137.991596 -54.044596)
		(width 0.254)
		(layer "F.Cu")
		(net "PV_VTT_DDR_REFO")
	)
	(segment
		(start 137.3632 -53.4162)
		(end 137.991596 -54.044596)
		(width 0.254)
		(layer "F.Cu")
		(net "PV_VTT_DDR_REFO")
	)
	(segment
		(start 138.86434 -55.460392)
		(end 138.86434 -54.91734)
		(width 0.254)
		(layer "F.Cu")
		(net "PV_VTT_DDR_REFO")
	)
	(segment
		(start 135.763 -53.4162)
		(end 137.3632 -53.4162)
		(width 0.254)
		(layer "F.Cu")
		(net "PV_VTT_DDR_REFO")
	)
	(via
		(at 137.991596 -54.044596)
		(size 0.7112)
		(drill 0.3556)
		(layers "F.Cu" "B.Cu")
		(net "PV_VTT_DDR_REFO")
	)
	(segment
		(start 102.168706 -46.116494)
		(end 102.039928 -46.116494)
		(width 0.1016)
		(layer "F.Cu")
		(net "M_A_CK_DP0")
	)
	(segment
		(start 102.5144 -45.7708)
		(end 102.168706 -46.116494)
		(width 0.1016)
		(layer "F.Cu")
		(net "M_A_CK_DP0")
	)
	(via
		(at 102.5144 -45.7708)
		(size 0.4318)
		(drill 0.2032)
		(layers "F.Cu" "B.Cu")
		(net "M_A_CK_DP0")
	)
	(via
		(at 154.923998 -64.034924)
		(size 0.4318)
		(drill 0.2032)
		(layers "F.Cu" "B.Cu")
		(net "M_A_CK_DP0")
	)
	(segment
		(start 154.59456 -63.506858)
		(end 154.59456 -63.879222)
		(width 0.2159)
		(layer "B.Cu")
		(net "M_A_CK_DP0")
	)
	(segment
		(start 154.59456 -63.879222)
		(end 154.750262 -64.034924)
		(width 0.2159)
		(layer "B.Cu")
		(net "M_A_CK_DP0")
	)
	(segment
		(start 154.750008 -62.599824)
		(end 154.750008 -63.35141)
		(width 0.2159)
		(layer "B.Cu")
		(net "M_A_CK_DP0")
	)
	(segment
		(start 154.750262 -64.034924)
		(end 154.923998 -64.034924)
		(width 0.2159)
		(layer "B.Cu")
		(net "M_A_CK_DP0")
	)
	(segment
		(start 154.750008 -63.35141)
		(end 154.59456 -63.506858)
		(width 0.2159)
		(layer "B.Cu")
		(net "M_A_CK_DP0")
	)
	(segment
		(start 114.422936 -51.6255)
		(end 116.7257 -51.6255)
		(width 0.1905)
		(layer "In7.Cu")
		(net "M_A_CK_DP0")
	)
	(segment
		(start 109.190536 -50.5841)
		(end 109.89183 -51.285394)
		(width 0.1905)
		(layer "In7.Cu")
		(net "M_A_CK_DP0")
	)
	(segment
		(start 103.840026 -46.080426)
		(end 104.181402 -46.421802)
		(width 0.1016)
		(layer "In7.Cu")
		(net "M_A_CK_DP0")
	)
	(segment
		(start 108.6104 -50.8)
		(end 108.8263 -50.5841)
		(width 0.1016)
		(layer "In7.Cu")
		(net "M_A_CK_DP0")
	)
	(segment
		(start 157.5308 -59.19216)
		(end 157.75686 -59.41822)
		(width 0.1905)
		(layer "In7.Cu")
		(net "M_A_CK_DP0")
	)
	(segment
		(start 155.998672 -55.888636)
		(end 156.402786 -56.29275)
		(width 0.1905)
		(layer "In7.Cu")
		(net "M_A_CK_DP0")
	)
	(segment
		(start 104.994202 -46.421802)
		(end 105.283 -46.7106)
		(width 0.1016)
		(layer "In7.Cu")
		(net "M_A_CK_DP0")
	)
	(segment
		(start 156.402786 -56.29275)
		(end 156.722572 -56.29275)
		(width 0.1905)
		(layer "In7.Cu")
		(net "M_A_CK_DP0")
	)
	(segment
		(start 157.5308 -62.172088)
		(end 157.5308 -62.797436)
		(width 0.1905)
		(layer "In7.Cu")
		(net "M_A_CK_DP0")
	)
	(segment
		(start 153.406856 -54.82844)
		(end 154.938476 -54.82844)
		(width 0.1905)
		(layer "In7.Cu")
		(net "M_A_CK_DP0")
	)
	(segment
		(start 154.938476 -54.82844)
		(end 155.275026 -55.16499)
		(width 0.1905)
		(layer "In7.Cu")
		(net "M_A_CK_DP0")
	)
	(segment
		(start 106.629962 -50.737516)
		(end 106.629962 -51.740562)
		(width 0.1016)
		(layer "In7.Cu")
		(net "M_A_CK_DP0")
	)
	(segment
		(start 105.283 -46.7106)
		(end 105.283 -49.1236)
		(width 0.1016)
		(layer "In7.Cu")
		(net "M_A_CK_DP0")
	)
	(segment
		(start 143.073882 -49.9491)
		(end 143.607282 -50.4825)
		(width 0.1905)
		(layer "In7.Cu")
		(net "M_A_CK_DP0")
	)
	(segment
		(start 157.75686 -61.374528)
		(end 157.75686 -61.946028)
		(width 0.1905)
		(layer "In7.Cu")
		(net "M_A_CK_DP0")
	)
	(segment
		(start 143.607282 -50.4825)
		(end 149.060916 -50.4825)
		(width 0.1905)
		(layer "In7.Cu")
		(net "M_A_CK_DP0")
	)
	(segment
		(start 108.8263 -50.5841)
		(end 109.190536 -50.5841)
		(width 0.1905)
		(layer "In7.Cu")
		(net "M_A_CK_DP0")
	)
	(segment
		(start 155.594558 -55.16499)
		(end 155.998672 -55.569104)
		(width 0.1905)
		(layer "In7.Cu")
		(net "M_A_CK_DP0")
	)
	(segment
		(start 156.722572 -56.29275)
		(end 157.126686 -56.696864)
		(width 0.1905)
		(layer "In7.Cu")
		(net "M_A_CK_DP0")
	)
	(segment
		(start 114.08283 -51.285394)
		(end 114.422936 -51.6255)
		(width 0.1905)
		(layer "In7.Cu")
		(net "M_A_CK_DP0")
	)
	(segment
		(start 155.210764 -63.7032)
		(end 154.923998 -63.989966)
		(width 0.1905)
		(layer "In7.Cu")
		(net "M_A_CK_DP0")
	)
	(segment
		(start 157.75686 -61.946028)
		(end 157.5308 -62.172088)
		(width 0.1905)
		(layer "In7.Cu")
		(net "M_A_CK_DP0")
	)
	(segment
		(start 149.060916 -50.4825)
		(end 153.406856 -54.82844)
		(width 0.1905)
		(layer "In7.Cu")
		(net "M_A_CK_DP0")
	)
	(segment
		(start 157.5308 -57.420764)
		(end 157.5308 -59.19216)
		(width 0.1905)
		(layer "In7.Cu")
		(net "M_A_CK_DP0")
	)
	(segment
		(start 108.5342 -50.8)
		(end 108.6104 -50.8)
		(width 0.1016)
		(layer "In7.Cu")
		(net "M_A_CK_DP0")
	)
	(segment
		(start 116.7257 -51.6255)
		(end 118.4021 -49.9491)
		(width 0.1905)
		(layer "In7.Cu")
		(net "M_A_CK_DP0")
	)
	(segment
		(start 155.998672 -55.569104)
		(end 155.998672 -55.888636)
		(width 0.1905)
		(layer "In7.Cu")
		(net "M_A_CK_DP0")
	)
	(segment
		(start 105.4227 -50.067972)
		(end 105.595928 -50.2412)
		(width 0.1016)
		(layer "In7.Cu")
		(net "M_A_CK_DP0")
	)
	(segment
		(start 107.3912 -51.943)
		(end 108.5342 -50.8)
		(width 0.1016)
		(layer "In7.Cu")
		(net "M_A_CK_DP0")
	)
	(segment
		(start 157.75686 -59.41822)
		(end 157.75686 -59.98972)
		(width 0.1905)
		(layer "In7.Cu")
		(net "M_A_CK_DP0")
	)
	(segment
		(start 102.5144 -45.7708)
		(end 102.5906 -45.7708)
		(width 0.1016)
		(layer "In7.Cu")
		(net "M_A_CK_DP0")
	)
	(segment
		(start 157.75686 -59.98972)
		(end 157.5308 -60.21578)
		(width 0.1905)
		(layer "In7.Cu")
		(net "M_A_CK_DP0")
	)
	(segment
		(start 105.283 -49.1236)
		(end 105.4227 -49.2633)
		(width 0.1016)
		(layer "In7.Cu")
		(net "M_A_CK_DP0")
	)
	(segment
		(start 157.5308 -60.21578)
		(end 157.5308 -61.148468)
		(width 0.1905)
		(layer "In7.Cu")
		(net "M_A_CK_DP0")
	)
	(segment
		(start 106.629962 -51.740562)
		(end 106.8324 -51.943)
		(width 0.1016)
		(layer "In7.Cu")
		(net "M_A_CK_DP0")
	)
	(segment
		(start 102.900226 -46.080426)
		(end 103.840026 -46.080426)
		(width 0.1016)
		(layer "In7.Cu")
		(net "M_A_CK_DP0")
	)
	(segment
		(start 157.5308 -62.797436)
		(end 156.625036 -63.7032)
		(width 0.1905)
		(layer "In7.Cu")
		(net "M_A_CK_DP0")
	)
	(segment
		(start 118.4021 -49.9491)
		(end 143.073882 -49.9491)
		(width 0.1905)
		(layer "In7.Cu")
		(net "M_A_CK_DP0")
	)
	(segment
		(start 155.275026 -55.16499)
		(end 155.594558 -55.16499)
		(width 0.1905)
		(layer "In7.Cu")
		(net "M_A_CK_DP0")
	)
	(segment
		(start 105.595928 -50.2412)
		(end 106.133646 -50.2412)
		(width 0.1016)
		(layer "In7.Cu")
		(net "M_A_CK_DP0")
	)
	(segment
		(start 106.8324 -51.943)
		(end 107.3912 -51.943)
		(width 0.1016)
		(layer "In7.Cu")
		(net "M_A_CK_DP0")
	)
	(segment
		(start 156.625036 -63.7032)
		(end 155.210764 -63.7032)
		(width 0.1905)
		(layer "In7.Cu")
		(net "M_A_CK_DP0")
	)
	(segment
		(start 102.5906 -45.7708)
		(end 102.900226 -46.080426)
		(width 0.1016)
		(layer "In7.Cu")
		(net "M_A_CK_DP0")
	)
	(segment
		(start 154.923998 -63.989966)
		(end 154.923998 -64.034924)
		(width 0.1905)
		(layer "In7.Cu")
		(net "M_A_CK_DP0")
	)
	(segment
		(start 105.4227 -49.2633)
		(end 105.4227 -50.067972)
		(width 0.1016)
		(layer "In7.Cu")
		(net "M_A_CK_DP0")
	)
	(segment
		(start 104.181402 -46.421802)
		(end 104.994202 -46.421802)
		(width 0.1016)
		(layer "In7.Cu")
		(net "M_A_CK_DP0")
	)
	(segment
		(start 157.126686 -57.01665)
		(end 157.5308 -57.420764)
		(width 0.1905)
		(layer "In7.Cu")
		(net "M_A_CK_DP0")
	)
	(segment
		(start 157.5308 -61.148468)
		(end 157.75686 -61.374528)
		(width 0.1905)
		(layer "In7.Cu")
		(net "M_A_CK_DP0")
	)
	(segment
		(start 157.126686 -56.696864)
		(end 157.126686 -57.01665)
		(width 0.1905)
		(layer "In7.Cu")
		(net "M_A_CK_DP0")
	)
	(segment
		(start 109.89183 -51.285394)
		(end 114.08283 -51.285394)
		(width 0.1905)
		(layer "In7.Cu")
		(net "M_A_CK_DP0")
	)
	(segment
		(start 106.133646 -50.2412)
		(end 106.629962 -50.737516)
		(width 0.1016)
		(layer "In7.Cu")
		(net "M_A_CK_DP0")
	)
	(segment
		(start 154.750008 -1.68402)
		(end 154.750008 -3.18897)
		(width 0.1778)
		(layer "F.Cu")
		(net "M_B_ECC6")
	)
	(segment
		(start 106.142028 -26.241502)
		(end 106.142028 -26.952194)
		(width 0.1016)
		(layer "F.Cu")
		(net "M_B_ECC6")
	)
	(segment
		(start 154.750008 -3.18897)
		(end 154.2542 -3.684778)
		(width 0.1778)
		(layer "F.Cu")
		(net "M_B_ECC6")
	)
	(segment
		(start 106.171746 -24.9301)
		(end 105.7529 -25.348946)
		(width 0.1016)
		(layer "F.Cu")
		(net "M_B_ECC6")
	)
	(segment
		(start 106.2736 -24.9301)
		(end 106.171746 -24.9301)
		(width 0.1016)
		(layer "F.Cu")
		(net "M_B_ECC6")
	)
	(segment
		(start 105.7529 -25.852374)
		(end 106.142028 -26.241502)
		(width 0.1016)
		(layer "F.Cu")
		(net "M_B_ECC6")
	)
	(segment
		(start 105.7529 -25.348946)
		(end 105.7529 -25.852374)
		(width 0.1016)
		(layer "F.Cu")
		(net "M_B_ECC6")
	)
	(via
		(at 154.2542 -3.684778)
		(size 0.4318)
		(drill 0.2032)
		(layers "F.Cu" "B.Cu")
		(net "M_B_ECC6")
	)
	(via
		(at 106.2736 -24.9301)
		(size 0.4318)
		(drill 0.2032)
		(layers "F.Cu" "B.Cu")
		(net "M_B_ECC6")
	)
	(segment
		(start 154.450034 -1.690624)
		(end 154.450034 -2.720594)
		(width 0.1778)
		(layer "B.Cu")
		(net "M_B_ECC6")
	)
	(segment
		(start 154.576018 -3.36296)
		(end 154.2542 -3.684778)
		(width 0.1778)
		(layer "B.Cu")
		(net "M_B_ECC6")
	)
	(segment
		(start 154.450034 -2.720594)
		(end 154.576018 -2.846578)
		(width 0.1778)
		(layer "B.Cu")
		(net "M_B_ECC6")
	)
	(segment
		(start 154.576018 -2.846578)
		(end 154.576018 -3.36296)
		(width 0.1778)
		(layer "B.Cu")
		(net "M_B_ECC6")
	)
	(segment
		(start 152.7556 -18.122138)
		(end 150.583138 -20.2946)
		(width 0.1524)
		(layer "In2.Cu")
		(net "M_B_ECC6")
	)
	(segment
		(start 150.583138 -20.2946)
		(end 125.66904 -20.2946)
		(width 0.1524)
		(layer "In2.Cu")
		(net "M_B_ECC6")
	)
	(segment
		(start 106.2736 -24.9301)
		(end 105.81132 -24.46782)
		(width 0.1016)
		(layer "In2.Cu")
		(net "M_B_ECC6")
	)
	(segment
		(start 154.308556 -4.780534)
		(end 154.308556 -6.549644)
		(width 0.1524)
		(layer "In2.Cu")
		(net "M_B_ECC6")
	)
	(segment
		(start 153.3398 -7.5184)
		(end 153.3398 -8.3312)
		(width 0.1524)
		(layer "In2.Cu")
		(net "M_B_ECC6")
	)
	(segment
		(start 154.2542 -4.726178)
		(end 154.308556 -4.780534)
		(width 0.1524)
		(layer "In2.Cu")
		(net "M_B_ECC6")
	)
	(segment
		(start 154.308556 -6.549644)
		(end 153.3398 -7.5184)
		(width 0.1524)
		(layer "In2.Cu")
		(net "M_B_ECC6")
	)
	(segment
		(start 125.66904 -20.2946)
		(end 123.35764 -22.606)
		(width 0.1524)
		(layer "In2.Cu")
		(net "M_B_ECC6")
	)
	(segment
		(start 153.3398 -8.3312)
		(end 152.7556 -8.9154)
		(width 0.1524)
		(layer "In2.Cu")
		(net "M_B_ECC6")
	)
	(segment
		(start 154.2542 -3.684778)
		(end 154.2542 -4.726178)
		(width 0.1524)
		(layer "In2.Cu")
		(net "M_B_ECC6")
	)
	(segment
		(start 123.35764 -22.606)
		(end 111.1504 -22.606)
		(width 0.1524)
		(layer "In2.Cu")
		(net "M_B_ECC6")
	)
	(segment
		(start 105.81132 -22.9108)
		(end 106.26852 -22.4536)
		(width 0.1016)
		(layer "In2.Cu")
		(net "M_B_ECC6")
	)
	(segment
		(start 106.26852 -22.4536)
		(end 110.998 -22.4536)
		(width 0.1016)
		(layer "In2.Cu")
		(net "M_B_ECC6")
	)
	(segment
		(start 105.81132 -24.46782)
		(end 105.81132 -22.9108)
		(width 0.1016)
		(layer "In2.Cu")
		(net "M_B_ECC6")
	)
	(segment
		(start 152.7556 -8.9154)
		(end 152.7556 -18.122138)
		(width 0.1524)
		(layer "In2.Cu")
		(net "M_B_ECC6")
	)
	(segment
		(start 111.1504 -22.606)
		(end 110.998 -22.4536)
		(width 0.1524)
		(layer "In2.Cu")
		(net "M_B_ECC6")
	)
	(segment
		(start 139.41806 -56.960516)
		(end 139.912344 -57.4548)
		(width 0.254)
		(layer "F.Cu")
		(net "PV_VTT_DDR_R_PG")
	)
	(segment
		(start 139.912344 -57.4548)
		(end 139.91844 -57.4548)
		(width 0.254)
		(layer "F.Cu")
		(net "PV_VTT_DDR_R_PG")
	)
	(segment
		(start 139.91844 -57.4548)
		(end 140.04544 -57.5818)
		(width 0.254)
		(layer "F.Cu")
		(net "PV_VTT_DDR_R_PG")
	)
	(segment
		(start 140.04544 -57.5818)
		(end 140.843 -57.5818)
		(width 0.254)
		(layer "F.Cu")
		(net "PV_VTT_DDR_R_PG")
	)
	(segment
		(start 140.843 -57.5818)
		(end 140.843 -56.8198)
		(width 0.254)
		(layer "F.Cu")
		(net "PV_VTT_DDR_R_PG")
	)
	(segment
		(start 138.86434 -56.960516)
		(end 139.41806 -56.960516)
		(width 0.254)
		(layer "F.Cu")
		(net "PV_VTT_DDR_R_PG")
	)
	(via
		(at 139.91844 -57.4548)
		(size 0.7112)
		(drill 0.3556)
		(layers "F.Cu" "B.Cu")
		(net "PV_VTT_DDR_R_PG")
	)
	(segment
		(start 102.5144 -46.3296)
		(end 102.5144 -46.404022)
		(width 0.1016)
		(layer "F.Cu")
		(net "M_A_CK_DN0")
	)
	(segment
		(start 102.5144 -46.404022)
		(end 102.039928 -46.878494)
		(width 0.1016)
		(layer "F.Cu")
		(net "M_A_CK_DN0")
	)
	(via
		(at 154.813 -64.7446)
		(size 0.4318)
		(drill 0.2032)
		(layers "F.Cu" "B.Cu")
		(net "M_A_CK_DN0")
	)
	(via
		(at 102.5144 -46.3296)
		(size 0.4318)
		(drill 0.2032)
		(layers "F.Cu" "B.Cu")
		(net "M_A_CK_DN0")
	)
	(segment
		(start 154.22626 -64.15786)
		(end 154.813 -64.7446)
		(width 0.2159)
		(layer "B.Cu")
		(net "M_A_CK_DN0")
	)
	(segment
		(start 154.22626 -63.4492)
		(end 154.22626 -64.15786)
		(width 0.2159)
		(layer "B.Cu")
		(net "M_A_CK_DN0")
	)
	(segment
		(start 154.15006 -63.373)
		(end 154.22626 -63.4492)
		(width 0.2159)
		(layer "B.Cu")
		(net "M_A_CK_DN0")
	)
	(segment
		(start 154.15006 -62.599824)
		(end 154.15006 -63.373)
		(width 0.2159)
		(layer "B.Cu")
		(net "M_A_CK_DN0")
	)
	(segment
		(start 102.560374 -46.283626)
		(end 103.755698 -46.283626)
		(width 0.1016)
		(layer "In7.Cu")
		(net "M_A_CK_DN0")
	)
	(segment
		(start 113.909094 -51.704494)
		(end 109.718094 -51.704494)
		(width 0.1905)
		(layer "In7.Cu")
		(net "M_A_CK_DN0")
	)
	(segment
		(start 105.2195 -49.347628)
		(end 105.2195 -50.1523)
		(width 0.1016)
		(layer "In7.Cu")
		(net "M_A_CK_DN0")
	)
	(segment
		(start 153.23312 -55.24754)
		(end 148.88718 -50.9016)
		(width 0.1905)
		(layer "In7.Cu")
		(net "M_A_CK_DN0")
	)
	(segment
		(start 154.485848 -63.83528)
		(end 155.037028 -63.2841)
		(width 0.1905)
		(layer "In7.Cu")
		(net "M_A_CK_DN0")
	)
	(segment
		(start 143.433546 -50.9016)
		(end 142.900146 -50.3682)
		(width 0.1905)
		(layer "In7.Cu")
		(net "M_A_CK_DN0")
	)
	(segment
		(start 109.0168 -51.0032)
		(end 108.8263 -51.0032)
		(width 0.1905)
		(layer "In7.Cu")
		(net "M_A_CK_DN0")
	)
	(segment
		(start 106.049318 -50.4444)
		(end 106.426762 -50.821844)
		(width 0.1016)
		(layer "In7.Cu")
		(net "M_A_CK_DN0")
	)
	(segment
		(start 154.813 -64.7446)
		(end 154.485848 -64.417448)
		(width 0.1905)
		(layer "In7.Cu")
		(net "M_A_CK_DN0")
	)
	(segment
		(start 114.2492 -52.0446)
		(end 113.909094 -51.704494)
		(width 0.1905)
		(layer "In7.Cu")
		(net "M_A_CK_DN0")
	)
	(segment
		(start 106.748072 -52.1462)
		(end 107.475528 -52.1462)
		(width 0.1016)
		(layer "In7.Cu")
		(net "M_A_CK_DN0")
	)
	(segment
		(start 157.1117 -57.5945)
		(end 154.76474 -55.24754)
		(width 0.1905)
		(layer "In7.Cu")
		(net "M_A_CK_DN0")
	)
	(segment
		(start 106.426762 -51.82489)
		(end 106.748072 -52.1462)
		(width 0.1016)
		(layer "In7.Cu")
		(net "M_A_CK_DN0")
	)
	(segment
		(start 116.899436 -52.0446)
		(end 114.2492 -52.0446)
		(width 0.1905)
		(layer "In7.Cu")
		(net "M_A_CK_DN0")
	)
	(segment
		(start 118.575836 -50.3682)
		(end 116.899436 -52.0446)
		(width 0.1905)
		(layer "In7.Cu")
		(net "M_A_CK_DN0")
	)
	(segment
		(start 148.88718 -50.9016)
		(end 143.433546 -50.9016)
		(width 0.1905)
		(layer "In7.Cu")
		(net "M_A_CK_DN0")
	)
	(segment
		(start 103.755698 -46.283626)
		(end 104.097074 -46.625002)
		(width 0.1016)
		(layer "In7.Cu")
		(net "M_A_CK_DN0")
	)
	(segment
		(start 104.909874 -46.625002)
		(end 105.0798 -46.794928)
		(width 0.1016)
		(layer "In7.Cu")
		(net "M_A_CK_DN0")
	)
	(segment
		(start 105.5116 -50.4444)
		(end 106.049318 -50.4444)
		(width 0.1016)
		(layer "In7.Cu")
		(net "M_A_CK_DN0")
	)
	(segment
		(start 106.426762 -50.821844)
		(end 106.426762 -51.82489)
		(width 0.1016)
		(layer "In7.Cu")
		(net "M_A_CK_DN0")
	)
	(segment
		(start 109.718094 -51.704494)
		(end 109.0168 -51.0032)
		(width 0.1905)
		(layer "In7.Cu")
		(net "M_A_CK_DN0")
	)
	(segment
		(start 156.4513 -63.2841)
		(end 157.1117 -62.6237)
		(width 0.1905)
		(layer "In7.Cu")
		(net "M_A_CK_DN0")
	)
	(segment
		(start 157.1117 -62.6237)
		(end 157.1117 -57.5945)
		(width 0.1905)
		(layer "In7.Cu")
		(net "M_A_CK_DN0")
	)
	(segment
		(start 154.76474 -55.24754)
		(end 153.23312 -55.24754)
		(width 0.1905)
		(layer "In7.Cu")
		(net "M_A_CK_DN0")
	)
	(segment
		(start 108.618528 -51.0032)
		(end 108.8263 -51.0032)
		(width 0.1016)
		(layer "In7.Cu")
		(net "M_A_CK_DN0")
	)
	(segment
		(start 154.485848 -64.417448)
		(end 154.485848 -63.83528)
		(width 0.1905)
		(layer "In7.Cu")
		(net "M_A_CK_DN0")
	)
	(segment
		(start 104.097074 -46.625002)
		(end 104.909874 -46.625002)
		(width 0.1016)
		(layer "In7.Cu")
		(net "M_A_CK_DN0")
	)
	(segment
		(start 105.2195 -50.1523)
		(end 105.5116 -50.4444)
		(width 0.1016)
		(layer "In7.Cu")
		(net "M_A_CK_DN0")
	)
	(segment
		(start 105.0798 -49.207928)
		(end 105.2195 -49.347628)
		(width 0.1016)
		(layer "In7.Cu")
		(net "M_A_CK_DN0")
	)
	(segment
		(start 155.037028 -63.2841)
		(end 156.4513 -63.2841)
		(width 0.1905)
		(layer "In7.Cu")
		(net "M_A_CK_DN0")
	)
	(segment
		(start 107.475528 -52.1462)
		(end 108.618528 -51.0032)
		(width 0.1016)
		(layer "In7.Cu")
		(net "M_A_CK_DN0")
	)
	(segment
		(start 105.0798 -46.794928)
		(end 105.0798 -49.207928)
		(width 0.1016)
		(layer "In7.Cu")
		(net "M_A_CK_DN0")
	)
	(segment
		(start 102.5144 -46.3296)
		(end 102.560374 -46.283626)
		(width 0.1016)
		(layer "In7.Cu")
		(net "M_A_CK_DN0")
	)
	(segment
		(start 142.900146 -50.3682)
		(end 118.575836 -50.3682)
		(width 0.1905)
		(layer "In7.Cu")
		(net "M_A_CK_DN0")
	)
	(segment
		(start 160.150048 -1.68402)
		(end 160.150048 -4.983226)
		(width 0.2413)
		(layer "F.Cu")
		(net "M_B_MA5")
	)
	(segment
		(start 101.577648 -29.235654)
		(end 101.943662 -29.601668)
		(width 0.1016)
		(layer "F.Cu")
		(net "M_B_MA5")
	)
	(segment
		(start 101.943662 -29.601668)
		(end 101.943662 -29.606748)
		(width 0.1016)
		(layer "F.Cu")
		(net "M_B_MA5")
	)
	(segment
		(start 160.150048 -4.983226)
		(end 160.274 -5.107178)
		(width 0.2413)
		(layer "F.Cu")
		(net "M_B_MA5")
	)
	(via
		(at 160.274 -5.107178)
		(size 0.4318)
		(drill 0.2032)
		(layers "F.Cu" "B.Cu")
		(net "M_B_MA5")
	)
	(via
		(at 101.943662 -29.606748)
		(size 0.4318)
		(drill 0.2032)
		(layers "F.Cu" "B.Cu")
		(net "M_B_MA5")
	)
	(segment
		(start 160.150048 -9.89076)
		(end 160.150048 -7.698486)
		(width 0.2413)
		(layer "B.Cu")
		(net "M_B_MA5")
	)
	(segment
		(start 159.79902 -7.347458)
		(end 159.79902 -5.889244)
		(width 0.2413)
		(layer "B.Cu")
		(net "M_B_MA5")
	)
	(segment
		(start 160.150048 -7.698486)
		(end 159.79902 -7.347458)
		(width 0.2413)
		(layer "B.Cu")
		(net "M_B_MA5")
	)
	(segment
		(start 160.18637 -5.183378)
		(end 160.1978 -5.183378)
		(width 0.2413)
		(layer "B.Cu")
		(net "M_B_MA5")
	)
	(segment
		(start 160.1978 -5.183378)
		(end 160.274 -5.107178)
		(width 0.2413)
		(layer "B.Cu")
		(net "M_B_MA5")
	)
	(segment
		(start 159.79902 -5.889244)
		(end 159.799528 -5.888736)
		(width 0.2413)
		(layer "B.Cu")
		(net "M_B_MA5")
	)
	(segment
		(start 159.799528 -5.57022)
		(end 160.18637 -5.183378)
		(width 0.2413)
		(layer "B.Cu")
		(net "M_B_MA5")
	)
	(segment
		(start 159.799528 -5.888736)
		(end 159.799528 -5.57022)
		(width 0.2413)
		(layer "B.Cu")
		(net "M_B_MA5")
	)
	(segment
		(start 157.5435 -11.397488)
		(end 157.5435 -13.5763)
		(width 0.1905)
		(layer "In7.Cu")
		(net "M_B_MA5")
	)
	(segment
		(start 159.5882 -9.352788)
		(end 157.5435 -11.397488)
		(width 0.1905)
		(layer "In7.Cu")
		(net "M_B_MA5")
	)
	(segment
		(start 151.680418 -18.956782)
		(end 151.411178 -18.956782)
		(width 0.1905)
		(layer "In7.Cu")
		(net "M_B_MA5")
	)
	(segment
		(start 151.950166 -18.687034)
		(end 151.680418 -18.956782)
		(width 0.1905)
		(layer "In7.Cu")
		(net "M_B_MA5")
	)
	(segment
		(start 153.358088 -16.591788)
		(end 153.088848 -16.591788)
		(width 0.1905)
		(layer "In7.Cu")
		(net "M_B_MA5")
	)
	(segment
		(start 152.010872 -17.669764)
		(end 151.741124 -17.939512)
		(width 0.1905)
		(layer "In7.Cu")
		(net "M_B_MA5")
	)
	(segment
		(start 103.605838 -27.676602)
		(end 101.943662 -29.338778)
		(width 0.1016)
		(layer "In7.Cu")
		(net "M_B_MA5")
	)
	(segment
		(start 160.274 -5.131562)
		(end 159.774128 -5.631434)
		(width 0.1905)
		(layer "In7.Cu")
		(net "M_B_MA5")
	)
	(segment
		(start 151.741124 -18.208752)
		(end 151.950166 -18.417794)
		(width 0.1905)
		(layer "In7.Cu")
		(net "M_B_MA5")
	)
	(segment
		(start 112.22228 -24.0792)
		(end 110.363 -24.0792)
		(width 0.1905)
		(layer "In7.Cu")
		(net "M_B_MA5")
	)
	(segment
		(start 152.8191 -17.130776)
		(end 153.028142 -17.339818)
		(width 0.1905)
		(layer "In7.Cu")
		(net "M_B_MA5")
	)
	(segment
		(start 152.8191 -16.861536)
		(end 152.8191 -17.130776)
		(width 0.1905)
		(layer "In7.Cu")
		(net "M_B_MA5")
	)
	(segment
		(start 154.106118 -16.531082)
		(end 153.83637 -16.80083)
		(width 0.1905)
		(layer "In7.Cu")
		(net "M_B_MA5")
	)
	(segment
		(start 151.741124 -17.939512)
		(end 151.741124 -18.208752)
		(width 0.1905)
		(layer "In7.Cu")
		(net "M_B_MA5")
	)
	(segment
		(start 152.489154 -17.878806)
		(end 152.280112 -17.669764)
		(width 0.1905)
		(layer "In7.Cu")
		(net "M_B_MA5")
	)
	(segment
		(start 159.77362 -5.87883)
		(end 159.77362 -6.801358)
		(width 0.1905)
		(layer "In7.Cu")
		(net "M_B_MA5")
	)
	(segment
		(start 154.166824 -15.513812)
		(end 153.897076 -15.78356)
		(width 0.1905)
		(layer "In7.Cu")
		(net "M_B_MA5")
	)
	(segment
		(start 159.77362 -6.801358)
		(end 159.5882 -6.986778)
		(width 0.1905)
		(layer "In7.Cu")
		(net "M_B_MA5")
	)
	(segment
		(start 154.106118 -16.261842)
		(end 154.106118 -16.531082)
		(width 0.1905)
		(layer "In7.Cu")
		(net "M_B_MA5")
	)
	(segment
		(start 153.028142 -17.609058)
		(end 152.758394 -17.878806)
		(width 0.1905)
		(layer "In7.Cu")
		(net "M_B_MA5")
	)
	(segment
		(start 151.950166 -18.417794)
		(end 151.950166 -18.687034)
		(width 0.1905)
		(layer "In7.Cu")
		(net "M_B_MA5")
	)
	(segment
		(start 153.83637 -16.80083)
		(end 153.56713 -16.80083)
		(width 0.1905)
		(layer "In7.Cu")
		(net "M_B_MA5")
	)
	(segment
		(start 156.9212 -13.716)
		(end 154.914346 -15.722854)
		(width 0.1905)
		(layer "In7.Cu")
		(net "M_B_MA5")
	)
	(segment
		(start 101.943662 -29.338778)
		(end 101.943662 -29.606748)
		(width 0.1016)
		(layer "In7.Cu")
		(net "M_B_MA5")
	)
	(segment
		(start 151.411178 -18.956782)
		(end 151.202136 -18.74774)
		(width 0.1905)
		(layer "In7.Cu")
		(net "M_B_MA5")
	)
	(segment
		(start 159.774128 -5.878322)
		(end 159.77362 -5.87883)
		(width 0.1905)
		(layer "In7.Cu")
		(net "M_B_MA5")
	)
	(segment
		(start 157.5435 -13.5763)
		(end 157.4038 -13.716)
		(width 0.1905)
		(layer "In7.Cu")
		(net "M_B_MA5")
	)
	(segment
		(start 150.663148 -19.286728)
		(end 150.87219 -19.49577)
		(width 0.1905)
		(layer "In7.Cu")
		(net "M_B_MA5")
	)
	(segment
		(start 154.436064 -15.513812)
		(end 154.166824 -15.513812)
		(width 0.1905)
		(layer "In7.Cu")
		(net "M_B_MA5")
	)
	(segment
		(start 110.363 -24.0792)
		(end 109.6518 -24.7904)
		(width 0.1905)
		(layer "In7.Cu")
		(net "M_B_MA5")
	)
	(segment
		(start 151.202136 -18.74774)
		(end 150.932896 -18.74774)
		(width 0.1905)
		(layer "In7.Cu")
		(net "M_B_MA5")
	)
	(segment
		(start 150.932896 -18.74774)
		(end 150.663148 -19.017488)
		(width 0.1905)
		(layer "In7.Cu")
		(net "M_B_MA5")
	)
	(segment
		(start 154.914346 -15.722854)
		(end 154.645106 -15.722854)
		(width 0.1905)
		(layer "In7.Cu")
		(net "M_B_MA5")
	)
	(segment
		(start 152.280112 -17.669764)
		(end 152.010872 -17.669764)
		(width 0.1905)
		(layer "In7.Cu")
		(net "M_B_MA5")
	)
	(segment
		(start 154.645106 -15.722854)
		(end 154.436064 -15.513812)
		(width 0.1905)
		(layer "In7.Cu")
		(net "M_B_MA5")
	)
	(segment
		(start 157.4038 -13.716)
		(end 156.9212 -13.716)
		(width 0.1905)
		(layer "In7.Cu")
		(net "M_B_MA5")
	)
	(segment
		(start 153.56713 -16.80083)
		(end 153.358088 -16.591788)
		(width 0.1905)
		(layer "In7.Cu")
		(net "M_B_MA5")
	)
	(segment
		(start 150.87219 -19.76501)
		(end 150.4315 -20.2057)
		(width 0.1905)
		(layer "In7.Cu")
		(net "M_B_MA5")
	)
	(segment
		(start 150.4315 -20.2057)
		(end 116.09578 -20.2057)
		(width 0.1905)
		(layer "In7.Cu")
		(net "M_B_MA5")
	)
	(segment
		(start 105.150158 -27.676602)
		(end 103.605838 -27.676602)
		(width 0.1016)
		(layer "In7.Cu")
		(net "M_B_MA5")
	)
	(segment
		(start 109.6518 -24.7904)
		(end 109.22 -25.2222)
		(width 0.1016)
		(layer "In7.Cu")
		(net "M_B_MA5")
	)
	(segment
		(start 150.663148 -19.017488)
		(end 150.663148 -19.286728)
		(width 0.1905)
		(layer "In7.Cu")
		(net "M_B_MA5")
	)
	(segment
		(start 153.028142 -17.339818)
		(end 153.028142 -17.609058)
		(width 0.1905)
		(layer "In7.Cu")
		(net "M_B_MA5")
	)
	(segment
		(start 116.09578 -20.2057)
		(end 112.22228 -24.0792)
		(width 0.1905)
		(layer "In7.Cu")
		(net "M_B_MA5")
	)
	(segment
		(start 150.87219 -19.49577)
		(end 150.87219 -19.76501)
		(width 0.1905)
		(layer "In7.Cu")
		(net "M_B_MA5")
	)
	(segment
		(start 107.60456 -25.2222)
		(end 105.150158 -27.676602)
		(width 0.1016)
		(layer "In7.Cu")
		(net "M_B_MA5")
	)
	(segment
		(start 159.774128 -5.631434)
		(end 159.774128 -5.878322)
		(width 0.1905)
		(layer "In7.Cu")
		(net "M_B_MA5")
	)
	(segment
		(start 153.088848 -16.591788)
		(end 152.8191 -16.861536)
		(width 0.1905)
		(layer "In7.Cu")
		(net "M_B_MA5")
	)
	(segment
		(start 159.5882 -6.986778)
		(end 159.5882 -9.352788)
		(width 0.1905)
		(layer "In7.Cu")
		(net "M_B_MA5")
	)
	(segment
		(start 109.22 -25.2222)
		(end 107.60456 -25.2222)
		(width 0.1016)
		(layer "In7.Cu")
		(net "M_B_MA5")
	)
	(segment
		(start 160.274 -5.107178)
		(end 160.274 -5.131562)
		(width 0.1905)
		(layer "In7.Cu")
		(net "M_B_MA5")
	)
	(segment
		(start 153.897076 -15.78356)
		(end 153.897076 -16.0528)
		(width 0.1905)
		(layer "In7.Cu")
		(net "M_B_MA5")
	)
	(segment
		(start 153.897076 -16.0528)
		(end 154.106118 -16.261842)
		(width 0.1905)
		(layer "In7.Cu")
		(net "M_B_MA5")
	)
	(segment
		(start 152.758394 -17.878806)
		(end 152.489154 -17.878806)
		(width 0.1905)
		(layer "In7.Cu")
		(net "M_B_MA5")
	)
	(segment
		(start 36.37788 -30.05455)
		(end 35.100006 -30.05455)
		(width 0.1397)
		(layer "F.Cu")
		(net "CLK_100M_XDP_R_DN")
	)
	(segment
		(start 30.51175 -21.181314)
		(end 29.442918 -20.112482)
		(width 0.1397)
		(layer "F.Cu")
		(net "CLK_100M_XDP_R_DN")
	)
	(segment
		(start 28.235148 -19.066256)
		(end 28.2448 -19.056604)
		(width 0.1397)
		(layer "F.Cu")
		(net "CLK_100M_XDP_R_DN")
	)
	(segment
		(start 33.53435 -28.488894)
		(end 33.53435 -25.706832)
		(width 0.1397)
		(layer "F.Cu")
		(net "CLK_100M_XDP_R_DN")
	)
	(segment
		(start 30.51175 -22.684232)
		(end 30.51175 -21.181314)
		(width 0.1397)
		(layer "F.Cu")
		(net "CLK_100M_XDP_R_DN")
	)
	(segment
		(start 38.02888 -29.9593)
		(end 38.27018 -30.2006)
		(width 0.1397)
		(layer "F.Cu")
		(net "CLK_100M_XDP_R_DN")
	)
	(segment
		(start 33.53435 -25.706832)
		(end 30.51175 -22.684232)
		(width 0.1397)
		(layer "F.Cu")
		(net "CLK_100M_XDP_R_DN")
	)
	(segment
		(start 28.473654 -20.112482)
		(end 28.235148 -19.873976)
		(width 0.1397)
		(layer "F.Cu")
		(net "CLK_100M_XDP_R_DN")
	)
	(segment
		(start 36.37788 -30.05455)
		(end 37.34435 -30.05455)
		(width 0.1397)
		(layer "F.Cu")
		(net "CLK_100M_XDP_R_DN")
	)
	(segment
		(start 28.2448 -19.056604)
		(end 28.2448 -17.0688)
		(width 0.1397)
		(layer "F.Cu")
		(net "CLK_100M_XDP_R_DN")
	)
	(segment
		(start 29.442918 -20.112482)
		(end 28.473654 -20.112482)
		(width 0.1397)
		(layer "F.Cu")
		(net "CLK_100M_XDP_R_DN")
	)
	(segment
		(start 37.4396 -29.9593)
		(end 38.02888 -29.9593)
		(width 0.1397)
		(layer "F.Cu")
		(net "CLK_100M_XDP_R_DN")
	)
	(segment
		(start 37.34435 -30.05455)
		(end 37.4396 -29.9593)
		(width 0.1397)
		(layer "F.Cu")
		(net "CLK_100M_XDP_R_DN")
	)
	(segment
		(start 35.100006 -30.05455)
		(end 33.53435 -28.488894)
		(width 0.1397)
		(layer "F.Cu")
		(net "CLK_100M_XDP_R_DN")
	)
	(segment
		(start 28.235148 -19.873976)
		(end 28.235148 -19.066256)
		(width 0.1397)
		(layer "F.Cu")
		(net "CLK_100M_XDP_R_DN")
	)
	(via
		(at 28.452318 -14.474952)
		(size 0.7112)
		(drill 0.3556)
		(layers "F.Cu" "B.Cu")
		(net "CLK_100M_XDP_R_DN")
	)
	(via
		(at 38.27018 -30.2006)
		(size 0.508)
		(drill 0.254)
		(layers "F.Cu" "B.Cu")
		(net "CLK_100M_XDP_R_DN")
	)
	(via
		(at 28.2448 -17.0688)
		(size 0.508)
		(drill 0.254)
		(layers "F.Cu" "B.Cu")
		(net "CLK_100M_XDP_R_DN")
	)
	(segment
		(start 37.6936 -29.9339)
		(end 38.00348 -29.9339)
		(width 0.1397)
		(layer "B.Cu")
		(net "CLK_100M_XDP_R_DN")
	)
	(segment
		(start 38.89121 -32.943292)
		(end 38.607492 -32.943292)
		(width 0.1397)
		(layer "B.Cu")
		(net "CLK_100M_XDP_R_DN")
	)
	(segment
		(start 43.475148 -35.7759)
		(end 43.274488 -35.57524)
		(width 0.1397)
		(layer "B.Cu")
		(net "CLK_100M_XDP_R_DN")
	)
	(segment
		(start 38.00348 -29.9339)
		(end 38.27018 -30.2006)
		(width 0.1397)
		(layer "B.Cu")
		(net "CLK_100M_XDP_R_DN")
	)
	(segment
		(start 37.4269 -31.7627)
		(end 37.4269 -30.2006)
		(width 0.1397)
		(layer "B.Cu")
		(net "CLK_100M_XDP_R_DN")
	)
	(segment
		(start 41.4401 -35.7759)
		(end 40.940482 -35.276282)
		(width 0.1397)
		(layer "B.Cu")
		(net "CLK_100M_XDP_R_DN")
	)
	(segment
		(start 45.48124 -35.7759)
		(end 43.475148 -35.7759)
		(width 0.1397)
		(layer "B.Cu")
		(net "CLK_100M_XDP_R_DN")
	)
	(segment
		(start 40.940482 -34.992564)
		(end 40.644318 -34.696146)
		(width 0.1397)
		(layer "B.Cu")
		(net "CLK_100M_XDP_R_DN")
	)
	(segment
		(start 47.658782 -45.66285)
		(end 48.3997 -44.921932)
		(width 0.1397)
		(layer "B.Cu")
		(net "CLK_100M_XDP_R_DN")
	)
	(segment
		(start 42.855388 -35.57524)
		(end 42.654728 -35.7759)
		(width 0.1397)
		(layer "B.Cu")
		(net "CLK_100M_XDP_R_DN")
	)
	(segment
		(start 47.658782 -46.087792)
		(end 47.658782 -45.66285)
		(width 0.1397)
		(layer "B.Cu")
		(net "CLK_100M_XDP_R_DN")
	)
	(segment
		(start 48.2473 -38.54196)
		(end 45.48124 -35.7759)
		(width 0.1397)
		(layer "B.Cu")
		(net "CLK_100M_XDP_R_DN")
	)
	(segment
		(start 40.064182 -34.399982)
		(end 40.064182 -34.11601)
		(width 0.1397)
		(layer "B.Cu")
		(net "CLK_100M_XDP_R_DN")
	)
	(segment
		(start 48.2473 -43.85056)
		(end 48.2473 -38.54196)
		(width 0.1397)
		(layer "B.Cu")
		(net "CLK_100M_XDP_R_DN")
	)
	(segment
		(start 28.452318 -14.474952)
		(end 28.452318 -16.861282)
		(width 0.1397)
		(layer "B.Cu")
		(net "CLK_100M_XDP_R_DN")
	)
	(segment
		(start 39.187628 -33.523428)
		(end 39.187628 -33.23971)
		(width 0.1397)
		(layer "B.Cu")
		(net "CLK_100M_XDP_R_DN")
	)
	(segment
		(start 28.452318 -16.861282)
		(end 28.2448 -17.0688)
		(width 0.1397)
		(layer "B.Cu")
		(net "CLK_100M_XDP_R_DN")
	)
	(segment
		(start 40.940482 -35.276282)
		(end 40.940482 -34.992564)
		(width 0.1397)
		(layer "B.Cu")
		(net "CLK_100M_XDP_R_DN")
	)
	(segment
		(start 37.4269 -30.2006)
		(end 37.6936 -29.9339)
		(width 0.1397)
		(layer "B.Cu")
		(net "CLK_100M_XDP_R_DN")
	)
	(segment
		(start 42.654728 -35.7759)
		(end 41.4401 -35.7759)
		(width 0.1397)
		(layer "B.Cu")
		(net "CLK_100M_XDP_R_DN")
	)
	(segment
		(start 43.274488 -35.57524)
		(end 42.855388 -35.57524)
		(width 0.1397)
		(layer "B.Cu")
		(net "CLK_100M_XDP_R_DN")
	)
	(segment
		(start 48.3997 -44.00296)
		(end 48.2473 -43.85056)
		(width 0.1397)
		(layer "B.Cu")
		(net "CLK_100M_XDP_R_DN")
	)
	(segment
		(start 39.484046 -33.819846)
		(end 39.187628 -33.523428)
		(width 0.1397)
		(layer "B.Cu")
		(net "CLK_100M_XDP_R_DN")
	)
	(segment
		(start 40.644318 -34.696146)
		(end 40.360346 -34.696146)
		(width 0.1397)
		(layer "B.Cu")
		(net "CLK_100M_XDP_R_DN")
	)
	(segment
		(start 40.360346 -34.696146)
		(end 40.064182 -34.399982)
		(width 0.1397)
		(layer "B.Cu")
		(net "CLK_100M_XDP_R_DN")
	)
	(segment
		(start 40.064182 -34.11601)
		(end 39.767764 -33.819846)
		(width 0.1397)
		(layer "B.Cu")
		(net "CLK_100M_XDP_R_DN")
	)
	(segment
		(start 39.187628 -33.23971)
		(end 38.89121 -32.943292)
		(width 0.1397)
		(layer "B.Cu")
		(net "CLK_100M_XDP_R_DN")
	)
	(segment
		(start 38.607492 -32.943292)
		(end 37.4269 -31.7627)
		(width 0.1397)
		(layer "B.Cu")
		(net "CLK_100M_XDP_R_DN")
	)
	(segment
		(start 48.3997 -44.921932)
		(end 48.3997 -44.00296)
		(width 0.1397)
		(layer "B.Cu")
		(net "CLK_100M_XDP_R_DN")
	)
	(segment
		(start 39.767764 -33.819846)
		(end 39.484046 -33.819846)
		(width 0.1397)
		(layer "B.Cu")
		(net "CLK_100M_XDP_R_DN")
	)
	(segment
		(start 99.352608 -47.259494)
		(end 99.352608 -47.246286)
		(width 0.1016)
		(layer "F.Cu")
		(net "M_A_ODT0")
	)
	(segment
		(start 99.352608 -47.246286)
		(end 99.726496 -46.872398)
		(width 0.1016)
		(layer "F.Cu")
		(net "M_A_ODT0")
	)
	(via
		(at 99.726496 -46.872398)
		(size 0.4318)
		(drill 0.2032)
		(layers "F.Cu" "B.Cu")
		(net "M_A_ODT0")
	)
	(via
		(at 150.250144 -69.342)
		(size 0.4318)
		(drill 0.2032)
		(layers "F.Cu" "B.Cu")
		(net "M_A_ODT0")
	)
	(segment
		(start 150.250144 -69.342)
		(end 150.250144 -70.79996)
		(width 0.1778)
		(layer "B.Cu")
		(net "M_A_ODT0")
	)
	(segment
		(start 150.250144 -69.561456)
		(end 150.01494 -69.79666)
		(width 0.1524)
		(layer "In7.Cu")
		(net "M_A_ODT0")
	)
	(segment
		(start 141.5288 -66.2432)
		(end 140.716 -65.4304)
		(width 0.1524)
		(layer "In7.Cu")
		(net "M_A_ODT0")
	)
	(segment
		(start 145.3642 -68.4022)
		(end 145.2118 -68.2498)
		(width 0.1524)
		(layer "In7.Cu")
		(net "M_A_ODT0")
	)
	(segment
		(start 145.8849 -68.5546)
		(end 145.7325 -68.4022)
		(width 0.1524)
		(layer "In7.Cu")
		(net "M_A_ODT0")
	)
	(segment
		(start 144.742662 -67.9196)
		(end 144.463262 -68.199)
		(width 0.1524)
		(layer "In7.Cu")
		(net "M_A_ODT0")
	)
	(segment
		(start 142.757398 -67.427602)
		(end 142.757398 -66.785998)
		(width 0.1524)
		(layer "In7.Cu")
		(net "M_A_ODT0")
	)
	(segment
		(start 145.0594 -67.9196)
		(end 144.742662 -67.9196)
		(width 0.1524)
		(layer "In7.Cu")
		(net "M_A_ODT0")
	)
	(segment
		(start 141.788134 -66.240406)
		(end 141.78534 -66.2432)
		(width 0.1524)
		(layer "In7.Cu")
		(net "M_A_ODT0")
	)
	(segment
		(start 99.5172 -56.896)
		(end 99.0854 -56.4642)
		(width 0.1016)
		(layer "In7.Cu")
		(net "M_A_ODT0")
	)
	(segment
		(start 119.7102 -60.6552)
		(end 119.55145 -60.49645)
		(width 0.1524)
		(layer "In7.Cu")
		(net "M_A_ODT0")
	)
	(segment
		(start 98.750628 -48.768)
		(end 99.0854 -48.768)
		(width 0.1016)
		(layer "In7.Cu")
		(net "M_A_ODT0")
	)
	(segment
		(start 150.250144 -69.342)
		(end 150.250144 -69.561456)
		(width 0.1524)
		(layer "In7.Cu")
		(net "M_A_ODT0")
	)
	(segment
		(start 99.0854 -56.4642)
		(end 99.0854 -51.364134)
		(width 0.1016)
		(layer "In7.Cu")
		(net "M_A_ODT0")
	)
	(segment
		(start 98.524568 -48.99406)
		(end 98.750628 -48.768)
		(width 0.1016)
		(layer "In7.Cu")
		(net "M_A_ODT0")
	)
	(segment
		(start 140.0556 -65.4304)
		(end 139.9032 -65.5828)
		(width 0.1524)
		(layer "In7.Cu")
		(net "M_A_ODT0")
	)
	(segment
		(start 142.757398 -66.785998)
		(end 142.211806 -66.240406)
		(width 0.1524)
		(layer "In7.Cu")
		(net "M_A_ODT0")
	)
	(segment
		(start 135.9154 -60.6552)
		(end 119.7102 -60.6552)
		(width 0.1524)
		(layer "In7.Cu")
		(net "M_A_ODT0")
	)
	(segment
		(start 119.55145 -60.49645)
		(end 102.48265 -60.49645)
		(width 0.1524)
		(layer "In7.Cu")
		(net "M_A_ODT0")
	)
	(segment
		(start 140.532104 -66.681096)
		(end 140.239496 -66.973704)
		(width 0.1524)
		(layer "In7.Cu")
		(net "M_A_ODT0")
	)
	(segment
		(start 99.187 -50.856134)
		(end 98.8822 -50.856134)
		(width 0.1016)
		(layer "In7.Cu")
		(net "M_A_ODT0")
	)
	(segment
		(start 139.9032 -65.8368)
		(end 140.532104 -66.465704)
		(width 0.1524)
		(layer "In7.Cu")
		(net "M_A_ODT0")
	)
	(segment
		(start 143.528796 -68.199)
		(end 142.757398 -67.427602)
		(width 0.1524)
		(layer "In7.Cu")
		(net "M_A_ODT0")
	)
	(segment
		(start 139.065 -63.8048)
		(end 135.9154 -60.6552)
		(width 0.1524)
		(layer "In7.Cu")
		(net "M_A_ODT0")
	)
	(segment
		(start 141.78534 -66.2432)
		(end 141.5288 -66.2432)
		(width 0.1524)
		(layer "In7.Cu")
		(net "M_A_ODT0")
	)
	(segment
		(start 140.716 -65.4304)
		(end 140.0556 -65.4304)
		(width 0.1524)
		(layer "In7.Cu")
		(net "M_A_ODT0")
	)
	(segment
		(start 98.7806 -50.754534)
		(end 98.7806 -50.1396)
		(width 0.1016)
		(layer "In7.Cu")
		(net "M_A_ODT0")
	)
	(segment
		(start 145.2118 -68.2498)
		(end 145.2118 -68.072)
		(width 0.1524)
		(layer "In7.Cu")
		(net "M_A_ODT0")
	)
	(segment
		(start 99.30892 -48.54448)
		(end 99.30892 -47.289974)
		(width 0.1016)
		(layer "In7.Cu")
		(net "M_A_ODT0")
	)
	(segment
		(start 150.01494 -69.79666)
		(end 146.0373 -69.79666)
		(width 0.1524)
		(layer "In7.Cu")
		(net "M_A_ODT0")
	)
	(segment
		(start 99.2886 -50.957734)
		(end 99.187 -50.856134)
		(width 0.1016)
		(layer "In7.Cu")
		(net "M_A_ODT0")
	)
	(segment
		(start 145.2118 -68.072)
		(end 145.0594 -67.9196)
		(width 0.1524)
		(layer "In7.Cu")
		(net "M_A_ODT0")
	)
	(segment
		(start 102.48265 -60.49645)
		(end 99.5172 -57.531)
		(width 0.1524)
		(layer "In7.Cu")
		(net "M_A_ODT0")
	)
	(segment
		(start 99.5172 -57.531)
		(end 99.5172 -56.896)
		(width 0.1016)
		(layer "In7.Cu")
		(net "M_A_ODT0")
	)
	(segment
		(start 145.8849 -69.64426)
		(end 145.8849 -68.5546)
		(width 0.1524)
		(layer "In7.Cu")
		(net "M_A_ODT0")
	)
	(segment
		(start 99.30892 -47.289974)
		(end 99.726496 -46.872398)
		(width 0.1016)
		(layer "In7.Cu")
		(net "M_A_ODT0")
	)
	(segment
		(start 99.2886 -51.160934)
		(end 99.2886 -50.957734)
		(width 0.1016)
		(layer "In7.Cu")
		(net "M_A_ODT0")
	)
	(segment
		(start 146.0373 -69.79666)
		(end 145.8849 -69.64426)
		(width 0.1524)
		(layer "In7.Cu")
		(net "M_A_ODT0")
	)
	(segment
		(start 98.524568 -49.883568)
		(end 98.524568 -48.99406)
		(width 0.1016)
		(layer "In7.Cu")
		(net "M_A_ODT0")
	)
	(segment
		(start 139.065 -66.0146)
		(end 139.065 -63.8048)
		(width 0.1524)
		(layer "In7.Cu")
		(net "M_A_ODT0")
	)
	(segment
		(start 98.8822 -50.856134)
		(end 98.7806 -50.754534)
		(width 0.1016)
		(layer "In7.Cu")
		(net "M_A_ODT0")
	)
	(segment
		(start 140.239496 -66.973704)
		(end 140.024104 -66.973704)
		(width 0.1524)
		(layer "In7.Cu")
		(net "M_A_ODT0")
	)
	(segment
		(start 145.7325 -68.4022)
		(end 145.3642 -68.4022)
		(width 0.1524)
		(layer "In7.Cu")
		(net "M_A_ODT0")
	)
	(segment
		(start 140.024104 -66.973704)
		(end 139.065 -66.0146)
		(width 0.1524)
		(layer "In7.Cu")
		(net "M_A_ODT0")
	)
	(segment
		(start 144.463262 -68.199)
		(end 143.528796 -68.199)
		(width 0.1524)
		(layer "In7.Cu")
		(net "M_A_ODT0")
	)
	(segment
		(start 98.7806 -50.1396)
		(end 98.524568 -49.883568)
		(width 0.1016)
		(layer "In7.Cu")
		(net "M_A_ODT0")
	)
	(segment
		(start 99.0854 -51.364134)
		(end 99.2886 -51.160934)
		(width 0.1016)
		(layer "In7.Cu")
		(net "M_A_ODT0")
	)
	(segment
		(start 140.532104 -66.465704)
		(end 140.532104 -66.681096)
		(width 0.1524)
		(layer "In7.Cu")
		(net "M_A_ODT0")
	)
	(segment
		(start 139.9032 -65.5828)
		(end 139.9032 -65.8368)
		(width 0.1524)
		(layer "In7.Cu")
		(net "M_A_ODT0")
	)
	(segment
		(start 99.0854 -48.768)
		(end 99.30892 -48.54448)
		(width 0.1016)
		(layer "In7.Cu")
		(net "M_A_ODT0")
	)
	(segment
		(start 142.211806 -66.240406)
		(end 141.788134 -66.240406)
		(width 0.1524)
		(layer "In7.Cu")
		(net "M_A_ODT0")
	)
	(segment
		(start 183.08574 -3.098038)
		(end 183.08574 -3.555238)
		(width 0.1778)
		(layer "F.Cu")
		(net "M_B_DQ54")
	)
	(segment
		(start 183.550052 -1.68402)
		(end 183.550052 -2.633726)
		(width 0.1778)
		(layer "F.Cu")
		(net "M_B_DQ54")
	)
	(segment
		(start 183.550052 -2.633726)
		(end 183.08574 -3.098038)
		(width 0.1778)
		(layer "F.Cu")
		(net "M_B_DQ54")
	)
	(segment
		(start 108.433108 -34.996374)
		(end 108.376974 -34.996374)
		(width 0.1016)
		(layer "F.Cu")
		(net "M_B_DQ54")
	)
	(segment
		(start 108.376974 -34.996374)
		(end 107.95 -34.5694)
		(width 0.1016)
		(layer "F.Cu")
		(net "M_B_DQ54")
	)
	(segment
		(start 107.95 -34.5694)
		(end 107.95 -34.3789)
		(width 0.1016)
		(layer "F.Cu")
		(net "M_B_DQ54")
	)
	(segment
		(start 183.08574 -3.555238)
		(end 182.9054 -3.735578)
		(width 0.1778)
		(layer "F.Cu")
		(net "M_B_DQ54")
	)
	(via
		(at 182.9054 -3.735578)
		(size 0.4318)
		(drill 0.2032)
		(layers "F.Cu" "B.Cu")
		(net "M_B_DQ54")
	)
	(via
		(at 107.95 -34.3789)
		(size 0.4318)
		(drill 0.2032)
		(layers "F.Cu" "B.Cu")
		(net "M_B_DQ54")
	)
	(segment
		(start 183.134 -3.519678)
		(end 182.9181 -3.735578)
		(width 0.1778)
		(layer "B.Cu")
		(net "M_B_DQ54")
	)
	(segment
		(start 182.649876 -2.367534)
		(end 183.134 -2.851658)
		(width 0.1778)
		(layer "B.Cu")
		(net "M_B_DQ54")
	)
	(segment
		(start 182.9181 -3.735578)
		(end 182.9054 -3.735578)
		(width 0.1778)
		(layer "B.Cu")
		(net "M_B_DQ54")
	)
	(segment
		(start 183.134 -2.851658)
		(end 183.134 -3.519678)
		(width 0.1778)
		(layer "B.Cu")
		(net "M_B_DQ54")
	)
	(segment
		(start 182.649876 -1.690624)
		(end 182.649876 -2.367534)
		(width 0.1778)
		(layer "B.Cu")
		(net "M_B_DQ54")
	)
	(segment
		(start 129.08407 -34.29)
		(end 128.93167 -34.1376)
		(width 0.1524)
		(layer "In9.Cu")
		(net "M_B_DQ54")
	)
	(segment
		(start 128.62687 -34.1376)
		(end 128.47447 -34.29)
		(width 0.1524)
		(layer "In9.Cu")
		(net "M_B_DQ54")
	)
	(segment
		(start 129.69367 -34.9504)
		(end 129.54127 -35.1028)
		(width 0.1524)
		(layer "In9.Cu")
		(net "M_B_DQ54")
	)
	(segment
		(start 115.257072 -35.4584)
		(end 115.104672 -35.306)
		(width 0.1524)
		(layer "In9.Cu")
		(net "M_B_DQ54")
	)
	(segment
		(start 119.672862 -35.1282)
		(end 118.6942 -35.1282)
		(width 0.1524)
		(layer "In9.Cu")
		(net "M_B_DQ54")
	)
	(segment
		(start 178.50612 -8.287766)
		(end 178.50612 -9.86028)
		(width 0.1524)
		(layer "In9.Cu")
		(net "M_B_DQ54")
	)
	(segment
		(start 182.5371 -4.167378)
		(end 181.8132 -4.167378)
		(width 0.1524)
		(layer "In9.Cu")
		(net "M_B_DQ54")
	)
	(segment
		(start 115.714272 -35.306)
		(end 115.561872 -35.4584)
		(width 0.1524)
		(layer "In9.Cu")
		(net "M_B_DQ54")
	)
	(segment
		(start 114.952272 -34.8996)
		(end 114.2492 -34.8996)
		(width 0.1524)
		(layer "In9.Cu")
		(net "M_B_DQ54")
	)
	(segment
		(start 127.25527 -34.5948)
		(end 127.10287 -34.7472)
		(width 0.1524)
		(layer "In9.Cu")
		(net "M_B_DQ54")
	)
	(segment
		(start 109.634528 -34.120328)
		(end 110.117128 -34.120328)
		(width 0.1016)
		(layer "In9.Cu")
		(net "M_B_DQ54")
	)
	(segment
		(start 109.375956 -34.3789)
		(end 109.634528 -34.120328)
		(width 0.1016)
		(layer "In9.Cu")
		(net "M_B_DQ54")
	)
	(segment
		(start 176.855628 -15.14348)
		(end 158.787846 -33.211262)
		(width 0.1524)
		(layer "In9.Cu")
		(net "M_B_DQ54")
	)
	(segment
		(start 127.86487 -34.7472)
		(end 127.86487 -34.29)
		(width 0.1524)
		(layer "In9.Cu")
		(net "M_B_DQ54")
	)
	(segment
		(start 120.663462 -34.1376)
		(end 120.199658 -34.601658)
		(width 0.1524)
		(layer "In9.Cu")
		(net "M_B_DQ54")
	)
	(segment
		(start 127.10287 -34.7472)
		(end 126.79807 -34.7472)
		(width 0.1524)
		(layer "In9.Cu")
		(net "M_B_DQ54")
	)
	(segment
		(start 126.79807 -34.7472)
		(end 126.64567 -34.5948)
		(width 0.1524)
		(layer "In9.Cu")
		(net "M_B_DQ54")
	)
	(segment
		(start 127.40767 -34.1376)
		(end 127.25527 -34.29)
		(width 0.1524)
		(layer "In9.Cu")
		(net "M_B_DQ54")
	)
	(segment
		(start 110.117128 -34.120328)
		(end 110.363 -34.3662)
		(width 0.1016)
		(layer "In9.Cu")
		(net "M_B_DQ54")
	)
	(segment
		(start 127.71247 -34.1376)
		(end 127.40767 -34.1376)
		(width 0.1524)
		(layer "In9.Cu")
		(net "M_B_DQ54")
	)
	(segment
		(start 116.84 -35.2806)
		(end 116.459 -34.8996)
		(width 0.1524)
		(layer "In9.Cu")
		(net "M_B_DQ54")
	)
	(segment
		(start 179.0192 -7.774686)
		(end 178.50612 -8.287766)
		(width 0.1524)
		(layer "In9.Cu")
		(net "M_B_DQ54")
	)
	(segment
		(start 126.49327 -34.1376)
		(end 120.663462 -34.1376)
		(width 0.1524)
		(layer "In9.Cu")
		(net "M_B_DQ54")
	)
	(segment
		(start 127.86487 -34.29)
		(end 127.71247 -34.1376)
		(width 0.1524)
		(layer "In9.Cu")
		(net "M_B_DQ54")
	)
	(segment
		(start 182.9054 -3.799078)
		(end 182.5371 -4.167378)
		(width 0.1524)
		(layer "In9.Cu")
		(net "M_B_DQ54")
	)
	(segment
		(start 129.84607 -34.1376)
		(end 129.69367 -34.29)
		(width 0.1524)
		(layer "In9.Cu")
		(net "M_B_DQ54")
	)
	(segment
		(start 129.69367 -34.29)
		(end 129.69367 -34.9504)
		(width 0.1524)
		(layer "In9.Cu")
		(net "M_B_DQ54")
	)
	(segment
		(start 129.23647 -35.1028)
		(end 129.08407 -34.9504)
		(width 0.1524)
		(layer "In9.Cu")
		(net "M_B_DQ54")
	)
	(segment
		(start 107.95 -34.3789)
		(end 109.375956 -34.3789)
		(width 0.1016)
		(layer "In9.Cu")
		(net "M_B_DQ54")
	)
	(segment
		(start 138.456924 -34.1376)
		(end 129.84607 -34.1376)
		(width 0.1524)
		(layer "In9.Cu")
		(net "M_B_DQ54")
	)
	(segment
		(start 181.8132 -4.167378)
		(end 179.0192 -6.961378)
		(width 0.1524)
		(layer "In9.Cu")
		(net "M_B_DQ54")
	)
	(segment
		(start 128.32207 -34.8996)
		(end 128.01727 -34.8996)
		(width 0.1524)
		(layer "In9.Cu")
		(net "M_B_DQ54")
	)
	(segment
		(start 120.199404 -34.601658)
		(end 119.672862 -35.1282)
		(width 0.1524)
		(layer "In9.Cu")
		(net "M_B_DQ54")
	)
	(segment
		(start 126.64567 -34.29)
		(end 126.49327 -34.1376)
		(width 0.1524)
		(layer "In9.Cu")
		(net "M_B_DQ54")
	)
	(segment
		(start 117.7036 -34.8996)
		(end 117.3226 -35.2806)
		(width 0.1524)
		(layer "In9.Cu")
		(net "M_B_DQ54")
	)
	(segment
		(start 118.6942 -35.1282)
		(end 118.4656 -34.8996)
		(width 0.1524)
		(layer "In9.Cu")
		(net "M_B_DQ54")
	)
	(segment
		(start 113.7158 -34.3662)
		(end 110.744 -34.3662)
		(width 0.1524)
		(layer "In9.Cu")
		(net "M_B_DQ54")
	)
	(segment
		(start 158.787846 -33.211262)
		(end 139.383262 -33.211262)
		(width 0.1524)
		(layer "In9.Cu")
		(net "M_B_DQ54")
	)
	(segment
		(start 115.866672 -34.8996)
		(end 115.714272 -35.052)
		(width 0.1524)
		(layer "In9.Cu")
		(net "M_B_DQ54")
	)
	(segment
		(start 178.50612 -9.86028)
		(end 176.855628 -11.510772)
		(width 0.1524)
		(layer "In9.Cu")
		(net "M_B_DQ54")
	)
	(segment
		(start 129.54127 -35.1028)
		(end 129.23647 -35.1028)
		(width 0.1524)
		(layer "In9.Cu")
		(net "M_B_DQ54")
	)
	(segment
		(start 115.714272 -35.052)
		(end 115.714272 -35.306)
		(width 0.1524)
		(layer "In9.Cu")
		(net "M_B_DQ54")
	)
	(segment
		(start 128.01727 -34.8996)
		(end 127.86487 -34.7472)
		(width 0.1524)
		(layer "In9.Cu")
		(net "M_B_DQ54")
	)
	(segment
		(start 118.4656 -34.8996)
		(end 117.7036 -34.8996)
		(width 0.1524)
		(layer "In9.Cu")
		(net "M_B_DQ54")
	)
	(segment
		(start 179.0192 -6.961378)
		(end 179.0192 -7.774686)
		(width 0.1524)
		(layer "In9.Cu")
		(net "M_B_DQ54")
	)
	(segment
		(start 120.199658 -34.601658)
		(end 120.199404 -34.601658)
		(width 0.1524)
		(layer "In9.Cu")
		(net "M_B_DQ54")
	)
	(segment
		(start 127.25527 -34.29)
		(end 127.25527 -34.5948)
		(width 0.1524)
		(layer "In9.Cu")
		(net "M_B_DQ54")
	)
	(segment
		(start 110.363 -34.3662)
		(end 110.744 -34.3662)
		(width 0.1016)
		(layer "In9.Cu")
		(net "M_B_DQ54")
	)
	(segment
		(start 129.08407 -34.9504)
		(end 129.08407 -34.29)
		(width 0.1524)
		(layer "In9.Cu")
		(net "M_B_DQ54")
	)
	(segment
		(start 115.104672 -35.306)
		(end 115.104672 -35.052)
		(width 0.1524)
		(layer "In9.Cu")
		(net "M_B_DQ54")
	)
	(segment
		(start 176.855628 -11.510772)
		(end 176.855628 -15.14348)
		(width 0.1524)
		(layer "In9.Cu")
		(net "M_B_DQ54")
	)
	(segment
		(start 128.47447 -34.7472)
		(end 128.32207 -34.8996)
		(width 0.1524)
		(layer "In9.Cu")
		(net "M_B_DQ54")
	)
	(segment
		(start 128.93167 -34.1376)
		(end 128.62687 -34.1376)
		(width 0.1524)
		(layer "In9.Cu")
		(net "M_B_DQ54")
	)
	(segment
		(start 115.104672 -35.052)
		(end 114.952272 -34.8996)
		(width 0.1524)
		(layer "In9.Cu")
		(net "M_B_DQ54")
	)
	(segment
		(start 182.9054 -3.735578)
		(end 182.9054 -3.799078)
		(width 0.1524)
		(layer "In9.Cu")
		(net "M_B_DQ54")
	)
	(segment
		(start 139.383262 -33.211262)
		(end 138.456924 -34.1376)
		(width 0.1524)
		(layer "In9.Cu")
		(net "M_B_DQ54")
	)
	(segment
		(start 115.561872 -35.4584)
		(end 115.257072 -35.4584)
		(width 0.1524)
		(layer "In9.Cu")
		(net "M_B_DQ54")
	)
	(segment
		(start 116.459 -34.8996)
		(end 115.866672 -34.8996)
		(width 0.1524)
		(layer "In9.Cu")
		(net "M_B_DQ54")
	)
	(segment
		(start 114.2492 -34.8996)
		(end 113.7158 -34.3662)
		(width 0.1524)
		(layer "In9.Cu")
		(net "M_B_DQ54")
	)
	(segment
		(start 128.47447 -34.29)
		(end 128.47447 -34.7472)
		(width 0.1524)
		(layer "In9.Cu")
		(net "M_B_DQ54")
	)
	(segment
		(start 117.3226 -35.2806)
		(end 116.84 -35.2806)
		(width 0.1524)
		(layer "In9.Cu")
		(net "M_B_DQ54")
	)
	(segment
		(start 126.64567 -34.5948)
		(end 126.64567 -34.29)
		(width 0.1524)
		(layer "In9.Cu")
		(net "M_B_DQ54")
	)
	(segment
		(start 34.978848 -33.55467)
		(end 36.37788 -33.55467)
		(width 0.1143)
		(layer "F.Cu")
		(net "TDI_56")
	)
	(segment
		(start 33.39973 -35.4965)
		(end 34.476944 -34.419286)
		(width 0.1143)
		(layer "F.Cu")
		(net "TDI_56")
	)
	(segment
		(start 32.4993 -35.4965)
		(end 33.39973 -35.4965)
		(width 0.1143)
		(layer "F.Cu")
		(net "TDI_56")
	)
	(segment
		(start 34.476944 -34.419286)
		(end 34.476944 -34.056574)
		(width 0.1143)
		(layer "F.Cu")
		(net "TDI_56")
	)
	(segment
		(start 32.2072 -35.7886)
		(end 32.4993 -35.4965)
		(width 0.1143)
		(layer "F.Cu")
		(net "TDI_56")
	)
	(segment
		(start 34.476944 -34.056574)
		(end 34.978848 -33.55467)
		(width 0.1143)
		(layer "F.Cu")
		(net "TDI_56")
	)
	(segment
		(start 135.9408 -60.2488)
		(end 135.9662 -60.2234)
		(width 0.254)
		(layer "F.Cu")
		(net "PV_VTT_DDR_REFIN")
	)
	(segment
		(start 135.9662 -59.4868)
		(end 135.9408 -59.4614)
		(width 0.254)
		(layer "F.Cu")
		(net "PV_VTT_DDR_REFIN")
	)
	(segment
		(start 135.9408 -57.462928)
		(end 135.9408 -58.5216)
		(width 0.254)
		(layer "F.Cu")
		(net "PV_VTT_DDR_REFIN")
	)
	(segment
		(start 135.9662 -60.2234)
		(end 135.9662 -59.4868)
		(width 0.254)
		(layer "F.Cu")
		(net "PV_VTT_DDR_REFIN")
	)
	(segment
		(start 135.94334 -57.460388)
		(end 135.9408 -57.462928)
		(width 0.254)
		(layer "F.Cu")
		(net "PV_VTT_DDR_REFIN")
	)
	(segment
		(start 135.001 -60.2488)
		(end 135.9408 -60.2488)
		(width 0.254)
		(layer "F.Cu")
		(net "PV_VTT_DDR_REFIN")
	)
	(segment
		(start 135.9408 -58.5216)
		(end 135.9408 -59.4614)
		(width 0.254)
		(layer "F.Cu")
		(net "PV_VTT_DDR_REFIN")
	)
	(via
		(at 135.9408 -58.5216)
		(size 0.7112)
		(drill 0.3556)
		(layers "F.Cu" "B.Cu")
		(net "PV_VTT_DDR_REFIN")
	)
	(segment
		(start 102.353618 -49.478184)
		(end 102.039928 -49.164494)
		(width 0.1016)
		(layer "F.Cu")
		(net "M_A_CK_DN1")
	)
	(segment
		(start 102.353618 -49.53127)
		(end 102.353618 -49.478184)
		(width 0.1016)
		(layer "F.Cu")
		(net "M_A_CK_DN1")
	)
	(via
		(at 102.353618 -49.53127)
		(size 0.4318)
		(drill 0.2032)
		(layers "F.Cu" "B.Cu")
		(net "M_A_CK_DN1")
	)
	(via
		(at 153.68651 -69.333618)
		(size 0.4318)
		(drill 0.2032)
		(layers "F.Cu" "B.Cu")
		(net "M_A_CK_DN1")
	)
	(segment
		(start 154.005534 -69.895466)
		(end 154.005534 -69.575934)
		(width 0.2159)
		(layer "B.Cu")
		(net "M_A_CK_DN1")
	)
	(segment
		(start 153.850086 -70.050914)
		(end 154.005534 -69.895466)
		(width 0.2159)
		(layer "B.Cu")
		(net "M_A_CK_DN1")
	)
	(segment
		(start 154.005534 -69.575934)
		(end 153.763218 -69.333618)
		(width 0.2159)
		(layer "B.Cu")
		(net "M_A_CK_DN1")
	)
	(segment
		(start 153.763218 -69.333618)
		(end 153.68651 -69.333618)
		(width 0.2159)
		(layer "B.Cu")
		(net "M_A_CK_DN1")
	)
	(segment
		(start 153.850086 -70.79996)
		(end 153.850086 -70.050914)
		(width 0.2159)
		(layer "B.Cu")
		(net "M_A_CK_DN1")
	)
	(segment
		(start 144.99336 -55.761382)
		(end 145.313146 -55.761382)
		(width 0.1905)
		(layer "In7.Cu")
		(net "M_A_CK_DN1")
	)
	(segment
		(start 149.374098 -56.95569)
		(end 149.58949 -56.95569)
		(width 0.1905)
		(layer "In7.Cu")
		(net "M_A_CK_DN1")
	)
	(segment
		(start 149.58949 -56.95569)
		(end 149.913086 -57.279286)
		(width 0.1905)
		(layer "In7.Cu")
		(net "M_A_CK_DN1")
	)
	(segment
		(start 113.76406 -55.5498)
		(end 118.975886 -55.5498)
		(width 0.1905)
		(layer "In7.Cu")
		(net "M_A_CK_DN1")
	)
	(segment
		(start 120.518936 -54.00675)
		(end 122.916696 -54.00675)
		(width 0.1905)
		(layer "In7.Cu")
		(net "M_A_CK_DN1")
	)
	(segment
		(start 144.589246 -55.357268)
		(end 144.99336 -55.761382)
		(width 0.1905)
		(layer "In7.Cu")
		(net "M_A_CK_DN1")
	)
	(segment
		(start 107.79379 -55.5498)
		(end 111.14532 -55.5498)
		(width 0.1905)
		(layer "In7.Cu")
		(net "M_A_CK_DN1")
	)
	(segment
		(start 111.14532 -55.5498)
		(end 111.37138 -55.77586)
		(width 0.1905)
		(layer "In7.Cu")
		(net "M_A_CK_DN1")
	)
	(segment
		(start 151.5364 -65.007236)
		(end 152.162256 -65.633092)
		(width 0.1905)
		(layer "In7.Cu")
		(net "M_A_CK_DN1")
	)
	(segment
		(start 107.0102 -54.76621)
		(end 107.79379 -55.5498)
		(width 0.1905)
		(layer "In7.Cu")
		(net "M_A_CK_DN1")
	)
	(segment
		(start 142.008606 -55.8419)
		(end 142.787878 -55.8419)
		(width 0.1905)
		(layer "In7.Cu")
		(net "M_A_CK_DN1")
	)
	(segment
		(start 141.394942 -54.38775)
		(end 141.585442 -54.57825)
		(width 0.1905)
		(layer "In7.Cu")
		(net "M_A_CK_DN1")
	)
	(segment
		(start 143.939514 -54.38775)
		(end 144.589246 -55.037482)
		(width 0.1905)
		(layer "In7.Cu")
		(net "M_A_CK_DN1")
	)
	(segment
		(start 144.589246 -55.037482)
		(end 144.589246 -55.357268)
		(width 0.1905)
		(layer "In7.Cu")
		(net "M_A_CK_DN1")
	)
	(segment
		(start 118.975886 -55.5498)
		(end 120.518936 -54.00675)
		(width 0.1905)
		(layer "In7.Cu")
		(net "M_A_CK_DN1")
	)
	(segment
		(start 143.185642 -54.57825)
		(end 143.376142 -54.38775)
		(width 0.1905)
		(layer "In7.Cu")
		(net "M_A_CK_DN1")
	)
	(segment
		(start 125.309376 -54.23281)
		(end 125.535436 -54.00675)
		(width 0.1905)
		(layer "In7.Cu")
		(net "M_A_CK_DN1")
	)
	(segment
		(start 149.913086 -57.279286)
		(end 149.913086 -57.494678)
		(width 0.1905)
		(layer "In7.Cu")
		(net "M_A_CK_DN1")
	)
	(segment
		(start 151.5364 -61.984636)
		(end 151.5364 -65.007236)
		(width 0.1905)
		(layer "In7.Cu")
		(net "M_A_CK_DN1")
	)
	(segment
		(start 153.661618 -69.333618)
		(end 153.68651 -69.333618)
		(width 0.1905)
		(layer "In7.Cu")
		(net "M_A_CK_DN1")
	)
	(segment
		(start 129.29235 -54.38775)
		(end 141.394942 -54.38775)
		(width 0.1905)
		(layer "In7.Cu")
		(net "M_A_CK_DN1")
	)
	(segment
		(start 153.0604 -67.440048)
		(end 153.0604 -68.7324)
		(width 0.1905)
		(layer "In7.Cu")
		(net "M_A_CK_DN1")
	)
	(segment
		(start 124.737876 -54.23281)
		(end 125.309376 -54.23281)
		(width 0.1905)
		(layer "In7.Cu")
		(net "M_A_CK_DN1")
	)
	(segment
		(start 153.0604 -68.7324)
		(end 153.661618 -69.333618)
		(width 0.1905)
		(layer "In7.Cu")
		(net "M_A_CK_DN1")
	)
	(segment
		(start 124.511816 -54.00675)
		(end 124.737876 -54.23281)
		(width 0.1905)
		(layer "In7.Cu")
		(net "M_A_CK_DN1")
	)
	(segment
		(start 112.74044 -55.5498)
		(end 112.9665 -55.77586)
		(width 0.1905)
		(layer "In7.Cu")
		(net "M_A_CK_DN1")
	)
	(segment
		(start 148.248878 -58.08091)
		(end 149.374098 -56.95569)
		(width 0.1905)
		(layer "In7.Cu")
		(net "M_A_CK_DN1")
	)
	(segment
		(start 142.787878 -55.8419)
		(end 143.185642 -55.444136)
		(width 0.1905)
		(layer "In7.Cu")
		(net "M_A_CK_DN1")
	)
	(segment
		(start 147.632674 -58.08091)
		(end 148.248878 -58.08091)
		(width 0.1905)
		(layer "In7.Cu")
		(net "M_A_CK_DN1")
	)
	(segment
		(start 104.887268 -53.765196)
		(end 106.141266 -53.765196)
		(width 0.1016)
		(layer "In7.Cu")
		(net "M_A_CK_DN1")
	)
	(segment
		(start 152.162256 -65.633092)
		(end 152.170638 -65.633092)
		(width 0.1905)
		(layer "In7.Cu")
		(net "M_A_CK_DN1")
	)
	(segment
		(start 113.538 -55.77586)
		(end 113.76406 -55.5498)
		(width 0.1905)
		(layer "In7.Cu")
		(net "M_A_CK_DN1")
	)
	(segment
		(start 146.077432 -56.8452)
		(end 146.396964 -56.8452)
		(width 0.1905)
		(layer "In7.Cu")
		(net "M_A_CK_DN1")
	)
	(segment
		(start 143.376142 -54.38775)
		(end 143.939514 -54.38775)
		(width 0.1905)
		(layer "In7.Cu")
		(net "M_A_CK_DN1")
	)
	(segment
		(start 151.710136 -59.469528)
		(end 150.673816 -60.505848)
		(width 0.1905)
		(layer "In7.Cu")
		(net "M_A_CK_DN1")
	)
	(segment
		(start 152.434544 -65.896998)
		(end 152.434544 -65.90538)
		(width 0.1905)
		(layer "In7.Cu")
		(net "M_A_CK_DN1")
	)
	(segment
		(start 145.313146 -55.761382)
		(end 145.71726 -56.165496)
		(width 0.1905)
		(layer "In7.Cu")
		(net "M_A_CK_DN1")
	)
	(segment
		(start 143.185642 -55.444136)
		(end 143.185642 -54.57825)
		(width 0.1905)
		(layer "In7.Cu")
		(net "M_A_CK_DN1")
	)
	(segment
		(start 148.787866 -59.236102)
		(end 149.518624 -59.96686)
		(width 0.1905)
		(layer "In7.Cu")
		(net "M_A_CK_DN1")
	)
	(segment
		(start 107.0102 -54.63413)
		(end 107.0102 -54.76621)
		(width 0.1016)
		(layer "In7.Cu")
		(net "M_A_CK_DN1")
	)
	(segment
		(start 111.37138 -55.77586)
		(end 111.94288 -55.77586)
		(width 0.1905)
		(layer "In7.Cu")
		(net "M_A_CK_DN1")
	)
	(segment
		(start 151.38654 -58.93054)
		(end 151.710136 -59.254136)
		(width 0.1905)
		(layer "In7.Cu")
		(net "M_A_CK_DN1")
	)
	(segment
		(start 150.134828 -59.96686)
		(end 151.171148 -58.93054)
		(width 0.1905)
		(layer "In7.Cu")
		(net "M_A_CK_DN1")
	)
	(segment
		(start 152.434544 -65.90538)
		(end 153.368248 -66.839084)
		(width 0.1905)
		(layer "In7.Cu")
		(net "M_A_CK_DN1")
	)
	(segment
		(start 148.787866 -58.619898)
		(end 148.787866 -59.236102)
		(width 0.1905)
		(layer "In7.Cu")
		(net "M_A_CK_DN1")
	)
	(segment
		(start 112.16894 -55.5498)
		(end 112.74044 -55.5498)
		(width 0.1905)
		(layer "In7.Cu")
		(net "M_A_CK_DN1")
	)
	(segment
		(start 125.535436 -54.00675)
		(end 128.91135 -54.00675)
		(width 0.1905)
		(layer "In7.Cu")
		(net "M_A_CK_DN1")
	)
	(segment
		(start 149.913086 -57.494678)
		(end 148.787866 -58.619898)
		(width 0.1905)
		(layer "In7.Cu")
		(net "M_A_CK_DN1")
	)
	(segment
		(start 111.94288 -55.77586)
		(end 112.16894 -55.5498)
		(width 0.1905)
		(layer "In7.Cu")
		(net "M_A_CK_DN1")
	)
	(segment
		(start 128.91135 -54.00675)
		(end 129.29235 -54.38775)
		(width 0.1905)
		(layer "In7.Cu")
		(net "M_A_CK_DN1")
	)
	(segment
		(start 149.518624 -59.96686)
		(end 150.134828 -59.96686)
		(width 0.1905)
		(layer "In7.Cu")
		(net "M_A_CK_DN1")
	)
	(segment
		(start 153.368248 -67.1322)
		(end 153.0604 -67.440048)
		(width 0.1905)
		(layer "In7.Cu")
		(net "M_A_CK_DN1")
	)
	(segment
		(start 151.710136 -59.254136)
		(end 151.710136 -59.469528)
		(width 0.1905)
		(layer "In7.Cu")
		(net "M_A_CK_DN1")
	)
	(segment
		(start 123.142756 -54.23281)
		(end 123.714256 -54.23281)
		(width 0.1905)
		(layer "In7.Cu")
		(net "M_A_CK_DN1")
	)
	(segment
		(start 146.396964 -56.8452)
		(end 147.632674 -58.08091)
		(width 0.1905)
		(layer "In7.Cu")
		(net "M_A_CK_DN1")
	)
	(segment
		(start 145.71726 -56.165496)
		(end 145.71726 -56.485028)
		(width 0.1905)
		(layer "In7.Cu")
		(net "M_A_CK_DN1")
	)
	(segment
		(start 123.714256 -54.23281)
		(end 123.940316 -54.00675)
		(width 0.1905)
		(layer "In7.Cu")
		(net "M_A_CK_DN1")
	)
	(segment
		(start 123.940316 -54.00675)
		(end 124.511816 -54.00675)
		(width 0.1905)
		(layer "In7.Cu")
		(net "M_A_CK_DN1")
	)
	(segment
		(start 151.171148 -58.93054)
		(end 151.38654 -58.93054)
		(width 0.1905)
		(layer "In7.Cu")
		(net "M_A_CK_DN1")
	)
	(segment
		(start 145.71726 -56.485028)
		(end 146.077432 -56.8452)
		(width 0.1905)
		(layer "In7.Cu")
		(net "M_A_CK_DN1")
	)
	(segment
		(start 102.4636 -49.641252)
		(end 102.4636 -51.341528)
		(width 0.1016)
		(layer "In7.Cu")
		(net "M_A_CK_DN1")
	)
	(segment
		(start 102.4636 -51.341528)
		(end 104.887268 -53.765196)
		(width 0.1016)
		(layer "In7.Cu")
		(net "M_A_CK_DN1")
	)
	(segment
		(start 106.141266 -53.765196)
		(end 107.0102 -54.63413)
		(width 0.1016)
		(layer "In7.Cu")
		(net "M_A_CK_DN1")
	)
	(segment
		(start 141.585442 -55.418736)
		(end 142.008606 -55.8419)
		(width 0.1905)
		(layer "In7.Cu")
		(net "M_A_CK_DN1")
	)
	(segment
		(start 122.916696 -54.00675)
		(end 123.142756 -54.23281)
		(width 0.1905)
		(layer "In7.Cu")
		(net "M_A_CK_DN1")
	)
	(segment
		(start 102.353618 -49.53127)
		(end 102.4636 -49.641252)
		(width 0.1016)
		(layer "In7.Cu")
		(net "M_A_CK_DN1")
	)
	(segment
		(start 141.585442 -54.57825)
		(end 141.585442 -55.418736)
		(width 0.1905)
		(layer "In7.Cu")
		(net "M_A_CK_DN1")
	)
	(segment
		(start 150.673816 -61.122052)
		(end 151.5364 -61.984636)
		(width 0.1905)
		(layer "In7.Cu")
		(net "M_A_CK_DN1")
	)
	(segment
		(start 112.9665 -55.77586)
		(end 113.538 -55.77586)
		(width 0.1905)
		(layer "In7.Cu")
		(net "M_A_CK_DN1")
	)
	(segment
		(start 150.673816 -60.505848)
		(end 150.673816 -61.122052)
		(width 0.1905)
		(layer "In7.Cu")
		(net "M_A_CK_DN1")
	)
	(segment
		(start 152.170638 -65.633092)
		(end 152.434544 -65.896998)
		(width 0.1905)
		(layer "In7.Cu")
		(net "M_A_CK_DN1")
	)
	(segment
		(start 153.368248 -66.839084)
		(end 153.368248 -67.1322)
		(width 0.1905)
		(layer "In7.Cu")
		(net "M_A_CK_DN1")
	)
	(segment
		(start 106.7054 -23.6474)
		(end 106.2482 -23.1902)
		(width 0.1016)
		(layer "F.Cu")
		(net "M_B_ECC7")
	)
	(segment
		(start 106.7054 -26.517346)
		(end 106.7054 -23.6474)
		(width 0.1016)
		(layer "F.Cu")
		(net "M_B_ECC7")
	)
	(segment
		(start 155.349956 -2.95783)
		(end 155.181808 -3.125978)
		(width 0.1778)
		(layer "F.Cu")
		(net "M_B_ECC7")
	)
	(segment
		(start 155.349956 -1.68402)
		(end 155.349956 -2.95783)
		(width 0.1778)
		(layer "F.Cu")
		(net "M_B_ECC7")
	)
	(segment
		(start 106.746548 -26.558494)
		(end 106.7054 -26.517346)
		(width 0.1016)
		(layer "F.Cu")
		(net "M_B_ECC7")
	)
	(via
		(at 155.181808 -3.125978)
		(size 0.4318)
		(drill 0.2032)
		(layers "F.Cu" "B.Cu")
		(net "M_B_ECC7")
	)
	(via
		(at 106.2482 -23.1902)
		(size 0.4318)
		(drill 0.2032)
		(layers "F.Cu" "B.Cu")
		(net "M_B_ECC7")
	)
	(segment
		(start 155.049982 -2.994152)
		(end 155.181808 -3.125978)
		(width 0.1778)
		(layer "B.Cu")
		(net "M_B_ECC7")
	)
	(segment
		(start 155.049982 -1.690624)
		(end 155.049982 -2.994152)
		(width 0.1778)
		(layer "B.Cu")
		(net "M_B_ECC7")
	)
	(segment
		(start 153.3652 -18.3388)
		(end 150.8252 -20.8788)
		(width 0.1524)
		(layer "In2.Cu")
		(net "M_B_ECC7")
	)
	(segment
		(start 106.68 -22.7584)
		(end 106.2482 -23.1902)
		(width 0.1016)
		(layer "In2.Cu")
		(net "M_B_ECC7")
	)
	(segment
		(start 153.8732 -8.6106)
		(end 153.3652 -9.1186)
		(width 0.1524)
		(layer "In2.Cu")
		(net "M_B_ECC7")
	)
	(segment
		(start 155.181808 -3.125978)
		(end 154.7114 -3.596386)
		(width 0.1524)
		(layer "In2.Cu")
		(net "M_B_ECC7")
	)
	(segment
		(start 150.8252 -20.8788)
		(end 125.911102 -20.8788)
		(width 0.1524)
		(layer "In2.Cu")
		(net "M_B_ECC7")
	)
	(segment
		(start 154.9908 -4.243578)
		(end 154.9908 -6.5024)
		(width 0.1524)
		(layer "In2.Cu")
		(net "M_B_ECC7")
	)
	(segment
		(start 154.7114 -3.964178)
		(end 154.9908 -4.243578)
		(width 0.1524)
		(layer "In2.Cu")
		(net "M_B_ECC7")
	)
	(segment
		(start 153.3652 -9.1186)
		(end 153.3652 -18.3388)
		(width 0.1524)
		(layer "In2.Cu")
		(net "M_B_ECC7")
	)
	(segment
		(start 125.911102 -20.8788)
		(end 123.500388 -23.289514)
		(width 0.1524)
		(layer "In2.Cu")
		(net "M_B_ECC7")
	)
	(segment
		(start 111.0488 -23.289514)
		(end 110.517686 -22.7584)
		(width 0.1016)
		(layer "In2.Cu")
		(net "M_B_ECC7")
	)
	(segment
		(start 154.7114 -3.596386)
		(end 154.7114 -3.964178)
		(width 0.1524)
		(layer "In2.Cu")
		(net "M_B_ECC7")
	)
	(segment
		(start 110.517686 -22.7584)
		(end 106.68 -22.7584)
		(width 0.1016)
		(layer "In2.Cu")
		(net "M_B_ECC7")
	)
	(segment
		(start 154.9908 -6.5024)
		(end 153.8732 -7.62)
		(width 0.1524)
		(layer "In2.Cu")
		(net "M_B_ECC7")
	)
	(segment
		(start 123.500388 -23.289514)
		(end 111.0488 -23.289514)
		(width 0.1524)
		(layer "In2.Cu")
		(net "M_B_ECC7")
	)
	(segment
		(start 153.8732 -7.62)
		(end 153.8732 -8.6106)
		(width 0.1524)
		(layer "In2.Cu")
		(net "M_B_ECC7")
	)
	(segment
		(start 34.778442 -26.650442)
		(end 34.671 -26.650442)
		(width 0.1143)
		(layer "F.Cu")
		(net "XDP_DFX_PORT13")
	)
	(segment
		(start 79.601568 -45.036994)
		(end 77.780388 -45.036994)
		(width 0.1143)
		(layer "F.Cu")
		(net "XDP_DFX_PORT13")
	)
	(segment
		(start 36.37788 -27.05481)
		(end 35.18281 -27.05481)
		(width 0.1143)
		(layer "F.Cu")
		(net "XDP_DFX_PORT13")
	)
	(segment
		(start 77.780388 -45.036994)
		(end 76.64323 -46.174152)
		(width 0.1143)
		(layer "F.Cu")
		(net "XDP_DFX_PORT13")
	)
	(segment
		(start 35.18281 -27.05481)
		(end 34.778442 -26.650442)
		(width 0.1143)
		(layer "F.Cu")
		(net "XDP_DFX_PORT13")
	)
	(via
		(at 76.64323 -46.174152)
		(size 0.508)
		(drill 0.254)
		(layers "F.Cu" "B.Cu")
		(net "XDP_DFX_PORT13")
	)
	(via
		(at 33.7566 -26.3398)
		(size 0.7112)
		(drill 0.3556)
		(layers "F.Cu" "B.Cu")
		(net "XDP_DFX_PORT13")
	)
	(via
		(at 34.671 -26.650442)
		(size 0.508)
		(drill 0.254)
		(layers "F.Cu" "B.Cu")
		(net "XDP_DFX_PORT13")
	)
	(segment
		(start 34.360358 -26.3398)
		(end 34.671 -26.650442)
		(width 0.1143)
		(layer "B.Cu")
		(net "XDP_DFX_PORT13")
	)
	(segment
		(start 33.7566 -26.3398)
		(end 34.360358 -26.3398)
		(width 0.1143)
		(layer "B.Cu")
		(net "XDP_DFX_PORT13")
	)
	(segment
		(start 57.373266 -41.70426)
		(end 57.015126 -42.0624)
		(width 0.0889)
		(layer "In7.Cu")
		(net "XDP_DFX_PORT13")
	)
	(segment
		(start 74.27595 -46.129702)
		(end 73.351898 -45.20565)
		(width 0.0889)
		(layer "In7.Cu")
		(net "XDP_DFX_PORT13")
	)
	(segment
		(start 38.41115 -33.94075)
		(end 35.810952 -31.340552)
		(width 0.0889)
		(layer "In7.Cu")
		(net "XDP_DFX_PORT13")
	)
	(segment
		(start 60.246768 -41.70426)
		(end 57.373266 -41.70426)
		(width 0.0889)
		(layer "In7.Cu")
		(net "XDP_DFX_PORT13")
	)
	(segment
		(start 35.810952 -31.340552)
		(end 35.810952 -27.790394)
		(width 0.0889)
		(layer "In7.Cu")
		(net "XDP_DFX_PORT13")
	)
	(segment
		(start 47.605188 -38.42385)
		(end 44.21505 -38.42385)
		(width 0.0889)
		(layer "In7.Cu")
		(net "XDP_DFX_PORT13")
	)
	(segment
		(start 63.956438 -43.18)
		(end 61.722508 -43.18)
		(width 0.0889)
		(layer "In7.Cu")
		(net "XDP_DFX_PORT13")
	)
	(segment
		(start 35.810952 -27.790394)
		(end 34.671 -26.650442)
		(width 0.0889)
		(layer "In7.Cu")
		(net "XDP_DFX_PORT13")
	)
	(segment
		(start 52.717446 -42.0624)
		(end 51.803046 -41.148)
		(width 0.0889)
		(layer "In7.Cu")
		(net "XDP_DFX_PORT13")
	)
	(segment
		(start 50.329338 -41.148)
		(end 47.605188 -38.42385)
		(width 0.0889)
		(layer "In7.Cu")
		(net "XDP_DFX_PORT13")
	)
	(segment
		(start 39.73195 -33.94075)
		(end 38.41115 -33.94075)
		(width 0.0889)
		(layer "In7.Cu")
		(net "XDP_DFX_PORT13")
	)
	(segment
		(start 76.59878 -46.129702)
		(end 74.27595 -46.129702)
		(width 0.0889)
		(layer "In7.Cu")
		(net "XDP_DFX_PORT13")
	)
	(segment
		(start 51.803046 -41.148)
		(end 50.329338 -41.148)
		(width 0.0889)
		(layer "In7.Cu")
		(net "XDP_DFX_PORT13")
	)
	(segment
		(start 73.351898 -45.20565)
		(end 65.982088 -45.20565)
		(width 0.0889)
		(layer "In7.Cu")
		(net "XDP_DFX_PORT13")
	)
	(segment
		(start 44.21505 -38.42385)
		(end 39.73195 -33.94075)
		(width 0.0889)
		(layer "In7.Cu")
		(net "XDP_DFX_PORT13")
	)
	(segment
		(start 76.64323 -46.174152)
		(end 76.59878 -46.129702)
		(width 0.0889)
		(layer "In7.Cu")
		(net "XDP_DFX_PORT13")
	)
	(segment
		(start 57.015126 -42.0624)
		(end 52.717446 -42.0624)
		(width 0.0889)
		(layer "In7.Cu")
		(net "XDP_DFX_PORT13")
	)
	(segment
		(start 65.982088 -45.20565)
		(end 63.956438 -43.18)
		(width 0.0889)
		(layer "In7.Cu")
		(net "XDP_DFX_PORT13")
	)
	(segment
		(start 61.722508 -43.18)
		(end 60.246768 -41.70426)
		(width 0.0889)
		(layer "In7.Cu")
		(net "XDP_DFX_PORT13")
	)
	(via
		(at 34.2392 -41.0972)
		(size 0.7112)
		(drill 0.3556)
		(layers "F.Cu" "B.Cu")
		(net "P1V8_STBY_PG")
	)
	(via
		(at 66.581274 -25.643586)
		(size 0.508)
		(drill 0.254)
		(layers "F.Cu" "B.Cu")
		(net "P1V8_STBY_PG")
	)
	(via
		(at 34.8742 -40.3606)
		(size 0.508)
		(drill 0.254)
		(layers "F.Cu" "B.Cu")
		(net "P1V8_STBY_PG")
	)
	(via
		(at 73.2536 -23.9268)
		(size 0.508)
		(drill 0.254)
		(layers "F.Cu" "B.Cu")
		(net "P1V8_STBY_PG")
	)
	(via
		(at 70.0786 -22.4028)
		(size 0.508)
		(drill 0.254)
		(layers "F.Cu" "B.Cu")
		(net "P1V8_STBY_PG")
	)
	(via
		(at 34.8234 -47.9806)
		(size 0.508)
		(drill 0.254)
		(layers "F.Cu" "B.Cu")
		(net "P1V8_STBY_PG")
	)
	(via
		(at 62.1792 -25.5778)
		(size 0.508)
		(drill 0.254)
		(layers "F.Cu" "B.Cu")
		(net "P1V8_STBY_PG")
	)
	(via
		(at 37.543232 -36.882832)
		(size 0.508)
		(drill 0.254)
		(layers "F.Cu" "B.Cu")
		(net "P1V8_STBY_PG")
	)
	(segment
		(start 34.3662 -48.4378)
		(end 34.8234 -47.9806)
		(width 0.254)
		(layer "B.Cu")
		(net "P1V8_STBY_PG")
	)
	(segment
		(start 73.279 -23.9014)
		(end 73.2536 -23.9268)
		(width 0.254)
		(layer "B.Cu")
		(net "P1V8_STBY_PG")
	)
	(segment
		(start 34.2392 -41.0972)
		(end 34.8742 -40.4622)
		(width 0.254)
		(layer "B.Cu")
		(net "P1V8_STBY_PG")
	)
	(segment
		(start 34.3408 -48.895)
		(end 34.3662 -48.8696)
		(width 0.254)
		(layer "B.Cu")
		(net "P1V8_STBY_PG")
	)
	(segment
		(start 70.108064 -21.38807)
		(end 70.108064 -22.373336)
		(width 0.254)
		(layer "B.Cu")
		(net "P1V8_STBY_PG")
	)
	(segment
		(start 70.108064 -22.373336)
		(end 70.0786 -22.4028)
		(width 0.254)
		(layer "B.Cu")
		(net "P1V8_STBY_PG")
	)
	(segment
		(start 73.279 -23.0124)
		(end 73.279 -23.9014)
		(width 0.254)
		(layer "B.Cu")
		(net "P1V8_STBY_PG")
	)
	(segment
		(start 34.8742 -40.4622)
		(end 34.8742 -40.3606)
		(width 0.254)
		(layer "B.Cu")
		(net "P1V8_STBY_PG")
	)
	(segment
		(start 34.3662 -48.8696)
		(end 34.3662 -48.4378)
		(width 0.254)
		(layer "B.Cu")
		(net "P1V8_STBY_PG")
	)
	(segment
		(start 67.81165 -25.16505)
		(end 70.0786 -22.8981)
		(width 0.254)
		(layer "In2.Cu")
		(net "P1V8_STBY_PG")
	)
	(segment
		(start 34.8742 -40.3606)
		(end 36.5252 -38.7096)
		(width 0.254)
		(layer "In2.Cu")
		(net "P1V8_STBY_PG")
	)
	(segment
		(start 36.5252 -38.7096)
		(end 36.9062 -38.7096)
		(width 0.254)
		(layer "In2.Cu")
		(net "P1V8_STBY_PG")
	)
	(segment
		(start 36.9062 -38.7096)
		(end 37.543232 -38.072568)
		(width 0.254)
		(layer "In2.Cu")
		(net "P1V8_STBY_PG")
	)
	(segment
		(start 67.371214 -25.643586)
		(end 67.81165 -25.20315)
		(width 0.254)
		(layer "In2.Cu")
		(net "P1V8_STBY_PG")
	)
	(segment
		(start 67.81165 -25.20315)
		(end 67.81165 -25.16505)
		(width 0.254)
		(layer "In2.Cu")
		(net "P1V8_STBY_PG")
	)
	(segment
		(start 37.543232 -38.072568)
		(end 37.543232 -36.882832)
		(width 0.254)
		(layer "In2.Cu")
		(net "P1V8_STBY_PG")
	)
	(segment
		(start 66.581274 -25.643586)
		(end 67.371214 -25.643586)
		(width 0.254)
		(layer "In2.Cu")
		(net "P1V8_STBY_PG")
	)
	(segment
		(start 70.0786 -22.8981)
		(end 70.0786 -22.4028)
		(width 0.254)
		(layer "In2.Cu")
		(net "P1V8_STBY_PG")
	)
	(segment
		(start 38.927278 -37.529008)
		(end 38.189408 -37.529008)
		(width 0.254)
		(layer "In4.Cu")
		(net "P1V8_STBY_PG")
	)
	(segment
		(start 52.67706 -34.33064)
		(end 51.4477 -35.56)
		(width 0.254)
		(layer "In4.Cu")
		(net "P1V8_STBY_PG")
	)
	(segment
		(start 48.48225 -35.56)
		(end 46.62805 -37.4142)
		(width 0.254)
		(layer "In4.Cu")
		(net "P1V8_STBY_PG")
	)
	(segment
		(start 39.78402 -38.38575)
		(end 38.927278 -37.529008)
		(width 0.254)
		(layer "In4.Cu")
		(net "P1V8_STBY_PG")
	)
	(segment
		(start 52.67706 -33.5661)
		(end 52.67706 -34.33064)
		(width 0.254)
		(layer "In4.Cu")
		(net "P1V8_STBY_PG")
	)
	(segment
		(start 56.651144 -29.592016)
		(end 52.67706 -33.5661)
		(width 0.254)
		(layer "In4.Cu")
		(net "P1V8_STBY_PG")
	)
	(segment
		(start 51.4477 -35.56)
		(end 48.48225 -35.56)
		(width 0.254)
		(layer "In4.Cu")
		(net "P1V8_STBY_PG")
	)
	(segment
		(start 38.189408 -37.529008)
		(end 37.543232 -36.882832)
		(width 0.254)
		(layer "In4.Cu")
		(net "P1V8_STBY_PG")
	)
	(segment
		(start 46.62805 -37.982906)
		(end 45.545756 -39.0652)
		(width 0.254)
		(layer "In4.Cu")
		(net "P1V8_STBY_PG")
	)
	(segment
		(start 45.545756 -39.0652)
		(end 44.471844 -39.0652)
		(width 0.254)
		(layer "In4.Cu")
		(net "P1V8_STBY_PG")
	)
	(segment
		(start 43.303444 -37.8968)
		(end 40.83812 -37.8968)
		(width 0.254)
		(layer "In4.Cu")
		(net "P1V8_STBY_PG")
	)
	(segment
		(start 62.1792 -25.5778)
		(end 62.1792 -26.820622)
		(width 0.254)
		(layer "In4.Cu")
		(net "P1V8_STBY_PG")
	)
	(segment
		(start 40.34917 -38.38575)
		(end 39.78402 -38.38575)
		(width 0.254)
		(layer "In4.Cu")
		(net "P1V8_STBY_PG")
	)
	(segment
		(start 59.407806 -29.592016)
		(end 56.651144 -29.592016)
		(width 0.254)
		(layer "In4.Cu")
		(net "P1V8_STBY_PG")
	)
	(segment
		(start 40.83812 -37.8968)
		(end 40.34917 -38.38575)
		(width 0.254)
		(layer "In4.Cu")
		(net "P1V8_STBY_PG")
	)
	(segment
		(start 44.471844 -39.0652)
		(end 43.303444 -37.8968)
		(width 0.254)
		(layer "In4.Cu")
		(net "P1V8_STBY_PG")
	)
	(segment
		(start 62.1792 -26.820622)
		(end 59.407806 -29.592016)
		(width 0.254)
		(layer "In4.Cu")
		(net "P1V8_STBY_PG")
	)
	(segment
		(start 46.62805 -37.4142)
		(end 46.62805 -37.982906)
		(width 0.254)
		(layer "In4.Cu")
		(net "P1V8_STBY_PG")
	)
	(segment
		(start 73.20915 -23.9268)
		(end 73.2536 -23.9268)
		(width 0.254)
		(layer "In7.Cu")
		(net "P1V8_STBY_PG")
	)
	(segment
		(start 73.18375 -23.9522)
		(end 73.20915 -23.9268)
		(width 0.254)
		(layer "In7.Cu")
		(net "P1V8_STBY_PG")
	)
	(segment
		(start 70.0786 -22.4028)
		(end 71.628 -23.9522)
		(width 0.254)
		(layer "In7.Cu")
		(net "P1V8_STBY_PG")
	)
	(segment
		(start 62.1792 -25.5778)
		(end 62.244986 -25.643586)
		(width 0.254)
		(layer "In7.Cu")
		(net "P1V8_STBY_PG")
	)
	(segment
		(start 71.628 -23.9522)
		(end 73.18375 -23.9522)
		(width 0.254)
		(layer "In7.Cu")
		(net "P1V8_STBY_PG")
	)
	(segment
		(start 62.244986 -25.643586)
		(end 66.581274 -25.643586)
		(width 0.254)
		(layer "In7.Cu")
		(net "P1V8_STBY_PG")
	)
	(segment
		(start 33.528 -41.402)
		(end 34.5694 -40.3606)
		(width 0.254)
		(layer "In9.Cu")
		(net "P1V8_STBY_PG")
	)
	(segment
		(start 34.5694 -40.3606)
		(end 34.8742 -40.3606)
		(width 0.254)
		(layer "In9.Cu")
		(net "P1V8_STBY_PG")
	)
	(segment
		(start 33.528 -47.3202)
		(end 33.528 -41.402)
		(width 0.254)
		(layer "In9.Cu")
		(net "P1V8_STBY_PG")
	)
	(segment
		(start 34.8234 -47.9806)
		(end 34.1884 -47.9806)
		(width 0.254)
		(layer "In9.Cu")
		(net "P1V8_STBY_PG")
	)
	(segment
		(start 34.1884 -47.9806)
		(end 33.528 -47.3202)
		(width 0.254)
		(layer "In9.Cu")
		(net "P1V8_STBY_PG")
	)
	(segment
		(start 133.0452 -55.3974)
		(end 132.715 -55.7276)
		(width 0.254)
		(layer "F.Cu")
		(net "PV_VTT_DDR_SNS")
	)
	(segment
		(start 133.0452 -54.737)
		(end 133.0452 -55.3974)
		(width 0.254)
		(layer "F.Cu")
		(net "PV_VTT_DDR_SNS")
	)
	(segment
		(start 134.366 -54.737)
		(end 133.0452 -54.737)
		(width 0.254)
		(layer "F.Cu")
		(net "PV_VTT_DDR_SNS")
	)
	(segment
		(start 135.94334 -55.460392)
		(end 135.724392 -55.460392)
		(width 0.254)
		(layer "F.Cu")
		(net "PV_VTT_DDR_SNS")
	)
	(segment
		(start 135.001 -54.737)
		(end 134.366 -54.737)
		(width 0.254)
		(layer "F.Cu")
		(net "PV_VTT_DDR_SNS")
	)
	(segment
		(start 135.724392 -55.460392)
		(end 135.001 -54.737)
		(width 0.254)
		(layer "F.Cu")
		(net "PV_VTT_DDR_SNS")
	)
	(via
		(at 134.366 -54.737)
		(size 0.7112)
		(drill 0.3556)
		(layers "F.Cu" "B.Cu")
		(net "PV_VTT_DDR_SNS")
	)
	(segment
		(start 110.602268 -48.989234)
		(end 110.623858 -49.010824)
		(width 0.1778)
		(layer "F.Cu")
		(net "M_A_CKE0")
	)
	(segment
		(start 110.623858 -49.010824)
		(end 111.231934 -49.010824)
		(width 0.1778)
		(layer "F.Cu")
		(net "M_A_CKE0")
	)
	(via
		(at 162.2806 -64.721486)
		(size 0.4318)
		(drill 0.2032)
		(layers "F.Cu" "B.Cu")
		(net "M_A_CKE0")
	)
	(via
		(at 111.231934 -49.010824)
		(size 0.4318)
		(drill 0.2032)
		(layers "F.Cu" "B.Cu")
		(net "M_A_CKE0")
	)
	(segment
		(start 161.950146 -63.724282)
		(end 161.808922 -63.865506)
		(width 0.1778)
		(layer "B.Cu")
		(net "M_A_CKE0")
	)
	(segment
		(start 162.229038 -64.669924)
		(end 162.2806 -64.721486)
		(width 0.1778)
		(layer "B.Cu")
		(net "M_A_CKE0")
	)
	(segment
		(start 161.808922 -64.255142)
		(end 162.223704 -64.669924)
		(width 0.1778)
		(layer "B.Cu")
		(net "M_A_CKE0")
	)
	(segment
		(start 162.223704 -64.669924)
		(end 162.229038 -64.669924)
		(width 0.1778)
		(layer "B.Cu")
		(net "M_A_CKE0")
	)
	(segment
		(start 161.808922 -63.865506)
		(end 161.808922 -64.255142)
		(width 0.1778)
		(layer "B.Cu")
		(net "M_A_CKE0")
	)
	(segment
		(start 161.950146 -62.599824)
		(end 161.950146 -63.724282)
		(width 0.1778)
		(layer "B.Cu")
		(net "M_A_CKE0")
	)
	(segment
		(start 132.905754 -47.92345)
		(end 133.29793 -47.92345)
		(width 0.1524)
		(layer "In7.Cu")
		(net "M_A_CKE0")
	)
	(segment
		(start 162.621214 -60.89396)
		(end 162.836606 -60.89396)
		(width 0.1524)
		(layer "In7.Cu")
		(net "M_A_CKE0")
	)
	(segment
		(start 129.64033 -47.92345)
		(end 129.857754 -47.706026)
		(width 0.1524)
		(layer "In7.Cu")
		(net "M_A_CKE0")
	)
	(segment
		(start 162.40506 -60.67806)
		(end 162.621214 -60.89396)
		(width 0.1524)
		(layer "In7.Cu")
		(net "M_A_CKE0")
	)
	(segment
		(start 146.721576 -47.92345)
		(end 147.113752 -47.92345)
		(width 0.1524)
		(layer "In7.Cu")
		(net "M_A_CKE0")
	)
	(segment
		(start 162.40506 -60.462922)
		(end 162.40506 -60.67806)
		(width 0.1524)
		(layer "In7.Cu")
		(net "M_A_CKE0")
	)
	(segment
		(start 153.78811 -50.060352)
		(end 153.600912 -50.247804)
		(width 0.1524)
		(layer "In7.Cu")
		(net "M_A_CKE0")
	)
	(segment
		(start 127.419354 -47.706026)
		(end 127.81153 -47.706026)
		(width 0.1524)
		(layer "In7.Cu")
		(net "M_A_CKE0")
	)
	(segment
		(start 151.259794 -49.816512)
		(end 153.16962 -49.816512)
		(width 0.1524)
		(layer "In7.Cu")
		(net "M_A_CKE0")
	)
	(segment
		(start 142.846552 -47.706026)
		(end 143.063976 -47.92345)
		(width 0.1524)
		(layer "In7.Cu")
		(net "M_A_CKE0")
	)
	(segment
		(start 147.723352 -47.706026)
		(end 147.940776 -47.92345)
		(width 0.1524)
		(layer "In7.Cu")
		(net "M_A_CKE0")
	)
	(segment
		(start 154.434794 -50.491644)
		(end 162.435032 -58.491882)
		(width 0.1524)
		(layer "In7.Cu")
		(net "M_A_CKE0")
	)
	(segment
		(start 144.675352 -47.92345)
		(end 144.892776 -47.706026)
		(width 0.1524)
		(layer "In7.Cu")
		(net "M_A_CKE0")
	)
	(segment
		(start 125.094238 -47.706026)
		(end 126.59233 -47.706026)
		(width 0.1524)
		(layer "In7.Cu")
		(net "M_A_CKE0")
	)
	(segment
		(start 162.836606 -60.89396)
		(end 163.728908 -60.00115)
		(width 0.1524)
		(layer "In7.Cu")
		(net "M_A_CKE0")
	)
	(segment
		(start 162.736022 -64.339978)
		(end 162.354514 -64.721486)
		(width 0.1524)
		(layer "In7.Cu")
		(net "M_A_CKE0")
	)
	(segment
		(start 164.493448 -62.049152)
		(end 162.736022 -63.806578)
		(width 0.1524)
		(layer "In7.Cu")
		(net "M_A_CKE0")
	)
	(segment
		(start 164.493448 -60.550298)
		(end 164.493448 -62.049152)
		(width 0.1524)
		(layer "In7.Cu")
		(net "M_A_CKE0")
	)
	(segment
		(start 163.728908 -60.00115)
		(end 163.9443 -60.00115)
		(width 0.1524)
		(layer "In7.Cu")
		(net "M_A_CKE0")
	)
	(segment
		(start 132.296154 -47.706026)
		(end 132.68833 -47.706026)
		(width 0.1524)
		(layer "In7.Cu")
		(net "M_A_CKE0")
	)
	(segment
		(start 154.219656 -50.491644)
		(end 154.434794 -50.491644)
		(width 0.1524)
		(layer "In7.Cu")
		(net "M_A_CKE0")
	)
	(segment
		(start 146.504152 -47.706026)
		(end 146.721576 -47.92345)
		(width 0.1524)
		(layer "In7.Cu")
		(net "M_A_CKE0")
	)
	(segment
		(start 162.354514 -64.721486)
		(end 162.2806 -64.721486)
		(width 0.1524)
		(layer "In7.Cu")
		(net "M_A_CKE0")
	)
	(segment
		(start 143.673576 -47.706026)
		(end 144.065752 -47.706026)
		(width 0.1524)
		(layer "In7.Cu")
		(net "M_A_CKE0")
	)
	(segment
		(start 153.78811 -49.84496)
		(end 153.78811 -50.060352)
		(width 0.1524)
		(layer "In7.Cu")
		(net "M_A_CKE0")
	)
	(segment
		(start 162.435032 -58.491882)
		(end 162.435032 -58.707274)
		(width 0.1524)
		(layer "In7.Cu")
		(net "M_A_CKE0")
	)
	(segment
		(start 162.866324 -59.138566)
		(end 163.081716 -59.138566)
		(width 0.1524)
		(layer "In7.Cu")
		(net "M_A_CKE0")
	)
	(segment
		(start 144.283176 -47.92345)
		(end 144.675352 -47.92345)
		(width 0.1524)
		(layer "In7.Cu")
		(net "M_A_CKE0")
	)
	(segment
		(start 163.081716 -59.138566)
		(end 163.297616 -59.354466)
		(width 0.1524)
		(layer "In7.Cu")
		(net "M_A_CKE0")
	)
	(segment
		(start 154.032204 -50.679096)
		(end 154.219656 -50.491644)
		(width 0.1524)
		(layer "In7.Cu")
		(net "M_A_CKE0")
	)
	(segment
		(start 153.600912 -50.247804)
		(end 153.600912 -50.463196)
		(width 0.1524)
		(layer "In7.Cu")
		(net "M_A_CKE0")
	)
	(segment
		(start 128.42113 -47.92345)
		(end 128.638554 -47.706026)
		(width 0.1524)
		(layer "In7.Cu")
		(net "M_A_CKE0")
	)
	(segment
		(start 130.24993 -47.706026)
		(end 130.467354 -47.92345)
		(width 0.1524)
		(layer "In7.Cu")
		(net "M_A_CKE0")
	)
	(segment
		(start 144.065752 -47.706026)
		(end 144.283176 -47.92345)
		(width 0.1524)
		(layer "In7.Cu")
		(net "M_A_CKE0")
	)
	(segment
		(start 129.857754 -47.706026)
		(end 130.24993 -47.706026)
		(width 0.1524)
		(layer "In7.Cu")
		(net "M_A_CKE0")
	)
	(segment
		(start 129.03073 -47.706026)
		(end 129.248154 -47.92345)
		(width 0.1524)
		(layer "In7.Cu")
		(net "M_A_CKE0")
	)
	(segment
		(start 133.515354 -47.706026)
		(end 142.846552 -47.706026)
		(width 0.1524)
		(layer "In7.Cu")
		(net "M_A_CKE0")
	)
	(segment
		(start 143.063976 -47.92345)
		(end 143.456152 -47.92345)
		(width 0.1524)
		(layer "In7.Cu")
		(net "M_A_CKE0")
	)
	(segment
		(start 147.940776 -47.92345)
		(end 149.366732 -47.92345)
		(width 0.1524)
		(layer "In7.Cu")
		(net "M_A_CKE0")
	)
	(segment
		(start 127.20193 -47.92345)
		(end 127.419354 -47.706026)
		(width 0.1524)
		(layer "In7.Cu")
		(net "M_A_CKE0")
	)
	(segment
		(start 128.028954 -47.92345)
		(end 128.42113 -47.92345)
		(width 0.1524)
		(layer "In7.Cu")
		(net "M_A_CKE0")
	)
	(segment
		(start 153.600912 -50.463196)
		(end 153.816812 -50.679096)
		(width 0.1524)
		(layer "In7.Cu")
		(net "M_A_CKE0")
	)
	(segment
		(start 132.68833 -47.706026)
		(end 132.905754 -47.92345)
		(width 0.1524)
		(layer "In7.Cu")
		(net "M_A_CKE0")
	)
	(segment
		(start 130.85953 -47.92345)
		(end 131.076954 -47.706026)
		(width 0.1524)
		(layer "In7.Cu")
		(net "M_A_CKE0")
	)
	(segment
		(start 147.113752 -47.92345)
		(end 147.331176 -47.706026)
		(width 0.1524)
		(layer "In7.Cu")
		(net "M_A_CKE0")
	)
	(segment
		(start 149.366732 -47.92345)
		(end 151.259794 -49.816512)
		(width 0.1524)
		(layer "In7.Cu")
		(net "M_A_CKE0")
	)
	(segment
		(start 126.809754 -47.92345)
		(end 127.20193 -47.92345)
		(width 0.1524)
		(layer "In7.Cu")
		(net "M_A_CKE0")
	)
	(segment
		(start 162.317176 -59.472576)
		(end 162.532568 -59.472576)
		(width 0.1524)
		(layer "In7.Cu")
		(net "M_A_CKE0")
	)
	(segment
		(start 132.07873 -47.92345)
		(end 132.296154 -47.706026)
		(width 0.1524)
		(layer "In7.Cu")
		(net "M_A_CKE0")
	)
	(segment
		(start 153.16962 -49.816512)
		(end 153.357072 -49.62906)
		(width 0.1524)
		(layer "In7.Cu")
		(net "M_A_CKE0")
	)
	(segment
		(start 124.759212 -47.371)
		(end 125.094238 -47.706026)
		(width 0.1524)
		(layer "In7.Cu")
		(net "M_A_CKE0")
	)
	(segment
		(start 153.816812 -50.679096)
		(end 154.032204 -50.679096)
		(width 0.1524)
		(layer "In7.Cu")
		(net "M_A_CKE0")
	)
	(segment
		(start 153.57221 -49.62906)
		(end 153.78811 -49.84496)
		(width 0.1524)
		(layer "In7.Cu")
		(net "M_A_CKE0")
	)
	(segment
		(start 144.892776 -47.706026)
		(end 146.504152 -47.706026)
		(width 0.1524)
		(layer "In7.Cu")
		(net "M_A_CKE0")
	)
	(segment
		(start 129.248154 -47.92345)
		(end 129.64033 -47.92345)
		(width 0.1524)
		(layer "In7.Cu")
		(net "M_A_CKE0")
	)
	(segment
		(start 131.46913 -47.706026)
		(end 131.686554 -47.92345)
		(width 0.1524)
		(layer "In7.Cu")
		(net "M_A_CKE0")
	)
	(segment
		(start 153.357072 -49.62906)
		(end 153.57221 -49.62906)
		(width 0.1524)
		(layer "In7.Cu")
		(net "M_A_CKE0")
	)
	(segment
		(start 162.435032 -58.707274)
		(end 162.101276 -59.041284)
		(width 0.1524)
		(layer "In7.Cu")
		(net "M_A_CKE0")
	)
	(segment
		(start 163.9443 -60.00115)
		(end 164.493448 -60.550298)
		(width 0.1524)
		(layer "In7.Cu")
		(net "M_A_CKE0")
	)
	(segment
		(start 162.736022 -63.806578)
		(end 162.736022 -64.339978)
		(width 0.1524)
		(layer "In7.Cu")
		(net "M_A_CKE0")
	)
	(segment
		(start 127.81153 -47.706026)
		(end 128.028954 -47.92345)
		(width 0.1524)
		(layer "In7.Cu")
		(net "M_A_CKE0")
	)
	(segment
		(start 131.686554 -47.92345)
		(end 132.07873 -47.92345)
		(width 0.1524)
		(layer "In7.Cu")
		(net "M_A_CKE0")
	)
	(segment
		(start 163.297616 -59.354466)
		(end 163.297616 -59.569858)
		(width 0.1524)
		(layer "In7.Cu")
		(net "M_A_CKE0")
	)
	(segment
		(start 112.668558 -47.5742)
		(end 120.8532 -47.5742)
		(width 0.1524)
		(layer "In7.Cu")
		(net "M_A_CKE0")
	)
	(segment
		(start 163.297616 -59.569858)
		(end 162.40506 -60.462922)
		(width 0.1524)
		(layer "In7.Cu")
		(net "M_A_CKE0")
	)
	(segment
		(start 128.638554 -47.706026)
		(end 129.03073 -47.706026)
		(width 0.1524)
		(layer "In7.Cu")
		(net "M_A_CKE0")
	)
	(segment
		(start 162.101276 -59.041284)
		(end 162.101276 -59.256676)
		(width 0.1524)
		(layer "In7.Cu")
		(net "M_A_CKE0")
	)
	(segment
		(start 130.467354 -47.92345)
		(end 130.85953 -47.92345)
		(width 0.1524)
		(layer "In7.Cu")
		(net "M_A_CKE0")
	)
	(segment
		(start 126.59233 -47.706026)
		(end 126.809754 -47.92345)
		(width 0.1524)
		(layer "In7.Cu")
		(net "M_A_CKE0")
	)
	(segment
		(start 162.532568 -59.472576)
		(end 162.866324 -59.138566)
		(width 0.1524)
		(layer "In7.Cu")
		(net "M_A_CKE0")
	)
	(segment
		(start 121.0564 -47.371)
		(end 124.759212 -47.371)
		(width 0.1524)
		(layer "In7.Cu")
		(net "M_A_CKE0")
	)
	(segment
		(start 143.456152 -47.92345)
		(end 143.673576 -47.706026)
		(width 0.1524)
		(layer "In7.Cu")
		(net "M_A_CKE0")
	)
	(segment
		(start 131.076954 -47.706026)
		(end 131.46913 -47.706026)
		(width 0.1524)
		(layer "In7.Cu")
		(net "M_A_CKE0")
	)
	(segment
		(start 162.101276 -59.256676)
		(end 162.317176 -59.472576)
		(width 0.1524)
		(layer "In7.Cu")
		(net "M_A_CKE0")
	)
	(segment
		(start 120.8532 -47.5742)
		(end 121.0564 -47.371)
		(width 0.1524)
		(layer "In7.Cu")
		(net "M_A_CKE0")
	)
	(segment
		(start 111.231934 -49.010824)
		(end 112.668558 -47.5742)
		(width 0.1524)
		(layer "In7.Cu")
		(net "M_A_CKE0")
	)
	(segment
		(start 133.29793 -47.92345)
		(end 133.515354 -47.706026)
		(width 0.1524)
		(layer "In7.Cu")
		(net "M_A_CKE0")
	)
	(segment
		(start 147.331176 -47.706026)
		(end 147.723352 -47.706026)
		(width 0.1524)
		(layer "In7.Cu")
		(net "M_A_CKE0")
	)
	(segment
		(start 104.5464 -48.3362)
		(end 104.231694 -48.021494)
		(width 0.1143)
		(layer "F.Cu")
		(net "PWRGD_DDR3_VCCA")
	)
	(segment
		(start 112.141254 -66.19875)
		(end 112.53724 -66.594736)
		(width 0.1143)
		(layer "F.Cu")
		(net "PWRGD_DDR3_VCCA")
	)
	(segment
		(start 112.110012 -66.19875)
		(end 112.141254 -66.19875)
		(width 0.1143)
		(layer "F.Cu")
		(net "PWRGD_DDR3_VCCA")
	)
	(segment
		(start 110.0455 -63.13551)
		(end 111.198406 -63.13551)
		(width 0.1143)
		(layer "F.Cu")
		(net "PWRGD_DDR3_VCCA")
	)
	(segment
		(start 104.648 -48.3362)
		(end 104.5464 -48.3362)
		(width 0.1143)
		(layer "F.Cu")
		(net "PWRGD_DDR3_VCCA")
	)
	(segment
		(start 104.231694 -48.021494)
		(end 104.026208 -48.021494)
		(width 0.1143)
		(layer "F.Cu")
		(net "PWRGD_DDR3_VCCA")
	)
	(segment
		(start 104.587802 -31.902654)
		(end 104.765348 -32.0802)
		(width 0.1143)
		(layer "F.Cu")
		(net "PWRGD_DDR3_VCCA")
	)
	(segment
		(start 111.59617 -63.533274)
		(end 111.59617 -65.684908)
		(width 0.1143)
		(layer "F.Cu")
		(net "PWRGD_DDR3_VCCA")
	)
	(segment
		(start 112.53724 -66.594736)
		(end 112.53724 -66.8655)
		(width 0.1143)
		(layer "F.Cu")
		(net "PWRGD_DDR3_VCCA")
	)
	(segment
		(start 109.22 -62.0903)
		(end 109.2708 -62.1411)
		(width 0.1143)
		(layer "F.Cu")
		(net "PWRGD_DDR3_VCCA")
	)
	(segment
		(start 109.2708 -62.36081)
		(end 110.0455 -63.13551)
		(width 0.1143)
		(layer "F.Cu")
		(net "PWRGD_DDR3_VCCA")
	)
	(segment
		(start 104.6734 -48.3616)
		(end 104.648 -48.3362)
		(width 0.1143)
		(layer "F.Cu")
		(net "PWRGD_DDR3_VCCA")
	)
	(segment
		(start 111.59617 -65.684908)
		(end 112.110012 -66.19875)
		(width 0.1143)
		(layer "F.Cu")
		(net "PWRGD_DDR3_VCCA")
	)
	(segment
		(start 109.2708 -62.1411)
		(end 109.2708 -62.36081)
		(width 0.1143)
		(layer "F.Cu")
		(net "PWRGD_DDR3_VCCA")
	)
	(segment
		(start 104.264968 -31.902654)
		(end 104.587802 -31.902654)
		(width 0.1143)
		(layer "F.Cu")
		(net "PWRGD_DDR3_VCCA")
	)
	(segment
		(start 111.198406 -63.13551)
		(end 111.59617 -63.533274)
		(width 0.1143)
		(layer "F.Cu")
		(net "PWRGD_DDR3_VCCA")
	)
	(via
		(at 109.22 -62.0903)
		(size 0.508)
		(drill 0.254)
		(layers "F.Cu" "B.Cu")
		(net "PWRGD_DDR3_VCCA")
	)
	(via
		(at 104.765348 -32.0802)
		(size 0.4318)
		(drill 0.2032)
		(layers "F.Cu" "B.Cu")
		(net "PWRGD_DDR3_VCCA")
	)
	(via
		(at 108.781088 -60.419488)
		(size 0.7112)
		(drill 0.3556)
		(layers "F.Cu" "B.Cu")
		(net "PWRGD_DDR3_VCCA")
	)
	(via
		(at 104.6734 -48.3616)
		(size 0.4318)
		(drill 0.2032)
		(layers "F.Cu" "B.Cu")
		(net "PWRGD_DDR3_VCCA")
	)
	(segment
		(start 104.3178 -53.6067)
		(end 104.3178 -52.832)
		(width 0.1143)
		(layer "B.Cu")
		(net "PWRGD_DDR3_VCCA")
	)
	(segment
		(start 104.14 -32.197802)
		(end 104.304846 -32.032956)
		(width 0.1143)
		(layer "B.Cu")
		(net "PWRGD_DDR3_VCCA")
	)
	(segment
		(start 109.22 -60.8584)
		(end 108.781088 -60.419488)
		(width 0.1143)
		(layer "B.Cu")
		(net "PWRGD_DDR3_VCCA")
	)
	(segment
		(start 104.718104 -32.032956)
		(end 104.765348 -32.0802)
		(width 0.1143)
		(layer "B.Cu")
		(net "PWRGD_DDR3_VCCA")
	)
	(segment
		(start 104.6734 -48.3616)
		(end 104.6988 -48.3616)
		(width 0.1143)
		(layer "B.Cu")
		(net "PWRGD_DDR3_VCCA")
	)
	(segment
		(start 104.3178 -52.75961)
		(end 104.3178 -52.832)
		(width 0.1143)
		(layer "B.Cu")
		(net "PWRGD_DDR3_VCCA")
	)
	(segment
		(start 105.1179 -56.9087)
		(end 105.1179 -54.4068)
		(width 0.1143)
		(layer "B.Cu")
		(net "PWRGD_DDR3_VCCA")
	)
	(segment
		(start 104.765348 -32.0802)
		(end 104.765348 -32.699452)
		(width 0.1143)
		(layer "B.Cu")
		(net "PWRGD_DDR3_VCCA")
	)
	(segment
		(start 104.6988 -48.3616)
		(end 105.156 -48.8188)
		(width 0.1143)
		(layer "B.Cu")
		(net "PWRGD_DDR3_VCCA")
	)
	(segment
		(start 105.156 -48.8188)
		(end 105.156 -50.092102)
		(width 0.1143)
		(layer "B.Cu")
		(net "PWRGD_DDR3_VCCA")
	)
	(segment
		(start 105.156 -50.092102)
		(end 105.17505 -50.111152)
		(width 0.1143)
		(layer "B.Cu")
		(net "PWRGD_DDR3_VCCA")
	)
	(segment
		(start 104.902 -50.8254)
		(end 104.902 -52.17541)
		(width 0.1143)
		(layer "B.Cu")
		(net "PWRGD_DDR3_VCCA")
	)
	(segment
		(start 109.22 -62.0903)
		(end 109.22 -60.8584)
		(width 0.1143)
		(layer "B.Cu")
		(net "PWRGD_DDR3_VCCA")
	)
	(segment
		(start 105.17505 -50.55235)
		(end 104.902 -50.8254)
		(width 0.1143)
		(layer "B.Cu")
		(net "PWRGD_DDR3_VCCA")
	)
	(segment
		(start 105.17505 -50.111152)
		(end 105.17505 -50.55235)
		(width 0.1143)
		(layer "B.Cu")
		(net "PWRGD_DDR3_VCCA")
	)
	(segment
		(start 108.628688 -60.419488)
		(end 105.1179 -56.9087)
		(width 0.1143)
		(layer "B.Cu")
		(net "PWRGD_DDR3_VCCA")
	)
	(segment
		(start 104.765348 -32.699452)
		(end 104.521 -32.9438)
		(width 0.1143)
		(layer "B.Cu")
		(net "PWRGD_DDR3_VCCA")
	)
	(segment
		(start 104.902 -52.17541)
		(end 104.3178 -52.75961)
		(width 0.1143)
		(layer "B.Cu")
		(net "PWRGD_DDR3_VCCA")
	)
	(segment
		(start 104.304846 -32.032956)
		(end 104.718104 -32.032956)
		(width 0.1143)
		(layer "B.Cu")
		(net "PWRGD_DDR3_VCCA")
	)
	(segment
		(start 108.781088 -60.419488)
		(end 108.628688 -60.419488)
		(width 0.1143)
		(layer "B.Cu")
		(net "PWRGD_DDR3_VCCA")
	)
	(segment
		(start 105.1179 -54.4068)
		(end 104.3178 -53.6067)
		(width 0.1143)
		(layer "B.Cu")
		(net "PWRGD_DDR3_VCCA")
	)
	(segment
		(start 103.310182 -45.19422)
		(end 103.310182 -47.150782)
		(width 0.0889)
		(layer "In2.Cu")
		(net "PWRGD_DDR3_VCCA")
	)
	(segment
		(start 103.4542 -47.2948)
		(end 103.759 -47.2948)
		(width 0.0889)
		(layer "In2.Cu")
		(net "PWRGD_DDR3_VCCA")
	)
	(segment
		(start 100.183442 -42.121074)
		(end 100.175314 -42.129202)
		(width 0.0889)
		(layer "In2.Cu")
		(net "PWRGD_DDR3_VCCA")
	)
	(segment
		(start 101.0031 -43.45813)
		(end 101.0031 -43.679618)
		(width 0.0889)
		(layer "In2.Cu")
		(net "PWRGD_DDR3_VCCA")
	)
	(segment
		(start 104.765348 -32.0802)
		(end 104.6988 -32.146748)
		(width 0.0889)
		(layer "In2.Cu")
		(net "PWRGD_DDR3_VCCA")
	)
	(segment
		(start 104.6988 -33.2232)
		(end 103.6574 -34.2646)
		(width 0.0889)
		(layer "In2.Cu")
		(net "PWRGD_DDR3_VCCA")
	)
	(segment
		(start 103.6574 -34.93516)
		(end 102.283514 -36.309046)
		(width 0.0889)
		(layer "In2.Cu")
		(net "PWRGD_DDR3_VCCA")
	)
	(segment
		(start 99.285806 -38.029388)
		(end 99.285806 -41.21912)
		(width 0.0889)
		(layer "In2.Cu")
		(net "PWRGD_DDR3_VCCA")
	)
	(segment
		(start 104.4194 -48.0822)
		(end 104.6734 -48.3362)
		(width 0.0889)
		(layer "In2.Cu")
		(net "PWRGD_DDR3_VCCA")
	)
	(segment
		(start 99.971606 -41.60901)
		(end 100.183442 -41.820846)
		(width 0.0889)
		(layer "In2.Cu")
		(net "PWRGD_DDR3_VCCA")
	)
	(segment
		(start 104.4194 -47.9552)
		(end 104.4194 -48.0822)
		(width 0.0889)
		(layer "In2.Cu")
		(net "PWRGD_DDR3_VCCA")
	)
	(segment
		(start 101.47427 -44.662852)
		(end 101.769418 -44.958)
		(width 0.0889)
		(layer "In2.Cu")
		(net "PWRGD_DDR3_VCCA")
	)
	(segment
		(start 100.183442 -41.820846)
		(end 100.183442 -42.121074)
		(width 0.0889)
		(layer "In2.Cu")
		(net "PWRGD_DDR3_VCCA")
	)
	(segment
		(start 99.7585 -37.556694)
		(end 99.285806 -38.029388)
		(width 0.0889)
		(layer "In2.Cu")
		(net "PWRGD_DDR3_VCCA")
	)
	(segment
		(start 100.02393 -37.556694)
		(end 99.7585 -37.556694)
		(width 0.0889)
		(layer "In2.Cu")
		(net "PWRGD_DDR3_VCCA")
	)
	(segment
		(start 103.073962 -44.958)
		(end 103.310182 -45.19422)
		(width 0.0889)
		(layer "In2.Cu")
		(net "PWRGD_DDR3_VCCA")
	)
	(segment
		(start 103.759 -47.2948)
		(end 104.4194 -47.9552)
		(width 0.0889)
		(layer "In2.Cu")
		(net "PWRGD_DDR3_VCCA")
	)
	(segment
		(start 99.285806 -41.21912)
		(end 99.675696 -41.60901)
		(width 0.0889)
		(layer "In2.Cu")
		(net "PWRGD_DDR3_VCCA")
	)
	(segment
		(start 102.283514 -36.309046)
		(end 101.006148 -36.309046)
		(width 0.0889)
		(layer "In2.Cu")
		(net "PWRGD_DDR3_VCCA")
	)
	(segment
		(start 101.006148 -36.309046)
		(end 100.235766 -37.079428)
		(width 0.0889)
		(layer "In2.Cu")
		(net "PWRGD_DDR3_VCCA")
	)
	(segment
		(start 103.310182 -47.150782)
		(end 103.4542 -47.2948)
		(width 0.0889)
		(layer "In2.Cu")
		(net "PWRGD_DDR3_VCCA")
	)
	(segment
		(start 104.6734 -48.3362)
		(end 104.6734 -48.3616)
		(width 0.0889)
		(layer "In2.Cu")
		(net "PWRGD_DDR3_VCCA")
	)
	(segment
		(start 100.235766 -37.344858)
		(end 100.02393 -37.556694)
		(width 0.0889)
		(layer "In2.Cu")
		(net "PWRGD_DDR3_VCCA")
	)
	(segment
		(start 103.6574 -34.2646)
		(end 103.6574 -34.93516)
		(width 0.0889)
		(layer "In2.Cu")
		(net "PWRGD_DDR3_VCCA")
	)
	(segment
		(start 104.6988 -32.146748)
		(end 104.6988 -33.2232)
		(width 0.0889)
		(layer "In2.Cu")
		(net "PWRGD_DDR3_VCCA")
	)
	(segment
		(start 99.675696 -41.60901)
		(end 99.971606 -41.60901)
		(width 0.0889)
		(layer "In2.Cu")
		(net "PWRGD_DDR3_VCCA")
	)
	(segment
		(start 101.47427 -44.150788)
		(end 101.47427 -44.662852)
		(width 0.0889)
		(layer "In2.Cu")
		(net "PWRGD_DDR3_VCCA")
	)
	(segment
		(start 100.235766 -37.079428)
		(end 100.235766 -37.344858)
		(width 0.0889)
		(layer "In2.Cu")
		(net "PWRGD_DDR3_VCCA")
	)
	(segment
		(start 101.769418 -44.958)
		(end 103.073962 -44.958)
		(width 0.0889)
		(layer "In2.Cu")
		(net "PWRGD_DDR3_VCCA")
	)
	(segment
		(start 100.175314 -42.129202)
		(end 100.175314 -42.630344)
		(width 0.0889)
		(layer "In2.Cu")
		(net "PWRGD_DDR3_VCCA")
	)
	(segment
		(start 100.175314 -42.630344)
		(end 101.0031 -43.45813)
		(width 0.0889)
		(layer "In2.Cu")
		(net "PWRGD_DDR3_VCCA")
	)
	(segment
		(start 101.0031 -43.679618)
		(end 101.47427 -44.150788)
		(width 0.0889)
		(layer "In2.Cu")
		(net "PWRGD_DDR3_VCCA")
	)
	(segment
		(start 129.943606 -7.700772)
		(end 129.943606 -7.69493)
		(width 0.1778)
		(layer "F.Cu")
		(net "M_B_DQ1")
	)
	(segment
		(start 129.84988 -9.897364)
		(end 129.84988 -7.794498)
		(width 0.1778)
		(layer "F.Cu")
		(net "M_B_DQ1")
	)
	(segment
		(start 129.84988 -7.794498)
		(end 129.943606 -7.700772)
		(width 0.1778)
		(layer "F.Cu")
		(net "M_B_DQ1")
	)
	(segment
		(start 93.243908 -27.300174)
		(end 92.95511 -27.300174)
		(width 0.1016)
		(layer "F.Cu")
		(net "M_B_DQ1")
	)
	(segment
		(start 92.95511 -27.300174)
		(end 92.790264 -27.46502)
		(width 0.1016)
		(layer "F.Cu")
		(net "M_B_DQ1")
	)
	(via
		(at 129.943606 -7.69493)
		(size 0.4318)
		(drill 0.2032)
		(layers "F.Cu" "B.Cu")
		(net "M_B_DQ1")
	)
	(via
		(at 92.790264 -27.46502)
		(size 0.4318)
		(drill 0.2032)
		(layers "F.Cu" "B.Cu")
		(net "M_B_DQ1")
	)
	(segment
		(start 129.8448 -8.536178)
		(end 129.8448 -7.793736)
		(width 0.1778)
		(layer "B.Cu")
		(net "M_B_DQ1")
	)
	(segment
		(start 130.149854 -9.89076)
		(end 130.149854 -8.841232)
		(width 0.1778)
		(layer "B.Cu")
		(net "M_B_DQ1")
	)
	(segment
		(start 129.8448 -7.793736)
		(end 129.943606 -7.69493)
		(width 0.1778)
		(layer "B.Cu")
		(net "M_B_DQ1")
	)
	(segment
		(start 130.149854 -8.841232)
		(end 129.8448 -8.536178)
		(width 0.1778)
		(layer "B.Cu")
		(net "M_B_DQ1")
	)
	(segment
		(start 129.8956 -6.2738)
		(end 129.5654 -6.2738)
		(width 0.1524)
		(layer "In7.Cu")
		(net "M_B_DQ1")
	)
	(segment
		(start 124.1552 -5.5626)
		(end 124.3584 -5.7658)
		(width 0.1524)
		(layer "In7.Cu")
		(net "M_B_DQ1")
	)
	(segment
		(start 127.3048 -7.3152)
		(end 127.889 -6.731)
		(width 0.1524)
		(layer "In7.Cu")
		(net "M_B_DQ1")
	)
	(segment
		(start 116.6876 -7.1755)
		(end 116.6876 -5.7658)
		(width 0.1524)
		(layer "In7.Cu")
		(net "M_B_DQ1")
	)
	(segment
		(start 127.889 -6.731)
		(end 127.889 -5.715)
		(width 0.1524)
		(layer "In7.Cu")
		(net "M_B_DQ1")
	)
	(segment
		(start 124.3584 -7.0866)
		(end 124.587 -7.3152)
		(width 0.1524)
		(layer "In7.Cu")
		(net "M_B_DQ1")
	)
	(segment
		(start 119.111522 -5.715)
		(end 119.111522 -5.9436)
		(width 0.1524)
		(layer "In7.Cu")
		(net "M_B_DQ1")
	)
	(segment
		(start 114.425984 -7.44474)
		(end 116.41836 -7.44474)
		(width 0.1524)
		(layer "In7.Cu")
		(net "M_B_DQ1")
	)
	(segment
		(start 121.702322 -6.096)
		(end 122.007122 -6.096)
		(width 0.1524)
		(layer "In7.Cu")
		(net "M_B_DQ1")
	)
	(segment
		(start 118.654322 -5.5626)
		(end 118.959122 -5.5626)
		(width 0.1524)
		(layer "In7.Cu")
		(net "M_B_DQ1")
	)
	(segment
		(start 120.178322 -5.5626)
		(end 120.330722 -5.715)
		(width 0.1524)
		(layer "In7.Cu")
		(net "M_B_DQ1")
	)
	(segment
		(start 118.349522 -6.096)
		(end 118.501922 -5.9436)
		(width 0.1524)
		(layer "In7.Cu")
		(net "M_B_DQ1")
	)
	(segment
		(start 122.159522 -5.715)
		(end 122.311922 -5.5626)
		(width 0.1524)
		(layer "In7.Cu")
		(net "M_B_DQ1")
	)
	(segment
		(start 119.873522 -5.5626)
		(end 120.178322 -5.5626)
		(width 0.1524)
		(layer "In7.Cu")
		(net "M_B_DQ1")
	)
	(segment
		(start 119.568722 -6.096)
		(end 119.721122 -5.9436)
		(width 0.1524)
		(layer "In7.Cu")
		(net "M_B_DQ1")
	)
	(segment
		(start 118.501922 -5.9436)
		(end 118.501922 -5.715)
		(width 0.1524)
		(layer "In7.Cu")
		(net "M_B_DQ1")
	)
	(segment
		(start 90.4494 -22.0726)
		(end 93.141546 -19.380454)
		(width 0.1016)
		(layer "In7.Cu")
		(net "M_B_DQ1")
	)
	(segment
		(start 119.263922 -6.096)
		(end 119.568722 -6.096)
		(width 0.1524)
		(layer "In7.Cu")
		(net "M_B_DQ1")
	)
	(segment
		(start 119.721122 -5.715)
		(end 119.873522 -5.5626)
		(width 0.1524)
		(layer "In7.Cu")
		(net "M_B_DQ1")
	)
	(segment
		(start 121.549922 -5.715)
		(end 121.549922 -5.9436)
		(width 0.1524)
		(layer "In7.Cu")
		(net "M_B_DQ1")
	)
	(segment
		(start 120.940322 -5.715)
		(end 121.092722 -5.5626)
		(width 0.1524)
		(layer "In7.Cu")
		(net "M_B_DQ1")
	)
	(segment
		(start 129.413 -6.7818)
		(end 129.5654 -6.9342)
		(width 0.1524)
		(layer "In7.Cu")
		(net "M_B_DQ1")
	)
	(segment
		(start 116.8908 -5.5626)
		(end 117.739922 -5.5626)
		(width 0.1524)
		(layer "In7.Cu")
		(net "M_B_DQ1")
	)
	(segment
		(start 118.501922 -5.715)
		(end 118.654322 -5.5626)
		(width 0.1524)
		(layer "In7.Cu")
		(net "M_B_DQ1")
	)
	(segment
		(start 93.673422 -19.380454)
		(end 94.003876 -19.05)
		(width 0.1016)
		(layer "In7.Cu")
		(net "M_B_DQ1")
	)
	(segment
		(start 120.330722 -5.9436)
		(end 120.483122 -6.096)
		(width 0.1524)
		(layer "In7.Cu")
		(net "M_B_DQ1")
	)
	(segment
		(start 117.892322 -5.9436)
		(end 118.044722 -6.096)
		(width 0.1524)
		(layer "In7.Cu")
		(net "M_B_DQ1")
	)
	(segment
		(start 116.6876 -5.7658)
		(end 116.8908 -5.5626)
		(width 0.1524)
		(layer "In7.Cu")
		(net "M_B_DQ1")
	)
	(segment
		(start 122.007122 -6.096)
		(end 122.159522 -5.9436)
		(width 0.1524)
		(layer "In7.Cu")
		(net "M_B_DQ1")
	)
	(segment
		(start 122.159522 -5.9436)
		(end 122.159522 -5.715)
		(width 0.1524)
		(layer "In7.Cu")
		(net "M_B_DQ1")
	)
	(segment
		(start 97.31502 -15.738856)
		(end 106.131868 -15.738856)
		(width 0.1524)
		(layer "In7.Cu")
		(net "M_B_DQ1")
	)
	(segment
		(start 120.787922 -6.096)
		(end 120.940322 -5.9436)
		(width 0.1524)
		(layer "In7.Cu")
		(net "M_B_DQ1")
	)
	(segment
		(start 124.587 -7.3152)
		(end 127.3048 -7.3152)
		(width 0.1524)
		(layer "In7.Cu")
		(net "M_B_DQ1")
	)
	(segment
		(start 118.959122 -5.5626)
		(end 119.111522 -5.715)
		(width 0.1524)
		(layer "In7.Cu")
		(net "M_B_DQ1")
	)
	(segment
		(start 120.940322 -5.9436)
		(end 120.940322 -5.715)
		(width 0.1524)
		(layer "In7.Cu")
		(net "M_B_DQ1")
	)
	(segment
		(start 91.0844 -24.7396)
		(end 90.7288 -24.7396)
		(width 0.1016)
		(layer "In7.Cu")
		(net "M_B_DQ1")
	)
	(segment
		(start 118.044722 -6.096)
		(end 118.349522 -6.096)
		(width 0.1524)
		(layer "In7.Cu")
		(net "M_B_DQ1")
	)
	(segment
		(start 116.41836 -7.44474)
		(end 116.6876 -7.1755)
		(width 0.1524)
		(layer "In7.Cu")
		(net "M_B_DQ1")
	)
	(segment
		(start 120.483122 -6.096)
		(end 120.787922 -6.096)
		(width 0.1524)
		(layer "In7.Cu")
		(net "M_B_DQ1")
	)
	(segment
		(start 130.048 -6.1214)
		(end 129.8956 -6.2738)
		(width 0.1524)
		(layer "In7.Cu")
		(net "M_B_DQ1")
	)
	(segment
		(start 128.0414 -5.5626)
		(end 129.8956 -5.5626)
		(width 0.1524)
		(layer "In7.Cu")
		(net "M_B_DQ1")
	)
	(segment
		(start 121.092722 -5.5626)
		(end 121.397522 -5.5626)
		(width 0.1524)
		(layer "In7.Cu")
		(net "M_B_DQ1")
	)
	(segment
		(start 121.549922 -5.9436)
		(end 121.702322 -6.096)
		(width 0.1524)
		(layer "In7.Cu")
		(net "M_B_DQ1")
	)
	(segment
		(start 122.311922 -5.5626)
		(end 124.1552 -5.5626)
		(width 0.1524)
		(layer "In7.Cu")
		(net "M_B_DQ1")
	)
	(segment
		(start 127.889 -5.715)
		(end 128.0414 -5.5626)
		(width 0.1524)
		(layer "In7.Cu")
		(net "M_B_DQ1")
	)
	(segment
		(start 119.721122 -5.9436)
		(end 119.721122 -5.715)
		(width 0.1524)
		(layer "In7.Cu")
		(net "M_B_DQ1")
	)
	(segment
		(start 90.4494 -24.4602)
		(end 90.4494 -22.0726)
		(width 0.1016)
		(layer "In7.Cu")
		(net "M_B_DQ1")
	)
	(segment
		(start 117.739922 -5.5626)
		(end 117.892322 -5.715)
		(width 0.1524)
		(layer "In7.Cu")
		(net "M_B_DQ1")
	)
	(segment
		(start 129.791206 -6.9342)
		(end 129.943606 -7.0866)
		(width 0.1524)
		(layer "In7.Cu")
		(net "M_B_DQ1")
	)
	(segment
		(start 117.892322 -5.715)
		(end 117.892322 -5.9436)
		(width 0.1524)
		(layer "In7.Cu")
		(net "M_B_DQ1")
	)
	(segment
		(start 119.111522 -5.9436)
		(end 119.263922 -6.096)
		(width 0.1524)
		(layer "In7.Cu")
		(net "M_B_DQ1")
	)
	(segment
		(start 129.5654 -6.2738)
		(end 129.413 -6.4262)
		(width 0.1524)
		(layer "In7.Cu")
		(net "M_B_DQ1")
	)
	(segment
		(start 129.943606 -7.0866)
		(end 129.943606 -7.69493)
		(width 0.1524)
		(layer "In7.Cu")
		(net "M_B_DQ1")
	)
	(segment
		(start 90.7288 -24.7396)
		(end 90.4494 -24.4602)
		(width 0.1016)
		(layer "In7.Cu")
		(net "M_B_DQ1")
	)
	(segment
		(start 92.790264 -26.445464)
		(end 91.0844 -24.7396)
		(width 0.1016)
		(layer "In7.Cu")
		(net "M_B_DQ1")
	)
	(segment
		(start 106.131868 -15.738856)
		(end 114.425984 -7.44474)
		(width 0.1524)
		(layer "In7.Cu")
		(net "M_B_DQ1")
	)
	(segment
		(start 94.003876 -19.05)
		(end 97.31502 -15.738856)
		(width 0.1524)
		(layer "In7.Cu")
		(net "M_B_DQ1")
	)
	(segment
		(start 92.790264 -27.46502)
		(end 92.790264 -26.445464)
		(width 0.1016)
		(layer "In7.Cu")
		(net "M_B_DQ1")
	)
	(segment
		(start 120.330722 -5.715)
		(end 120.330722 -5.9436)
		(width 0.1524)
		(layer "In7.Cu")
		(net "M_B_DQ1")
	)
	(segment
		(start 130.048 -5.715)
		(end 130.048 -6.1214)
		(width 0.1524)
		(layer "In7.Cu")
		(net "M_B_DQ1")
	)
	(segment
		(start 129.5654 -6.9342)
		(end 129.791206 -6.9342)
		(width 0.1524)
		(layer "In7.Cu")
		(net "M_B_DQ1")
	)
	(segment
		(start 121.397522 -5.5626)
		(end 121.549922 -5.715)
		(width 0.1524)
		(layer "In7.Cu")
		(net "M_B_DQ1")
	)
	(segment
		(start 124.3584 -5.7658)
		(end 124.3584 -7.0866)
		(width 0.1524)
		(layer "In7.Cu")
		(net "M_B_DQ1")
	)
	(segment
		(start 129.8956 -5.5626)
		(end 130.048 -5.715)
		(width 0.1524)
		(layer "In7.Cu")
		(net "M_B_DQ1")
	)
	(segment
		(start 129.413 -6.4262)
		(end 129.413 -6.7818)
		(width 0.1524)
		(layer "In7.Cu")
		(net "M_B_DQ1")
	)
	(segment
		(start 93.141546 -19.380454)
		(end 93.673422 -19.380454)
		(width 0.1016)
		(layer "In7.Cu")
		(net "M_B_DQ1")
	)
	(segment
		(start 38.354 -38.6842)
		(end 38.72865 -38.30955)
		(width 0.1143)
		(layer "F.Cu")
		(net "SMB_XDP_CLK_R")
	)
	(segment
		(start 38.72865 -37.754306)
		(end 39.624 -36.858956)
		(width 0.1143)
		(layer "F.Cu")
		(net "SMB_XDP_CLK_R")
	)
	(segment
		(start 39.624 -34.182812)
		(end 40.751252 -33.05556)
		(width 0.1143)
		(layer "F.Cu")
		(net "SMB_XDP_CLK_R")
	)
	(segment
		(start 39.624 -36.858956)
		(end 39.624 -34.182812)
		(width 0.1143)
		(layer "F.Cu")
		(net "SMB_XDP_CLK_R")
	)
	(segment
		(start 38.72865 -38.30955)
		(end 38.72865 -37.754306)
		(width 0.1143)
		(layer "F.Cu")
		(net "SMB_XDP_CLK_R")
	)
	(segment
		(start 40.751252 -33.05556)
		(end 42.10177 -33.05556)
		(width 0.1143)
		(layer "F.Cu")
		(net "SMB_XDP_CLK_R")
	)
	(via
		(at 131.699 -58.547)
		(size 0.7112)
		(drill 0.3556)
		(layers "F.Cu" "B.Cu")
		(net "CHA_0_SA1")
	)
	(segment
		(start 131.2164 -60.3758)
		(end 129.54 -60.3758)
		(width 0.1143)
		(layer "B.Cu")
		(net "CHA_0_SA1")
	)
	(segment
		(start 128.9812 -60.3758)
		(end 129.54 -60.3758)
		(width 0.1143)
		(layer "B.Cu")
		(net "CHA_0_SA1")
	)
	(segment
		(start 132.08 -58.928)
		(end 132.08 -59.5122)
		(width 0.1143)
		(layer "B.Cu")
		(net "CHA_0_SA1")
	)
	(segment
		(start 131.699 -58.547)
		(end 132.08 -58.928)
		(width 0.1143)
		(layer "B.Cu")
		(net "CHA_0_SA1")
	)
	(segment
		(start 132.08 -59.5122)
		(end 131.2164 -60.3758)
		(width 0.1143)
		(layer "B.Cu")
		(net "CHA_0_SA1")
	)
	(segment
		(start 127.750062 -62.599824)
		(end 127.750062 -61.606938)
		(width 0.1143)
		(layer "B.Cu")
		(net "CHA_0_SA1")
	)
	(segment
		(start 127.750062 -61.606938)
		(end 128.9812 -60.3758)
		(width 0.1143)
		(layer "B.Cu")
		(net "CHA_0_SA1")
	)
	(segment
		(start 132.5499 -1.68402)
		(end 132.5499 -2.681478)
		(width 0.1778)
		(layer "F.Cu")
		(net "M_B_DQ7")
	)
	(segment
		(start 132.9436 -3.075178)
		(end 132.9436 -3.125978)
		(width 0.1778)
		(layer "F.Cu")
		(net "M_B_DQ7")
	)
	(segment
		(start 94.226634 -26.256234)
		(end 94.29242 -26.256234)
		(width 0.1016)
		(layer "F.Cu")
		(net "M_B_DQ7")
	)
	(segment
		(start 132.5499 -2.681478)
		(end 132.9436 -3.075178)
		(width 0.1778)
		(layer "F.Cu")
		(net "M_B_DQ7")
	)
	(segment
		(start 94.29242 -26.256234)
		(end 94.745048 -26.708862)
		(width 0.1016)
		(layer "F.Cu")
		(net "M_B_DQ7")
	)
	(segment
		(start 132.9436 -3.125978)
		(end 132.957062 -3.13944)
		(width 0.1778)
		(layer "F.Cu")
		(net "M_B_DQ7")
	)
	(segment
		(start 94.745048 -26.708862)
		(end 94.745048 -26.957274)
		(width 0.1016)
		(layer "F.Cu")
		(net "M_B_DQ7")
	)
	(segment
		(start 92.9259 -24.9555)
		(end 94.226634 -26.256234)
		(width 0.1016)
		(layer "F.Cu")
		(net "M_B_DQ7")
	)
	(segment
		(start 92.677996 -24.9555)
		(end 92.9259 -24.9555)
		(width 0.1016)
		(layer "F.Cu")
		(net "M_B_DQ7")
	)
	(via
		(at 132.957062 -3.13944)
		(size 0.4318)
		(drill 0.2032)
		(layers "F.Cu" "B.Cu")
		(net "M_B_DQ7")
	)
	(via
		(at 92.677996 -24.9555)
		(size 0.4318)
		(drill 0.2032)
		(layers "F.Cu" "B.Cu")
		(net "M_B_DQ7")
	)
	(segment
		(start 132.9944 -3.125978)
		(end 132.970524 -3.125978)
		(width 0.1778)
		(layer "B.Cu")
		(net "M_B_DQ7")
	)
	(segment
		(start 133.449822 -2.670556)
		(end 132.9944 -3.125978)
		(width 0.1778)
		(layer "B.Cu")
		(net "M_B_DQ7")
	)
	(segment
		(start 133.449822 -1.690624)
		(end 133.449822 -2.670556)
		(width 0.1778)
		(layer "B.Cu")
		(net "M_B_DQ7")
	)
	(segment
		(start 132.970524 -3.125978)
		(end 132.957062 -3.13944)
		(width 0.1778)
		(layer "B.Cu")
		(net "M_B_DQ7")
	)
	(segment
		(start 93.1672 -24.466296)
		(end 92.677996 -24.9555)
		(width 0.1016)
		(layer "In7.Cu")
		(net "M_B_DQ7")
	)
	(segment
		(start 99.919028 -18.355056)
		(end 99.577144 -18.69694)
		(width 0.1524)
		(layer "In7.Cu")
		(net "M_B_DQ7")
	)
	(segment
		(start 134.0866 -5.058918)
		(end 133.1214 -5.058918)
		(width 0.1524)
		(layer "In7.Cu")
		(net "M_B_DQ7")
	)
	(segment
		(start 132.1308 -9.7028)
		(end 130.7084 -11.1252)
		(width 0.1524)
		(layer "In7.Cu")
		(net "M_B_DQ7")
	)
	(segment
		(start 134.239 -6.097778)
		(end 134.239 -6.732778)
		(width 0.1524)
		(layer "In7.Cu")
		(net "M_B_DQ7")
	)
	(segment
		(start 134.239 -6.732778)
		(end 134.0866 -6.885178)
		(width 0.1524)
		(layer "In7.Cu")
		(net "M_B_DQ7")
	)
	(segment
		(start 134.0866 -5.945378)
		(end 134.239 -6.097778)
		(width 0.1524)
		(layer "In7.Cu")
		(net "M_B_DQ7")
	)
	(segment
		(start 115.850924 -10.2108)
		(end 114.784124 -11.2776)
		(width 0.1524)
		(layer "In7.Cu")
		(net "M_B_DQ7")
	)
	(segment
		(start 132.1308 -8.8646)
		(end 132.1308 -9.7028)
		(width 0.1524)
		(layer "In7.Cu")
		(net "M_B_DQ7")
	)
	(segment
		(start 133.0198 -4.00685)
		(end 133.332728 -4.319778)
		(width 0.1524)
		(layer "In7.Cu")
		(net "M_B_DQ7")
	)
	(segment
		(start 128.512062 -11.1252)
		(end 128.029462 -11.6078)
		(width 0.1524)
		(layer "In7.Cu")
		(net "M_B_DQ7")
	)
	(segment
		(start 97.6376 -19.0246)
		(end 96.6216 -20.0406)
		(width 0.1524)
		(layer "In7.Cu")
		(net "M_B_DQ7")
	)
	(segment
		(start 122.7582 -11.4554)
		(end 122.7582 -10.3632)
		(width 0.1524)
		(layer "In7.Cu")
		(net "M_B_DQ7")
	)
	(segment
		(start 132.7658 -6.885178)
		(end 132.207 -7.443978)
		(width 0.1524)
		(layer "In7.Cu")
		(net "M_B_DQ7")
	)
	(segment
		(start 132.355082 -8.25246)
		(end 132.355082 -8.640318)
		(width 0.1524)
		(layer "In7.Cu")
		(net "M_B_DQ7")
	)
	(segment
		(start 107.21594 -18.355056)
		(end 99.919028 -18.355056)
		(width 0.1524)
		(layer "In7.Cu")
		(net "M_B_DQ7")
	)
	(segment
		(start 133.0198 -3.202178)
		(end 133.0198 -4.00685)
		(width 0.1524)
		(layer "In7.Cu")
		(net "M_B_DQ7")
	)
	(segment
		(start 134.239 -4.472178)
		(end 134.239 -4.906518)
		(width 0.1524)
		(layer "In7.Cu")
		(net "M_B_DQ7")
	)
	(segment
		(start 114.293396 -11.2776)
		(end 107.21594 -18.355056)
		(width 0.1524)
		(layer "In7.Cu")
		(net "M_B_DQ7")
	)
	(segment
		(start 94.234 -20.7772)
		(end 93.1672 -21.844)
		(width 0.1016)
		(layer "In7.Cu")
		(net "M_B_DQ7")
	)
	(segment
		(start 132.957062 -3.13944)
		(end 133.0198 -3.202178)
		(width 0.1524)
		(layer "In7.Cu")
		(net "M_B_DQ7")
	)
	(segment
		(start 133.332728 -4.319778)
		(end 134.0866 -4.319778)
		(width 0.1524)
		(layer "In7.Cu")
		(net "M_B_DQ7")
	)
	(segment
		(start 134.0866 -6.885178)
		(end 132.7658 -6.885178)
		(width 0.1524)
		(layer "In7.Cu")
		(net "M_B_DQ7")
	)
	(segment
		(start 128.029462 -11.6078)
		(end 122.9106 -11.6078)
		(width 0.1524)
		(layer "In7.Cu")
		(net "M_B_DQ7")
	)
	(segment
		(start 93.1672 -21.844)
		(end 93.1672 -24.466296)
		(width 0.1016)
		(layer "In7.Cu")
		(net "M_B_DQ7")
	)
	(segment
		(start 132.207 -8.104378)
		(end 132.355082 -8.25246)
		(width 0.1524)
		(layer "In7.Cu")
		(net "M_B_DQ7")
	)
	(segment
		(start 122.7582 -10.3632)
		(end 122.6058 -10.2108)
		(width 0.1524)
		(layer "In7.Cu")
		(net "M_B_DQ7")
	)
	(segment
		(start 122.9106 -11.6078)
		(end 122.7582 -11.4554)
		(width 0.1524)
		(layer "In7.Cu")
		(net "M_B_DQ7")
	)
	(segment
		(start 134.239 -4.906518)
		(end 134.0866 -5.058918)
		(width 0.1524)
		(layer "In7.Cu")
		(net "M_B_DQ7")
	)
	(segment
		(start 133.1214 -5.058918)
		(end 132.969 -5.211318)
		(width 0.1524)
		(layer "In7.Cu")
		(net "M_B_DQ7")
	)
	(segment
		(start 99.577144 -18.69694)
		(end 99.577144 -18.697194)
		(width 0.1524)
		(layer "In7.Cu")
		(net "M_B_DQ7")
	)
	(segment
		(start 96.6216 -20.0406)
		(end 95.885 -20.7772)
		(width 0.1016)
		(layer "In7.Cu")
		(net "M_B_DQ7")
	)
	(segment
		(start 122.6058 -10.2108)
		(end 115.850924 -10.2108)
		(width 0.1524)
		(layer "In7.Cu")
		(net "M_B_DQ7")
	)
	(segment
		(start 133.1214 -5.945378)
		(end 134.0866 -5.945378)
		(width 0.1524)
		(layer "In7.Cu")
		(net "M_B_DQ7")
	)
	(segment
		(start 134.0866 -4.319778)
		(end 134.239 -4.472178)
		(width 0.1524)
		(layer "In7.Cu")
		(net "M_B_DQ7")
	)
	(segment
		(start 132.969 -5.792978)
		(end 133.1214 -5.945378)
		(width 0.1524)
		(layer "In7.Cu")
		(net "M_B_DQ7")
	)
	(segment
		(start 95.885 -20.7772)
		(end 94.234 -20.7772)
		(width 0.1016)
		(layer "In7.Cu")
		(net "M_B_DQ7")
	)
	(segment
		(start 99.577144 -18.697194)
		(end 99.249738 -19.0246)
		(width 0.1524)
		(layer "In7.Cu")
		(net "M_B_DQ7")
	)
	(segment
		(start 99.249738 -19.0246)
		(end 97.6376 -19.0246)
		(width 0.1524)
		(layer "In7.Cu")
		(net "M_B_DQ7")
	)
	(segment
		(start 130.7084 -11.1252)
		(end 128.512062 -11.1252)
		(width 0.1524)
		(layer "In7.Cu")
		(net "M_B_DQ7")
	)
	(segment
		(start 132.207 -7.443978)
		(end 132.207 -8.104378)
		(width 0.1524)
		(layer "In7.Cu")
		(net "M_B_DQ7")
	)
	(segment
		(start 132.355082 -8.640318)
		(end 132.1308 -8.8646)
		(width 0.1524)
		(layer "In7.Cu")
		(net "M_B_DQ7")
	)
	(segment
		(start 132.969 -5.211318)
		(end 132.969 -5.792978)
		(width 0.1524)
		(layer "In7.Cu")
		(net "M_B_DQ7")
	)
	(segment
		(start 114.784124 -11.2776)
		(end 114.293396 -11.2776)
		(width 0.1524)
		(layer "In7.Cu")
		(net "M_B_DQ7")
	)
	(segment
		(start 133.53796 -22.59584)
		(end 132.588 -21.64588)
		(width 0.3048)
		(layer "F.Cu")
		(net "GND")
	)
	(segment
		(start 51.7779 -17.7546)
		(end 51.054 -17.7546)
		(width 0.508)
		(layer "F.Cu")
		(net "GND")
	)
	(segment
		(start 99.451668 -39.200074)
		(end 99.451668 -39.199566)
		(width 0.3048)
		(layer "F.Cu")
		(net "GND")
	)
	(segment
		(start 40.194738 -29.05506)
		(end 42.10177 -29.05506)
		(width 0.2794)
		(layer "F.Cu")
		(net "GND")
	)
	(segment
		(start 90.64879 -41.600374)
		(end 90.648028 -41.600374)
		(width 0.254)
		(layer "F.Cu")
		(net "GND")
	)
	(segment
		(start 68.62445 -47.923958)
		(end 68.522088 -47.821596)
		(width 0.3048)
		(layer "F.Cu")
		(net "GND")
	)
	(segment
		(start 143.6878 -69.595746)
		(end 143.6878 -69.3547)
		(width 0.254)
		(layer "F.Cu")
		(net "GND")
	)
	(segment
		(start 159.3342 -26.5938)
		(end 157.70987 -26.5938)
		(width 0.3048)
		(layer "F.Cu")
		(net "GND")
	)
	(segment
		(start 184.315862 -8.649716)
		(end 184.315862 -8.294116)
		(width 0.254)
		(layer "F.Cu")
		(net "GND")
	)
	(segment
		(start 74.349864 -6.195568)
		(end 74.367898 -6.213602)
		(width 0.7112)
		(layer "F.Cu")
		(net "GND")
	)
	(segment
		(start 88.9 -44.951142)
		(end 89.149428 -44.701714)
		(width 0.254)
		(layer "F.Cu")
		(net "GND")
	)
	(segment
		(start 96.251268 -35.199574)
		(end 96.17075 -35.119056)
		(width 0.3048)
		(layer "F.Cu")
		(net "GND")
	)
	(segment
		(start 171.549822 -2.98704)
		(end 171.70146 -3.138678)
		(width 0.254)
		(layer "F.Cu")
		(net "GND")
	)
	(segment
		(start 186.250072 -62.59322)
		(end 186.250072 -63.446914)
		(width 0.254)
		(layer "F.Cu")
		(net "GND")
	)
	(segment
		(start 102.908354 -41.526968)
		(end 102.913434 -41.526968)
		(width 0.254)
		(layer "F.Cu")
		(net "GND")
	)
	(segment
		(start 99.877626 -35.628072)
		(end 99.822 -35.628072)
		(width 0.3048)
		(layer "F.Cu")
		(net "GND")
	)
	(segment
		(start 152.6032 -12.446)
		(end 152.6032 -11.7094)
		(width 0.3048)
		(layer "F.Cu")
		(net "GND")
	)
	(segment
		(start 152.5778 -11.684)
		(end 152.5778 -11.492484)
		(width 0.3048)
		(layer "F.Cu")
		(net "GND")
	)
	(segment
		(start 81.1784 -67.7418)
		(end 80.381094 -67.7418)
		(width 0.3048)
		(layer "F.Cu")
		(net "GND")
	)
	(segment
		(start 62.333886 -42.7863)
		(end 61.595 -42.047414)
		(width 0.3048)
		(layer "F.Cu")
		(net "GND")
	)
	(segment
		(start 105.669842 -36.3474)
		(end 105.5878 -36.3474)
		(width 0.254)
		(layer "F.Cu")
		(net "GND")
	)
	(segment
		(start 97.843848 -27.996134)
		(end 97.843848 -27.980894)
		(width 0.254)
		(layer "F.Cu")
		(net "GND")
	)
	(segment
		(start 140.1318 -53.2892)
		(end 140.119608 -53.277008)
		(width 0.3048)
		(layer "F.Cu")
		(net "GND")
	)
	(segment
		(start 141.8082 -46.791372)
		(end 141.96441 -46.635162)
		(width 0.508)
		(layer "F.Cu")
		(net "GND")
	)
	(segment
		(start 102.779068 -40.955214)
		(end 103.124 -41.300146)
		(width 0.254)
		(layer "F.Cu")
		(net "GND")
	)
	(segment
		(start 101.7778 -27.6352)
		(end 101.986334 -27.6352)
		(width 0.254)
		(layer "F.Cu")
		(net "GND")
	)
	(segment
		(start 101.849428 -41.600374)
		(end 101.849428 -41.599866)
		(width 0.254)
		(layer "F.Cu")
		(net "GND")
	)
	(segment
		(start 84.815934 -42.702734)
		(end 85.1916 -43.0784)
		(width 0.254)
		(layer "F.Cu")
		(net "GND")
	)
	(segment
		(start 135.86587 -69.6595)
		(end 135.86587 -69.366638)
		(width 0.254)
		(layer "F.Cu")
		(net "GND")
	)
	(segment
		(start 141.351 -22.606)
		(end 140.99794 -22.95906)
		(width 0.3048)
		(layer "F.Cu")
		(net "GND")
	)
	(segment
		(start 82.3214 -40.0812)
		(end 82.290412 -40.112188)
		(width 0.254)
		(layer "F.Cu")
		(net "GND")
	)
	(segment
		(start 183.550052 -69.71665)
		(end 183.23433 -69.400928)
		(width 0.254)
		(layer "F.Cu")
		(net "GND")
	)
	(segment
		(start 85.023452 -27.996134)
		(end 84.687664 -27.660346)
		(width 0.254)
		(layer "F.Cu")
		(net "GND")
	)
	(segment
		(start 111.23676 -66.8655)
		(end 108.024676 -66.8655)
		(width 0.3048)
		(layer "F.Cu")
		(net "GND")
	)
	(segment
		(start 91.450668 -42.400474)
		(end 91.496642 -42.3545)
		(width 0.254)
		(layer "F.Cu")
		(net "GND")
	)
	(segment
		(start 155.702 -31.877)
		(end 156.8958 -31.877)
		(width 0.3048)
		(layer "F.Cu")
		(net "GND")
	)
	(segment
		(start 27.7368 -59.7916)
		(end 27.7368 -58.8264)
		(width 0.508)
		(layer "F.Cu")
		(net "GND")
	)
	(segment
		(start 79.738728 -27.770328)
		(end 80.1116 -28.1432)
		(width 0.3048)
		(layer "F.Cu")
		(net "GND")
	)
	(segment
		(start 84.321142 -31.95574)
		(end 84.790788 -31.486094)
		(width 0.3048)
		(layer "F.Cu")
		(net "GND")
	)
	(segment
		(start 96.393 -42.545)
		(end 96.393 -42.542206)
		(width 0.254)
		(layer "F.Cu")
		(net "GND")
	)
	(segment
		(start 103.520748 -25.951434)
		(end 103.520748 -25.618948)
		(width 0.254)
		(layer "F.Cu")
		(net "GND")
	)
	(segment
		(start 189.850014 -62.59322)
		(end 189.850014 -63.662814)
		(width 0.254)
		(layer "F.Cu")
		(net "GND")
	)
	(segment
		(start 81.9912 -34.577528)
		(end 81.963514 -34.549842)
		(width 0.254)
		(layer "F.Cu")
		(net "GND")
	)
	(segment
		(start 103.786178 -37.993066)
		(end 103.844598 -38.051486)
		(width 0.3048)
		(layer "F.Cu")
		(net "GND")
	)
	(segment
		(start 88.387428 -25.951434)
		(end 88.387428 -25.639268)
		(width 0.3048)
		(layer "F.Cu")
		(net "GND")
	)
	(segment
		(start 88.67013 -50.404014)
		(end 89.003886 -50.73777)
		(width 0.254)
		(layer "F.Cu")
		(net "GND")
	)
	(segment
		(start 89.370154 -42.532554)
		(end 89.3318 -42.4942)
		(width 0.3048)
		(layer "F.Cu")
		(net "GND")
	)
	(segment
		(start 81.34985 -6.195568)
		(end 81.34985 -9.010142)
		(width 0.7112)
		(layer "F.Cu")
		(net "GND")
	)
	(segment
		(start 110.053628 -45.697394)
		(end 110.053628 -45.696886)
		(width 0.254)
		(layer "F.Cu")
		(net "GND")
	)
	(segment
		(start 143.34998 -69.933566)
		(end 143.6878 -69.595746)
		(width 0.254)
		(layer "F.Cu")
		(net "GND")
	)
	(segment
		(start 106.040936 -35.697414)
		(end 106.147108 -35.697414)
		(width 0.254)
		(layer "F.Cu")
		(net "GND")
	)
	(segment
		(start 176.350168 -70.806564)
		(end 176.350168 -69.674232)
		(width 0.254)
		(layer "F.Cu")
		(net "GND")
	)
	(segment
		(start 109.931708 -47.091854)
		(end 109.931708 -47.091346)
		(width 0.254)
		(layer "F.Cu")
		(net "GND")
	)
	(segment
		(start 149.049994 -9.897364)
		(end 149.049994 -8.788654)
		(width 0.254)
		(layer "F.Cu")
		(net "GND")
	)
	(segment
		(start 55.86476 -40.45712)
		(end 55.6768 -40.26916)
		(width 0.3556)
		(layer "F.Cu")
		(net "GND")
	)
	(segment
		(start 110.053628 -45.696886)
		(end 110.186978 -45.696886)
		(width 0.254)
		(layer "F.Cu")
		(net "GND")
	)
	(segment
		(start 109.863128 -40.515794)
		(end 109.673136 -40.515794)
		(width 0.254)
		(layer "F.Cu")
		(net "GND")
	)
	(segment
		(start 110.362746 -34.772092)
		(end 109.865668 -34.772092)
		(width 0.254)
		(layer "F.Cu")
		(net "GND")
	)
	(segment
		(start 81.764632 -30.091634)
		(end 81.79054 -30.117542)
		(width 0.3048)
		(layer "F.Cu")
		(net "GND")
	)
	(segment
		(start 103.672386 -45.381164)
		(end 103.672132 -45.381164)
		(width 0.254)
		(layer "F.Cu")
		(net "GND")
	)
	(segment
		(start 99.736148 -26.06675)
		(end 99.665028 -25.99563)
		(width 0.3048)
		(layer "F.Cu")
		(net "GND")
	)
	(segment
		(start 81.785968 -35.105594)
		(end 81.785968 -35.105086)
		(width 0.254)
		(layer "F.Cu")
		(net "GND")
	)
	(segment
		(start 45.0088 -32.975296)
		(end 45.4152 -32.568896)
		(width 0.381)
		(layer "F.Cu")
		(net "GND")
	)
	(segment
		(start 80.551528 -26.001726)
		(end 80.165702 -25.6159)
		(width 0.3048)
		(layer "F.Cu")
		(net "GND")
	)
	(segment
		(start 80.264254 -28.295854)
		(end 80.1116 -28.1432)
		(width 0.3048)
		(layer "F.Cu")
		(net "GND")
	)
	(segment
		(start 90.122248 -45.373798)
		(end 89.743534 -45.752512)
		(width 0.254)
		(layer "F.Cu")
		(net "GND")
	)
	(segment
		(start 88.11768 -45.734986)
		(end 87.99322 -45.610526)
		(width 0.254)
		(layer "F.Cu")
		(net "GND")
	)
	(segment
		(start 102.779068 -37.683694)
		(end 102.779068 -37.683186)
		(width 0.3048)
		(layer "F.Cu")
		(net "GND")
	)
	(segment
		(start 183.550052 -70.806564)
		(end 183.550052 -69.71665)
		(width 0.254)
		(layer "F.Cu")
		(net "GND")
	)
	(segment
		(start 135.4455 -14.71676)
		(end 134.76224 -14.71676)
		(width 0.3048)
		(layer "F.Cu")
		(net "GND")
	)
	(segment
		(start 92.787978 -52.554124)
		(end 92.7735 -52.568602)
		(width 0.254)
		(layer "F.Cu")
		(net "GND")
	)
	(segment
		(start 133.75005 -70.806564)
		(end 133.75005 -69.94652)
		(width 0.254)
		(layer "F.Cu")
		(net "GND")
	)
	(segment
		(start 182.049928 -8.82015)
		(end 182.4609 -8.409178)
		(width 0.254)
		(layer "F.Cu")
		(net "GND")
	)
	(segment
		(start 132.1308 -41.29405)
		(end 130.02895 -41.29405)
		(width 0.3048)
		(layer "F.Cu")
		(net "GND")
	)
	(segment
		(start 81.646268 -32.702754)
		(end 81.646268 -32.869378)
		(width 0.254)
		(layer "F.Cu")
		(net "GND")
	)
	(segment
		(start 25.206198 -57.420002)
		(end 25.2984 -57.3278)
		(width 0.2032)
		(layer "F.Cu")
		(net "GND")
	)
	(segment
		(start 43.18 -41.55948)
		(end 43.51528 -41.89476)
		(width 0.3048)
		(layer "F.Cu")
		(net "GND")
	)
	(segment
		(start 29.349954 -6.195568)
		(end 29.367988 -6.213602)
		(width 0.7112)
		(layer "F.Cu")
		(net "GND")
	)
	(segment
		(start 179.050188 -62.59322)
		(end 179.050188 -63.429896)
		(width 0.254)
		(layer "F.Cu")
		(net "GND")
	)
	(segment
		(start 41.367964 -6.213602)
		(end 41.367964 -9.076944)
		(width 0.7112)
		(layer "F.Cu")
		(net "GND")
	)
	(segment
		(start 164.650166 -63.975234)
		(end 164.5412 -64.0842)
		(width 0.3048)
		(layer "F.Cu")
		(net "GND")
	)
	(segment
		(start 84.028788 -34.701988)
		(end 83.742022 -34.415222)
		(width 0.254)
		(layer "F.Cu")
		(net "GND")
	)
	(segment
		(start 107.3658 -65.849754)
		(end 107.3658 -66.167)
		(width 0.3048)
		(layer "F.Cu")
		(net "GND")
	)
	(segment
		(start 185.35015 -69.902324)
		(end 184.8612 -69.413374)
		(width 0.254)
		(layer "F.Cu")
		(net "GND")
	)
	(segment
		(start 84.028788 -39.431214)
		(end 84.365846 -39.094156)
		(width 0.254)
		(layer "F.Cu")
		(net "GND")
	)
	(segment
		(start 102.779068 -41.656254)
		(end 102.908354 -41.526968)
		(width 0.254)
		(layer "F.Cu")
		(net "GND")
	)
	(segment
		(start 98.306128 -32.283654)
		(end 97.9805 -32.609282)
		(width 0.254)
		(layer "F.Cu")
		(net "GND")
	)
	(segment
		(start 140.1572 -50.5968)
		(end 140.1572 -51.3588)
		(width 0.3048)
		(layer "F.Cu")
		(net "GND")
	)
	(segment
		(start 174.030894 -42.164)
		(end 172.847 -42.164)
		(width 0.508)
		(layer "F.Cu")
		(net "GND")
	)
	(segment
		(start 58.02757 -47.23003)
		(end 55.86857 -47.23003)
		(width 0.3048)
		(layer "F.Cu")
		(net "GND")
	)
	(segment
		(start 85.171788 -40.716454)
		(end 85.10651 -40.716454)
		(width 0.254)
		(layer "F.Cu")
		(net "GND")
	)
	(segment
		(start 183.22925 -64.05245)
		(end 183.23433 -64.05245)
		(width 0.254)
		(layer "F.Cu")
		(net "GND")
	)
	(segment
		(start 84.4042 -44.1706)
		(end 84.028788 -43.795188)
		(width 0.254)
		(layer "F.Cu")
		(net "GND")
	)
	(segment
		(start 33.349946 -6.195568)
		(end 33.36798 -6.213602)
		(width 0.7112)
		(layer "F.Cu")
		(net "GND")
	)
	(segment
		(start 80.551528 -26.088594)
		(end 80.551528 -26.901394)
		(width 0.3048)
		(layer "F.Cu")
		(net "GND")
	)
	(segment
		(start 81.587848 -33.380426)
		(end 81.361534 -33.154112)
		(width 0.254)
		(layer "F.Cu")
		(net "GND")
	)
	(segment
		(start 83.0834 -25.995122)
		(end 83.0834 -24.892)
		(width 0.254)
		(layer "F.Cu")
		(net "GND")
	)
	(segment
		(start 95.448628 -36.799774)
		(end 95.448628 -36.798504)
		(width 0.3048)
		(layer "F.Cu")
		(net "GND")
	)
	(segment
		(start 107.363768 -50.404014)
		(end 107.349036 -50.404014)
		(width 0.254)
		(layer "F.Cu")
		(net "GND")
	)
	(segment
		(start 129.8448 -46.5836)
		(end 129.8448 -45.466)
		(width 0.3048)
		(layer "F.Cu")
		(net "GND")
	)
	(segment
		(start 83.93938 -28.57881)
		(end 84.126324 -28.57881)
		(width 0.3048)
		(layer "F.Cu")
		(net "GND")
	)
	(segment
		(start 105.5878 -36.15055)
		(end 106.040936 -35.697414)
		(width 0.254)
		(layer "F.Cu")
		(net "GND")
	)
	(segment
		(start 104.6734 -34.4424)
		(end 104.6734 -34.946082)
		(width 0.3048)
		(layer "F.Cu")
		(net "GND")
	)
	(segment
		(start 96.251268 -36.797996)
		(end 96.621092 -36.428172)
		(width 0.3048)
		(layer "F.Cu")
		(net "GND")
	)
	(segment
		(start 109.913928 -47.797974)
		(end 109.913928 -47.788322)
		(width 0.254)
		(layer "F.Cu")
		(net "GND")
	)
	(segment
		(start 110.053628 -28.387294)
		(end 110.632748 -28.387294)
		(width 0.254)
		(layer "F.Cu")
		(net "GND")
	)
	(segment
		(start 135.849868 -9.03351)
		(end 135.8392 -9.03351)
		(width 0.3048)
		(layer "F.Cu")
		(net "GND")
	)
	(segment
		(start 132.94868 -33.29432)
		(end 133.2738 -32.9692)
		(width 0.3048)
		(layer "F.Cu")
		(net "GND")
	)
	(segment
		(start 107.111038 -43.844464)
		(end 107.111038 -44.208446)
		(width 0.254)
		(layer "F.Cu")
		(net "GND")
	)
	(segment
		(start 89.907872 -36.799774)
		(end 90.256868 -36.450778)
		(width 0.254)
		(layer "F.Cu")
		(net "GND")
	)
	(segment
		(start 132.249926 -9.897364)
		(end 132.249926 -8.790686)
		(width 0.3048)
		(layer "F.Cu")
		(net "GND")
	)
	(segment
		(start 86.388448 -29.235654)
		(end 86.286594 -29.1338)
		(width 0.3048)
		(layer "F.Cu")
		(net "GND")
	)
	(segment
		(start 133.2738 -37.333174)
		(end 133.2738 -36.840414)
		(width 0.3048)
		(layer "F.Cu")
		(net "GND")
	)
	(segment
		(start 187.449968 -9.897364)
		(end 187.449968 -8.531606)
		(width 0.254)
		(layer "F.Cu")
		(net "GND")
	)
	(segment
		(start 129.159 -42.164)
		(end 129.159 -43.688)
		(width 0.3048)
		(layer "F.Cu")
		(net "GND")
	)
	(segment
		(start 24.3586 -50.0888)
		(end 24.3078 -50.0888)
		(width 0.3048)
		(layer "F.Cu")
		(net "GND")
	)
	(segment
		(start 42.10177 -17.71523)
		(end 42.545 -17.272)
		(width 0.2794)
		(layer "F.Cu")
		(net "GND")
	)
	(segment
		(start 146.05 -63.373)
		(end 145.3642 -64.0588)
		(width 0.254)
		(layer "F.Cu")
		(net "GND")
	)
	(segment
		(start 148.149818 -2.604516)
		(end 148.66112 -3.115818)
		(width 0.254)
		(layer "F.Cu")
		(net "GND")
	)
	(segment
		(start 104.026208 -46.497494)
		(end 104.480868 -46.952154)
		(width 0.254)
		(layer "F.Cu")
		(net "GND")
	)
	(segment
		(start 82.883502 -31.08452)
		(end 82.504788 -31.463234)
		(width 0.254)
		(layer "F.Cu")
		(net "GND")
	)
	(segment
		(start 82.043778 -32.428688)
		(end 81.646268 -32.031178)
		(width 0.254)
		(layer "F.Cu")
		(net "GND")
	)
	(segment
		(start 109.603286 -32.018224)
		(end 109.602016 -32.019494)
		(width 0.254)
		(layer "F.Cu")
		(net "GND")
	)
	(segment
		(start 57.16524 -42.8625)
		(end 57.16524 -42.38244)
		(width 0.3048)
		(layer "F.Cu")
		(net "GND")
	)
	(segment
		(start 83.619848 -26.952194)
		(end 83.124548 -27.447494)
		(width 0.3048)
		(layer "F.Cu")
		(net "GND")
	)
	(segment
		(start 157.70987 -26.5938)
		(end 157.45587 -26.8478)
		(width 0.3048)
		(layer "F.Cu")
		(net "GND")
	)
	(segment
		(start 181.749954 -69.64045)
		(end 182.051198 -69.339206)
		(width 0.254)
		(layer "F.Cu")
		(net "GND")
	)
	(segment
		(start 176.4284 -58.1152)
		(end 176.4284 -58.3692)
		(width 0.3048)
		(layer "F.Cu")
		(net "GND")
	)
	(segment
		(start 79.601568 -46.662086)
		(end 79.458566 -46.519084)
		(width 0.254)
		(layer "F.Cu")
		(net "GND")
	)
	(segment
		(start 93.393768 -47.640494)
		(end 93.393768 -47.576486)
		(width 0.254)
		(layer "F.Cu")
		(net "GND")
	)
	(segment
		(start 106.582972 -35.322002)
		(end 106.553254 -35.322002)
		(width 0.254)
		(layer "F.Cu")
		(net "GND")
	)
	(segment
		(start 80.546448 -39.146734)
		(end 80.546448 -38.835838)
		(width 0.254)
		(layer "F.Cu")
		(net "GND")
	)
	(segment
		(start 88.839548 -27.996134)
		(end 88.744298 -27.996134)
		(width 0.3048)
		(layer "F.Cu")
		(net "GND")
	)
	(segment
		(start 97.08134 -25.6413)
		(end 97.0153 -25.6413)
		(width 0.254)
		(layer "F.Cu")
		(net "GND")
	)
	(segment
		(start 92.108528 -47.259494)
		(end 91.7702 -46.921166)
		(width 0.254)
		(layer "F.Cu")
		(net "GND")
	)
	(segment
		(start 85.171788 -36.280852)
		(end 85.39226 -36.06038)
		(width 0.254)
		(layer "F.Cu")
		(net "GND")
	)
	(segment
		(start 143.649954 -8.475472)
		(end 143.62938 -8.454898)
		(width 0.254)
		(layer "F.Cu")
		(net "GND")
	)
	(segment
		(start 99.944428 -28.135834)
		(end 100.306632 -28.135834)
		(width 0.254)
		(layer "F.Cu")
		(net "GND")
	)
	(segment
		(start 153.891234 -3.125978)
		(end 153.8732 -3.125978)
		(width 0.3048)
		(layer "F.Cu")
		(net "GND")
	)
	(segment
		(start 40.882316 -27.6098)
		(end 39.13378 -27.6098)
		(width 0.2794)
		(layer "F.Cu")
		(net "GND")
	)
	(segment
		(start 110.053628 -41.193974)
		(end 109.896656 -41.037002)
		(width 0.254)
		(layer "F.Cu")
		(net "GND")
	)
	(segment
		(start 70.358 -57.15)
		(end 69.596 -57.15)
		(width 0.3048)
		(layer "F.Cu")
		(net "GND")
	)
	(segment
		(start 87.417148 -28.128214)
		(end 86.947248 -27.658314)
		(width 0.3048)
		(layer "F.Cu")
		(net "GND")
	)
	(segment
		(start 84.790788 -46.817788)
		(end 85.09 -47.117)
		(width 0.254)
		(layer "F.Cu")
		(net "GND")
	)
	(segment
		(start 177.54981 -1.68402)
		(end 177.54981 -3.046476)
		(width 0.254)
		(layer "F.Cu")
		(net "GND")
	)
	(segment
		(start 90.321892 -39.674038)
		(end 90.31224 -39.674038)
		(width 0.254)
		(layer "F.Cu")
		(net "GND")
	)
	(segment
		(start 151.4983 -23.9268)
		(end 151.4983 -23.0251)
		(width 0.3048)
		(layer "F.Cu")
		(net "GND")
	)
	(segment
		(start 84.409788 -32.771334)
		(end 84.40928 -32.771334)
		(width 0.254)
		(layer "F.Cu")
		(net "GND")
	)
	(segment
		(start 145.750026 -1.68402)
		(end 145.750026 -3.027172)
		(width 0.3048)
		(layer "F.Cu")
		(net "GND")
	)
	(segment
		(start 91.078304 -41.17086)
		(end 90.64879 -41.600374)
		(width 0.254)
		(layer "F.Cu")
		(net "GND")
	)
	(segment
		(start 111.9124 -70.6882)
		(end 111.8362 -70.612)
		(width 0.3048)
		(layer "F.Cu")
		(net "GND")
	)
	(segment
		(start 34.6964 -32.0548)
		(end 34.671 -32.0802)
		(width 0.2794)
		(layer "F.Cu")
		(net "GND")
	)
	(segment
		(start 91.44889 -40.800274)
		(end 91.078304 -41.17086)
		(width 0.254)
		(layer "F.Cu")
		(net "GND")
	)
	(segment
		(start 23.5204 -50.0888)
		(end 24.3078 -50.0888)
		(width 0.3048)
		(layer "F.Cu")
		(net "GND")
	)
	(segment
		(start 82.3214 -40.0558)
		(end 82.290412 -40.0558)
		(width 0.254)
		(layer "F.Cu")
		(net "GND")
	)
	(segment
		(start 109.931708 -47.091346)
		(end 110.4138 -47.091346)
		(width 0.254)
		(layer "F.Cu")
		(net "GND")
	)
	(segment
		(start 74.5236 -39.1414)
		(end 74.4982 -39.1668)
		(width 0.3048)
		(layer "F.Cu")
		(net "GND")
	)
	(segment
		(start 79.568548 -35.999674)
		(end 78.994 -35.999674)
		(width 0.254)
		(layer "F.Cu")
		(net "GND")
	)
	(segment
		(start 147.50923 -47.5107)
		(end 147.50923 -47.66183)
		(width 0.3048)
		(layer "F.Cu")
		(net "GND")
	)
	(segment
		(start 81.097628 -47.422054)
		(end 81.097628 -47.001938)
		(width 0.254)
		(layer "F.Cu")
		(net "GND")
	)
	(segment
		(start 38.671754 -21.55444)
		(end 36.37788 -21.55444)
		(width 0.2794)
		(layer "F.Cu")
		(net "GND")
	)
	(segment
		(start 81.785968 -34.081974)
		(end 81.788 -34.084006)
		(width 0.254)
		(layer "F.Cu")
		(net "GND")
	)
	(segment
		(start 42.10177 -27.55519)
		(end 40.936926 -27.55519)
		(width 0.2794)
		(layer "F.Cu")
		(net "GND")
	)
	(segment
		(start 181.356 -2.973578)
		(end 181.356 -3.151378)
		(width 0.254)
		(layer "F.Cu")
		(net "GND")
	)
	(segment
		(start 51.8668 -24.2062)
		(end 51.435 -24.638)
		(width 0.3048)
		(layer "F.Cu")
		(net "GND")
	)
	(segment
		(start 98.989134 -36.45916)
		(end 98.989134 -36.40328)
		(width 0.3048)
		(layer "F.Cu")
		(net "GND")
	)
	(segment
		(start 80.551528 -27.714194)
		(end 80.540606 -27.714194)
		(width 0.3048)
		(layer "F.Cu")
		(net "GND")
	)
	(segment
		(start 185.82259 -50.82159)
		(end 186.436 -51.435)
		(width 0.3048)
		(layer "F.Cu")
		(net "GND")
	)
	(segment
		(start 142.49781 -46.068742)
		(end 141.986 -46.580552)
		(width 0.3048)
		(layer "F.Cu")
		(net "GND")
	)
	(segment
		(start 188.05017 -64.0588)
		(end 187.89777 -64.2112)
		(width 0.254)
		(layer "F.Cu")
		(net "GND")
	)
	(segment
		(start 84.365846 -39.066724)
		(end 84.37499 -39.066724)
		(width 0.254)
		(layer "F.Cu")
		(net "GND")
	)
	(segment
		(start 72.43826 -32.89554)
		(end 72.4154 -32.89554)
		(width 0.3048)
		(layer "F.Cu")
		(net "GND")
	)
	(segment
		(start 189.55004 -70.806564)
		(end 189.55004 -69.434964)
		(width 0.254)
		(layer "F.Cu")
		(net "GND")
	)
	(segment
		(start 90.707718 -40.800274)
		(end 91.078304 -41.17086)
		(width 0.254)
		(layer "F.Cu")
		(net "GND")
	)
	(segment
		(start 90.400124 -27.667712)
		(end 90.396314 -27.667712)
		(width 0.3048)
		(layer "F.Cu")
		(net "GND")
	)
	(segment
		(start 69.30644 -49.08804)
		(end 68.62445 -48.40605)
		(width 0.3048)
		(layer "F.Cu")
		(net "GND")
	)
	(segment
		(start 85.18906 -35.856926)
		(end 84.790788 -35.458654)
		(width 0.254)
		(layer "F.Cu")
		(net "GND")
	)
	(segment
		(start 94.333568 -31.48457)
		(end 93.98 -31.131002)
		(width 0.3048)
		(layer "F.Cu")
		(net "GND")
	)
	(segment
		(start 110.391448 -43.807126)
		(end 109.908848 -43.807126)
		(width 0.254)
		(layer "F.Cu")
		(net "GND")
	)
	(segment
		(start 138.49858 -23.010114)
		(end 138.772646 -22.736048)
		(width 0.3048)
		(layer "F.Cu")
		(net "GND")
	)
	(segment
		(start 46.34992 -9.06272)
		(end 46.863 -9.5758)
		(width 0.7112)
		(layer "F.Cu")
		(net "GND")
	)
	(segment
		(start 141.550136 -69.904864)
		(end 142.1384 -69.3166)
		(width 0.3048)
		(layer "F.Cu")
		(net "GND")
	)
	(segment
		(start 90.107008 -27.996134)
		(end 90.231468 -28.120594)
		(width 0.3048)
		(layer "F.Cu")
		(net "GND")
	)
	(segment
		(start 101.051868 -35.999674)
		(end 100.95357 -36.097972)
		(width 0.3048)
		(layer "F.Cu")
		(net "GND")
	)
	(segment
		(start 174.55007 -69.434964)
		(end 174.671228 -69.313806)
		(width 0.254)
		(layer "F.Cu")
		(net "GND")
	)
	(segment
		(start 172.150024 -69.915024)
		(end 171.6024 -69.3674)
		(width 0.254)
		(layer "F.Cu")
		(net "GND")
	)
	(segment
		(start 84.028788 -34.757614)
		(end 84.028788 -34.701988)
		(width 0.254)
		(layer "F.Cu")
		(net "GND")
	)
	(segment
		(start 81.785968 -43.088814)
		(end 82.08391 -43.386756)
		(width 0.254)
		(layer "F.Cu")
		(net "GND")
	)
	(segment
		(start 87.06104 -47.70374)
		(end 87.434928 -47.329852)
		(width 0.254)
		(layer "F.Cu")
		(net "GND")
	)
	(segment
		(start 97.048828 -36.799774)
		(end 97.048828 -36.799266)
		(width 0.3048)
		(layer "F.Cu")
		(net "GND")
	)
	(segment
		(start 99.451668 -39.199566)
		(end 99.452938 -39.199566)
		(width 0.3048)
		(layer "F.Cu")
		(net "GND")
	)
	(segment
		(start 81.34985 -9.010142)
		(end 80.784192 -9.5758)
		(width 0.7112)
		(layer "F.Cu")
		(net "GND")
	)
	(segment
		(start 20.881594 -9.587738)
		(end 21.368004 -9.101328)
		(width 0.7112)
		(layer "F.Cu")
		(net "GND")
	)
	(segment
		(start 100.249228 -39.200074)
		(end 100.249228 -39.199566)
		(width 0.3048)
		(layer "F.Cu")
		(net "GND")
	)
	(segment
		(start 115.8748 -69.9516)
		(end 115.9002 -69.9262)
		(width 0.3048)
		(layer "F.Cu")
		(net "GND")
	)
	(segment
		(start 95.618808 -28.854654)
		(end 95.618808 -28.865068)
		(width 0.3048)
		(layer "F.Cu")
		(net "GND")
	)
	(segment
		(start 172.449998 -9.897364)
		(end 172.449998 -9.063482)
		(width 0.254)
		(layer "F.Cu")
		(net "GND")
	)
	(segment
		(start 145.3642 -64.0588)
		(end 145.3261 -64.0588)
		(width 0.254)
		(layer "F.Cu")
		(net "GND")
	)
	(segment
		(start 88.13546 -45.734986)
		(end 88.11768 -45.734986)
		(width 0.254)
		(layer "F.Cu")
		(net "GND")
	)
	(segment
		(start 103.124 -41.300146)
		(end 103.124 -41.316402)
		(width 0.254)
		(layer "F.Cu")
		(net "GND")
	)
	(segment
		(start 38.813994 -21.4122)
		(end 38.671754 -21.55444)
		(width 0.2794)
		(layer "F.Cu")
		(net "GND")
	)
	(segment
		(start 74.367898 -9.166098)
		(end 74.803 -9.6012)
		(width 0.7112)
		(layer "F.Cu")
		(net "GND")
	)
	(segment
		(start 79.982822 -33.89376)
		(end 79.480918 -33.89376)
		(width 0.254)
		(layer "F.Cu")
		(net "GND")
	)
	(segment
		(start 79.601568 -42.161714)
		(end 79.601568 -42.161206)
		(width 0.254)
		(layer "F.Cu")
		(net "GND")
	)
	(segment
		(start 183.1848 -35.56)
		(end 184.705498 -35.56)
		(width 0.3048)
		(layer "F.Cu")
		(net "GND")
	)
	(segment
		(start 98.3107 -39.537894)
		(end 98.64852 -39.200074)
		(width 0.3048)
		(layer "F.Cu")
		(net "GND")
	)
	(segment
		(start 105.766108 -37.718492)
		(end 105.4354 -38.0492)
		(width 0.254)
		(layer "F.Cu")
		(net "GND")
	)
	(segment
		(start 113.1062 -69.6976)
		(end 113.1062 -69.9516)
		(width 0.3048)
		(layer "F.Cu")
		(net "GND")
	)
	(segment
		(start 97.945194 -42.4942)
		(end 97.851468 -42.400474)
		(width 0.254)
		(layer "F.Cu")
		(net "GND")
	)
	(segment
		(start 96.6216 -34.017712)
		(end 96.72955 -34.017712)
		(width 0.3048)
		(layer "F.Cu")
		(net "GND")
	)
	(segment
		(start 90.061288 -51.447954)
		(end 90.061288 -50.844958)
		(width 0.254)
		(layer "F.Cu")
		(net "GND")
	)
	(segment
		(start 95.618808 -30.378654)
		(end 95.618808 -30.390084)
		(width 0.3048)
		(layer "F.Cu")
		(net "GND")
	)
	(segment
		(start 85.01761 -45.9486)
		(end 85.01888 -45.94987)
		(width 0.254)
		(layer "F.Cu")
		(net "GND")
	)
	(segment
		(start 62.349888 -8.951976)
		(end 62.865 -9.467088)
		(width 0.7112)
		(layer "F.Cu")
		(net "GND")
	)
	(segment
		(start 96.64954 -47.117)
		(end 97.127822 -47.117)
		(width 0.3048)
		(layer "F.Cu")
		(net "GND")
	)
	(segment
		(start 133.604 -3.042412)
		(end 133.604 -3.176778)
		(width 0.3048)
		(layer "F.Cu")
		(net "GND")
	)
	(segment
		(start 99.677474 -25.9334)
		(end 99.665028 -25.945846)
		(width 0.254)
		(layer "F.Cu")
		(net "GND")
	)
	(segment
		(start 34.349944 -6.195568)
		(end 34.367978 -6.213602)
		(width 0.7112)
		(layer "F.Cu")
		(net "GND")
	)
	(segment
		(start 106.190288 -52.448206)
		(end 106.190288 -52.448714)
		(width 0.254)
		(layer "F.Cu")
		(net "GND")
	)
	(segment
		(start 84.04098 -33.13938)
		(end 84.04098 -33.15716)
		(width 0.254)
		(layer "F.Cu")
		(net "GND")
	)
	(segment
		(start 101.051868 -39.200074)
		(end 101.051868 -39.199566)
		(width 0.3048)
		(layer "F.Cu")
		(net "GND")
	)
	(segment
		(start 46.5328 -18.415)
		(end 46.5582 -18.4404)
		(width 0.3048)
		(layer "F.Cu")
		(net "GND")
	)
	(segment
		(start 85.01888 -45.94987)
		(end 85.01888 -45.97908)
		(width 0.254)
		(layer "F.Cu")
		(net "GND")
	)
	(segment
		(start 109.863128 -36.014914)
		(end 110.491016 -36.09594)
		(width 0.254)
		(layer "F.Cu")
		(net "GND")
	)
	(segment
		(start 81.308448 -39.095934)
		(end 81.308448 -39.095426)
		(width 0.254)
		(layer "F.Cu")
		(net "GND")
	)
	(segment
		(start 186.26328 -48.26)
		(end 186.817 -48.26)
		(width 0.3048)
		(layer "F.Cu")
		(net "GND")
	)
	(segment
		(start 80.607408 -40.304974)
		(end 80.58277 -40.304974)
		(width 0.2032)
		(layer "F.Cu")
		(net "GND")
	)
	(segment
		(start 181.150006 -1.68402)
		(end 181.150006 -2.767584)
		(width 0.254)
		(layer "F.Cu")
		(net "GND")
	)
	(segment
		(start 187.449968 -8.531606)
		(end 187.575698 -8.405876)
		(width 0.254)
		(layer "F.Cu")
		(net "GND")
	)
	(segment
		(start 164.650166 -62.59322)
		(end 164.650166 -63.975234)
		(width 0.3048)
		(layer "F.Cu")
		(net "GND")
	)
	(segment
		(start 89.047828 -33.698434)
		(end 89.047828 -32.431228)
		(width 0.3048)
		(layer "F.Cu")
		(net "GND")
	)
	(segment
		(start 61.595 -41.424098)
		(end 61.16701 -40.996108)
		(width 0.3048)
		(layer "F.Cu")
		(net "GND")
	)
	(segment
		(start 98.298 -39.5859)
		(end 98.3107 -39.5732)
		(width 0.3048)
		(layer "F.Cu")
		(net "GND")
	)
	(segment
		(start 104.09936 -41.097962)
		(end 104.02824 -41.097962)
		(width 0.254)
		(layer "F.Cu")
		(net "GND")
	)
	(segment
		(start 186.673998 -63.87084)
		(end 186.673998 -64.2874)
		(width 0.254)
		(layer "F.Cu")
		(net "GND")
	)
	(segment
		(start 75.437238 -41.6052)
		(end 75.462638 -41.5798)
		(width 0.3048)
		(layer "F.Cu")
		(net "GND")
	)
	(segment
		(start 102.795832 -37.683186)
		(end 103.134668 -37.34435)
		(width 0.3048)
		(layer "F.Cu")
		(net "GND")
	)
	(segment
		(start 149.049994 -8.788654)
		(end 148.7297 -8.46836)
		(width 0.254)
		(layer "F.Cu")
		(net "GND")
	)
	(segment
		(start 88.0364 -30.7594)
		(end 88.374728 -31.097728)
		(width 0.3048)
		(layer "F.Cu")
		(net "GND")
	)
	(segment
		(start 84.409788 -33.472374)
		(end 84.389214 -33.472374)
		(width 0.254)
		(layer "F.Cu")
		(net "GND")
	)
	(segment
		(start 107.569 -64.7192)
		(end 107.6706 -64.8208)
		(width 0.3048)
		(layer "F.Cu")
		(net "GND")
	)
	(segment
		(start 140.99794 -44.323)
		(end 141.27988 -44.04106)
		(width 0.3048)
		(layer "F.Cu")
		(net "GND")
	)
	(segment
		(start 104.19969 -36.033456)
		(end 104.216708 -36.033456)
		(width 0.3048)
		(layer "F.Cu")
		(net "GND")
	)
	(segment
		(start 44.7548 -61.214)
		(end 44.9072 -61.3664)
		(width 0.508)
		(layer "F.Cu")
		(net "GND")
	)
	(segment
		(start 188.949838 -2.807462)
		(end 189.2554 -3.113024)
		(width 0.254)
		(layer "F.Cu")
		(net "GND")
	)
	(segment
		(start 103.480108 -36.982146)
		(end 103.895652 -36.566602)
		(width 0.3048)
		(layer "F.Cu")
		(net "GND")
	)
	(segment
		(start 82.87766 -41.416986)
		(end 82.538062 -41.077388)
		(width 0.254)
		(layer "F.Cu")
		(net "GND")
	)
	(segment
		(start 105.474008 -51.953414)
		(end 105.4862 -51.965606)
		(width 0.254)
		(layer "F.Cu")
		(net "GND")
	)
	(segment
		(start 105.4862 -52.373784)
		(end 105.753662 -52.641246)
		(width 0.254)
		(layer "F.Cu")
		(net "GND")
	)
	(segment
		(start 176.350168 -69.674232)
		(end 176.657 -69.3674)
		(width 0.254)
		(layer "F.Cu")
		(net "GND")
	)
	(segment
		(start 91.646248 -33.426654)
		(end 91.646248 -33.382458)
		(width 0.3048)
		(layer "F.Cu")
		(net "GND")
	)
	(segment
		(start 83.454748 -50.279554)
		(end 83.429348 -50.304954)
		(width 0.254)
		(layer "F.Cu")
		(net "GND")
	)
	(segment
		(start 101.792786 -41.599866)
		(end 101.421692 -41.97096)
		(width 0.254)
		(layer "F.Cu")
		(net "GND")
	)
	(segment
		(start 95.692468 -46.107096)
		(end 95.692468 -46.047914)
		(width 0.3048)
		(layer "F.Cu")
		(net "GND")
	)
	(segment
		(start 103.844598 -38.051486)
		(end 103.874316 -38.051486)
		(width 0.3048)
		(layer "F.Cu")
		(net "GND")
	)
	(segment
		(start 66.367914 -6.213602)
		(end 66.367914 -9.116314)
		(width 0.7112)
		(layer "F.Cu")
		(net "GND")
	)
	(segment
		(start 138.418316 -46.63313)
		(end 138.38809 -46.602904)
		(width 0.3048)
		(layer "F.Cu")
		(net "GND")
	)
	(segment
		(start 99.786948 -27.404314)
		(end 99.271836 -27.404314)
		(width 0.254)
		(layer "F.Cu")
		(net "GND")
	)
	(segment
		(start 46.609 -34.544)
		(end 46.2788 -34.8742)
		(width 0.3048)
		(layer "F.Cu")
		(net "GND")
	)
	(segment
		(start 106.577384 -28.819602)
		(end 107.400852 -27.996134)
		(width 0.254)
		(layer "F.Cu")
		(net "GND")
	)
	(segment
		(start 130.64744 -3.129788)
		(end 130.64744 -3.153918)
		(width 0.3048)
		(layer "F.Cu")
		(net "GND")
	)
	(segment
		(start 187.749942 -70.806564)
		(end 187.749942 -69.463412)
		(width 0.254)
		(layer "F.Cu")
		(net "GND")
	)
	(segment
		(start 103.741728 -28.120594)
		(end 103.172768 -28.120594)
		(width 0.254)
		(layer "F.Cu")
		(net "GND")
	)
	(segment
		(start 110.683548 -44.566586)
		(end 110.602268 -44.485306)
		(width 0.254)
		(layer "F.Cu")
		(net "GND")
	)
	(segment
		(start 90.241628 -26.957274)
		(end 90.241628 -26.956766)
		(width 0.3048)
		(layer "F.Cu")
		(net "GND")
	)
	(segment
		(start 91.8718 -37.223446)
		(end 92.248228 -37.599874)
		(width 0.254)
		(layer "F.Cu")
		(net "GND")
	)
	(segment
		(start 41.34993 -6.195568)
		(end 41.367964 -6.213602)
		(width 0.7112)
		(layer "F.Cu")
		(net "GND")
	)
	(segment
		(start 109.857286 -31.511494)
		(end 109.603286 -31.765494)
		(width 0.254)
		(layer "F.Cu")
		(net "GND")
	)
	(segment
		(start 131.350004 -1.68402)
		(end 131.350004 -2.543302)
		(width 0.3048)
		(layer "F.Cu")
		(net "GND")
	)
	(segment
		(start 95.618808 -31.902654)
		(end 95.618808 -31.879794)
		(width 0.3048)
		(layer "F.Cu")
		(net "GND")
	)
	(segment
		(start 50.0888 -18.415)
		(end 50.0888 -17.526)
		(width 0.3048)
		(layer "F.Cu")
		(net "GND")
	)
	(segment
		(start 96.319848 -28.854654)
		(end 95.9612 -28.496006)
		(width 0.3048)
		(layer "F.Cu")
		(net "GND")
	)
	(segment
		(start 98.555302 -42.4942)
		(end 97.945194 -42.4942)
		(width 0.254)
		(layer "F.Cu")
		(net "GND")
	)
	(segment
		(start 36.37788 -27.55519)
		(end 37.74059 -27.55519)
		(width 0.2794)
		(layer "F.Cu")
		(net "GND")
	)
	(segment
		(start 164.698172 -41.321228)
		(end 164.719 -41.3004)
		(width 0.3048)
		(layer "F.Cu")
		(net "GND")
	)
	(segment
		(start 101.849428 -33.698434)
		(end 101.78923 -33.698434)
		(width 0.254)
		(layer "F.Cu")
		(net "GND")
	)
	(segment
		(start 100.249228 -42.399966)
		(end 100.249228 -42.400474)
		(width 0.254)
		(layer "F.Cu")
		(net "GND")
	)
	(segment
		(start 134.649972 -62.59322)
		(end 134.649972 -63.343028)
		(width 0.254)
		(layer "F.Cu")
		(net "GND")
	)
	(segment
		(start 79.601568 -39.095934)
		(end 79.1464 -39.095934)
		(width 0.254)
		(layer "F.Cu")
		(net "GND")
	)
	(segment
		(start 82.2452 -48.8061)
		(end 82.052414 -48.613314)
		(width 0.254)
		(layer "F.Cu")
		(net "GND")
	)
	(segment
		(start 88.130888 -26.952194)
		(end 88.130888 -27.382724)
		(width 0.3048)
		(layer "F.Cu")
		(net "GND")
	)
	(segment
		(start 45.466 -30.6832)
		(end 45.2374 -30.4546)
		(width 0.3048)
		(layer "F.Cu")
		(net "GND")
	)
	(segment
		(start 131.949952 -70.806564)
		(end 131.949952 -69.962268)
		(width 0.254)
		(layer "F.Cu")
		(net "GND")
	)
	(segment
		(start 73.6092 -32.131)
		(end 73.6092 -32.893)
		(width 0.3048)
		(layer "F.Cu")
		(net "GND")
	)
	(segment
		(start 46.5582 -18.4404)
		(end 46.5582 -19.177)
		(width 0.3048)
		(layer "F.Cu")
		(net "GND")
	)
	(segment
		(start 37.9984 -27.813)
		(end 37.9984 -28.20162)
		(width 0.2794)
		(layer "F.Cu")
		(net "GND")
	)
	(segment
		(start 110.335568 -26.088594)
		(end 110.335568 -25.526746)
		(width 0.3048)
		(layer "F.Cu")
		(net "GND")
	)
	(segment
		(start 103.427276 -33.290002)
		(end 102.997 -33.290002)
		(width 0.254)
		(layer "F.Cu")
		(net "GND")
	)
	(segment
		(start 164.349938 -69.934836)
		(end 164.665914 -69.61886)
		(width 0.3048)
		(layer "F.Cu")
		(net "GND")
	)
	(segment
		(start 98.298 -36.39312)
		(end 98.244914 -36.39312)
		(width 0.3048)
		(layer "F.Cu")
		(net "GND")
	)
	(segment
		(start 133.149848 -1.68402)
		(end 133.149848 -2.58826)
		(width 0.3048)
		(layer "F.Cu")
		(net "GND")
	)
	(segment
		(start 110.632748 -28.387294)
		(end 110.749588 -28.504134)
		(width 0.254)
		(layer "F.Cu")
		(net "GND")
	)
	(segment
		(start 109.296708 -28.472892)
		(end 109.461808 -28.307792)
		(width 0.254)
		(layer "F.Cu")
		(net "GND")
	)
	(segment
		(start 85.159088 -27.269694)
		(end 85.128608 -27.300174)
		(width 0.254)
		(layer "F.Cu")
		(net "GND")
	)
	(segment
		(start 78.01737 -59.16803)
		(end 76.8731 -59.16803)
		(width 0.3048)
		(layer "F.Cu")
		(net "GND")
	)
	(segment
		(start 140.349986 -2.754884)
		(end 140.64488 -3.049778)
		(width 0.254)
		(layer "F.Cu")
		(net "GND")
	)
	(segment
		(start 81.026 -56.1848)
		(end 78.5622 -58.6486)
		(width 0.3048)
		(layer "F.Cu")
		(net "GND")
	)
	(segment
		(start 88.374728 -28.854654)
		(end 89.09939 -28.854654)
		(width 0.3048)
		(layer "F.Cu")
		(net "GND")
	)
	(segment
		(start 127.2286 -39.9034)
		(end 127.2286 -46.5836)
		(width 0.3048)
		(layer "F.Cu")
		(net "GND")
	)
	(segment
		(start 109.2962 -64.7192)
		(end 107.569 -64.7192)
		(width 0.3048)
		(layer "F.Cu")
		(net "GND")
	)
	(segment
		(start 97.605088 -33.025842)
		(end 97.605088 -33.045654)
		(width 0.254)
		(layer "F.Cu")
		(net "GND")
	)
	(segment
		(start 179.95011 -70.806564)
		(end 179.95011 -69.902324)
		(width 0.254)
		(layer "F.Cu")
		(net "GND")
	)
	(segment
		(start 98.832416 -36.615878)
		(end 98.989134 -36.45916)
		(width 0.3048)
		(layer "F.Cu")
		(net "GND")
	)
	(segment
		(start 90.648028 -39.237412)
		(end 90.31224 -39.5732)
		(width 0.254)
		(layer "F.Cu")
		(net "GND")
	)
	(segment
		(start 98.649028 -36.799774)
		(end 98.832416 -36.616386)
		(width 0.3048)
		(layer "F.Cu")
		(net "GND")
	)
	(segment
		(start 156.7688 -52.17033)
		(end 156.7688 -52.832)
		(width 0.254)
		(layer "F.Cu")
		(net "GND")
	)
	(segment
		(start 81.016348 -33.833054)
		(end 80.043528 -33.833054)
		(width 0.254)
		(layer "F.Cu")
		(net "GND")
	)
	(segment
		(start 87.434928 -44.973494)
		(end 87.434928 -45.05198)
		(width 0.254)
		(layer "F.Cu")
		(net "GND")
	)
	(segment
		(start 4.572 -50.8762)
		(end 4.2672 -50.8762)
		(width 0.3048)
		(layer "F.Cu")
		(net "GND")
	)
	(segment
		(start 99.238308 -28.120594)
		(end 99.238308 -27.447494)
		(width 0.254)
		(layer "F.Cu")
		(net "GND")
	)
	(segment
		(start 43.18 -41.400984)
		(end 43.18 -41.55948)
		(width 0.3048)
		(layer "F.Cu")
		(net "GND")
	)
	(segment
		(start 90.396314 -27.667712)
		(end 90.21445 -27.485848)
		(width 0.3048)
		(layer "F.Cu")
		(net "GND")
	)
	(segment
		(start 91.496642 -42.3545)
		(end 92.202254 -42.3545)
		(width 0.254)
		(layer "F.Cu")
		(net "GND")
	)
	(segment
		(start 82.954368 -28.135834)
		(end 82.954368 -27.617674)
		(width 0.254)
		(layer "F.Cu")
		(net "GND")
	)
	(segment
		(start 149.5552 -52.2986)
		(end 149.5552 -52.2478)
		(width 0.3048)
		(layer "F.Cu")
		(net "GND")
	)
	(segment
		(start 169.450004 -62.59322)
		(end 169.450004 -63.333884)
		(width 0.254)
		(layer "F.Cu")
		(net "GND")
	)
	(segment
		(start 90.932 -29.664914)
		(end 90.932 -29.337)
		(width 0.3048)
		(layer "F.Cu")
		(net "GND")
	)
	(segment
		(start 90.061288 -50.844958)
		(end 90.0938 -50.812446)
		(width 0.254)
		(layer "F.Cu")
		(net "GND")
	)
	(segment
		(start 55.6768 -39.878)
		(end 58.928 -39.878)
		(width 0.3048)
		(layer "F.Cu")
		(net "GND")
	)
	(segment
		(start 166.37 -24.13)
		(end 166.4208 -24.13)
		(width 0.508)
		(layer "F.Cu")
		(net "GND")
	)
	(segment
		(start 66.4718 -11.4554)
		(end 66.5226 -11.4046)
		(width 0.3048)
		(layer "F.Cu")
		(net "GND")
	)
	(segment
		(start 112.625378 -70.432422)
		(end 112.625378 -70.584822)
		(width 0.3048)
		(layer "F.Cu")
		(net "GND")
	)
	(segment
		(start 105.5878 -36.3474)
		(end 105.5878 -36.15055)
		(width 0.254)
		(layer "F.Cu")
		(net "GND")
	)
	(segment
		(start 94.64929 -34.399474)
		(end 94.278704 -34.77006)
		(width 0.3048)
		(layer "F.Cu")
		(net "GND")
	)
	(segment
		(start 70.367906 -9.052306)
		(end 70.8152 -9.4996)
		(width 0.7112)
		(layer "F.Cu")
		(net "GND")
	)
	(segment
		(start 85.448648 -49.164494)
		(end 85.448648 -49.202848)
		(width 0.254)
		(layer "F.Cu")
		(net "GND")
	)
	(segment
		(start 172.749972 -69.464428)
		(end 172.8216 -69.3928)
		(width 0.254)
		(layer "F.Cu")
		(net "GND")
	)
	(segment
		(start 90.868246 -28.135834)
		(end 90.400124 -27.667712)
		(width 0.3048)
		(layer "F.Cu")
		(net "GND")
	)
	(segment
		(start 164.719 -41.372028)
		(end 164.698172 -41.3512)
		(width 0.3048)
		(layer "F.Cu")
		(net "GND")
	)
	(segment
		(start 40.64889 -23.05558)
		(end 40.15867 -23.5458)
		(width 0.2794)
		(layer "F.Cu")
		(net "GND")
	)
	(segment
		(start 81.097628 -47.001938)
		(end 81.287366 -46.8122)
		(width 0.254)
		(layer "F.Cu")
		(net "GND")
	)
	(segment
		(start 91.425268 -28.174696)
		(end 91.922346 -28.174696)
		(width 0.3048)
		(layer "F.Cu")
		(net "GND")
	)
	(segment
		(start 102.9589 -33.290002)
		(end 102.997 -33.290002)
		(width 0.254)
		(layer "F.Cu")
		(net "GND")
	)
	(segment
		(start 150.10765 -46.55185)
		(end 150.10765 -46.33595)
		(width 0.3048)
		(layer "F.Cu")
		(net "GND")
	)
	(segment
		(start 91.64574 -30.378146)
		(end 91.645232 -30.378146)
		(width 0.3048)
		(layer "F.Cu")
		(net "GND")
	)
	(segment
		(start 77.349858 -9.010142)
		(end 76.8604 -9.4996)
		(width 0.7112)
		(layer "F.Cu")
		(net "GND")
	)
	(segment
		(start 91.450668 -35.200336)
		(end 91.878404 -35.628072)
		(width 0.254)
		(layer "F.Cu")
		(net "GND")
	)
	(segment
		(start 89.3064 -50.206402)
		(end 89.3064 -49.279302)
		(width 0.254)
		(layer "F.Cu")
		(net "GND")
	)
	(segment
		(start 93.632528 -29.235654)
		(end 93.632528 -29.220922)
		(width 0.3048)
		(layer "F.Cu")
		(net "GND")
	)
	(segment
		(start 139.065 -3.024378)
		(end 139.065 -3.176778)
		(width 0.254)
		(layer "F.Cu")
		(net "GND")
	)
	(segment
		(start 187.2996 -16.5354)
		(end 186.4614 -16.5354)
		(width 0.3048)
		(layer "F.Cu")
		(net "GND")
	)
	(segment
		(start 91.645232 -30.378146)
		(end 90.932 -29.664914)
		(width 0.3048)
		(layer "F.Cu")
		(net "GND")
	)
	(segment
		(start 69.367908 -9.118092)
		(end 68.8848 -9.6012)
		(width 0.7112)
		(layer "F.Cu")
		(net "GND")
	)
	(segment
		(start 79.121 -39.070534)
		(end 79.099918 -39.070534)
		(width 0.254)
		(layer "F.Cu")
		(net "GND")
	)
	(segment
		(start 109.913928 -34.723832)
		(end 109.865668 -34.772092)
		(width 0.254)
		(layer "F.Cu")
		(net "GND")
	)
	(segment
		(start 89.3064 -42.4688)
		(end 89.3064 -42.415206)
		(width 0.3048)
		(layer "F.Cu")
		(net "GND")
	)
	(segment
		(start 84.724748 -29.235654)
		(end 84.721954 -29.23286)
		(width 0.3048)
		(layer "F.Cu")
		(net "GND")
	)
	(segment
		(start 89.543128 -50.213514)
		(end 89.352628 -50.404014)
		(width 0.254)
		(layer "F.Cu")
		(net "GND")
	)
	(segment
		(start 86.247732 -39.430706)
		(end 85.958934 -39.141908)
		(width 0.254)
		(layer "F.Cu")
		(net "GND")
	)
	(segment
		(start 88.519 -38.647878)
		(end 88.519 -37.933122)
		(width 0.254)
		(layer "F.Cu")
		(net "GND")
	)
	(segment
		(start 96.399604 -27.024584)
		(end 96.270826 -26.895806)
		(width 0.254)
		(layer "F.Cu")
		(net "GND")
	)
	(segment
		(start 127.199898 -20.955)
		(end 127.199898 -17.790668)
		(width 0.508)
		(layer "F.Cu")
		(net "GND")
	)
	(segment
		(start 98.544888 -27.996134)
		(end 98.298 -28.243022)
		(width 0.254)
		(layer "F.Cu")
		(net "GND")
	)
	(segment
		(start 106.398568 -25.778968)
		(end 106.1212 -25.5016)
		(width 0.254)
		(layer "F.Cu")
		(net "GND")
	)
	(segment
		(start 85.159088 -28.120594)
		(end 85.034628 -27.996134)
		(width 0.254)
		(layer "F.Cu")
		(net "GND")
	)
	(segment
		(start 81.308448 -39.095934)
		(end 81.366868 -39.037514)
		(width 0.254)
		(layer "F.Cu")
		(net "GND")
	)
	(segment
		(start 80.607408 -35.801554)
		(end 80.885792 -35.801554)
		(width 0.254)
		(layer "F.Cu")
		(net "GND")
	)
	(segment
		(start 187.149994 -70.806564)
		(end 187.149994 -69.979794)
		(width 0.254)
		(layer "F.Cu")
		(net "GND")
	)
	(segment
		(start 82.1817 -36.2839)
		(end 82.1817 -36.094416)
		(width 0.254)
		(layer "F.Cu")
		(net "GND")
	)
	(segment
		(start 93.6117 -31.521146)
		(end 93.274134 -31.858712)
		(width 0.3048)
		(layer "F.Cu")
		(net "GND")
	)
	(segment
		(start 39.13378 -27.6098)
		(end 38.27018 -28.4734)
		(width 0.2794)
		(layer "F.Cu")
		(net "GND")
	)
	(segment
		(start 96.319848 -32.664654)
		(end 95.618808 -32.664654)
		(width 0.3048)
		(layer "F.Cu")
		(net "GND")
	)
	(segment
		(start 152.349962 -2.873756)
		(end 152.627584 -3.151378)
		(width 0.3048)
		(layer "F.Cu")
		(net "GND")
	)
	(segment
		(start 167.0558 -31.877)
		(end 166.998904 -31.933896)
		(width 0.508)
		(layer "F.Cu")
		(net "GND")
	)
	(segment
		(start 97.451418 -36.399724)
		(end 97.38233 -36.399724)
		(width 0.3048)
		(layer "F.Cu")
		(net "GND")
	)
	(segment
		(start 81.646268 -32.031178)
		(end 81.646268 -32.001714)
		(width 0.254)
		(layer "F.Cu")
		(net "GND")
	)
	(segment
		(start 42.592752 -40.813736)
		(end 43.18 -41.400984)
		(width 0.3048)
		(layer "F.Cu")
		(net "GND")
	)
	(segment
		(start 93.076014 -42.400474)
		(end 93.076268 -42.40022)
		(width 0.254)
		(layer "F.Cu")
		(net "GND")
	)
	(segment
		(start 37.367972 -6.213602)
		(end 37.367972 -9.040876)
		(width 0.7112)
		(layer "F.Cu")
		(net "GND")
	)
	(segment
		(start 183.23433 -69.400928)
		(end 183.23433 -69.3674)
		(width 0.254)
		(layer "F.Cu")
		(net "GND")
	)
	(segment
		(start 85.789262 -29.1338)
		(end 85.687408 -29.235654)
		(width 0.3048)
		(layer "F.Cu")
		(net "GND")
	)
	(segment
		(start 109.527848 -26.896314)
		(end 110.335568 -26.088594)
		(width 0.254)
		(layer "F.Cu")
		(net "GND")
	)
	(segment
		(start 138.49858 -25.019)
		(end 138.49858 -23.9268)
		(width 0.3048)
		(layer "F.Cu")
		(net "GND")
	)
	(segment
		(start 92.347288 -33.426654)
		(end 92.347288 -33.423606)
		(width 0.3048)
		(layer "F.Cu")
		(net "GND")
	)
	(segment
		(start 91.018868 -41.992296)
		(end 91.088718 -41.992296)
		(width 0.254)
		(layer "F.Cu")
		(net "GND")
	)
	(segment
		(start 91.661488 -27.447494)
		(end 91.450668 -27.658314)
		(width 0.3048)
		(layer "F.Cu")
		(net "GND")
	)
	(segment
		(start 161.036 -35.4838)
		(end 161.61766 -35.4838)
		(width 0.508)
		(layer "F.Cu")
		(net "GND")
	)
	(segment
		(start 133.2738 -32.9692)
		(end 133.2738 -30.353)
		(width 0.3048)
		(layer "F.Cu")
		(net "GND")
	)
	(segment
		(start 95.350076 -9.245346)
		(end 95.3516 -9.24687)
		(width 0.7112)
		(layer "F.Cu")
		(net "GND")
	)
	(segment
		(start 94.278704 -34.82721)
		(end 94.278704 -34.77006)
		(width 0.3048)
		(layer "F.Cu")
		(net "GND")
	)
	(segment
		(start 148.149818 -1.68402)
		(end 148.149818 -2.604516)
		(width 0.254)
		(layer "F.Cu")
		(net "GND")
	)
	(segment
		(start 105.766108 -40.954706)
		(end 106.11739 -41.305988)
		(width 0.254)
		(layer "F.Cu")
		(net "GND")
	)
	(segment
		(start 80.73771 -38.686994)
		(end 80.695292 -38.686994)
		(width 0.254)
		(layer "F.Cu")
		(net "GND")
	)
	(segment
		(start 147.50923 -47.37227)
		(end 147.892516 -46.988984)
		(width 0.3048)
		(layer "F.Cu")
		(net "GND")
	)
	(segment
		(start 84.074 -31.88208)
		(end 84.14766 -31.95574)
		(width 0.3048)
		(layer "F.Cu")
		(net "GND")
	)
	(segment
		(start 69.596 -13.244576)
		(end 69.596 -14.1732)
		(width 0.3048)
		(layer "F.Cu")
		(net "GND")
	)
	(segment
		(start 82.237834 -28.135834)
		(end 82.6262 -28.5242)
		(width 0.254)
		(layer "F.Cu")
		(net "GND")
	)
	(segment
		(start 84.389214 -33.472374)
		(end 84.074 -33.15716)
		(width 0.254)
		(layer "F.Cu")
		(net "GND")
	)
	(segment
		(start 186.550046 -1.68402)
		(end 186.5376 -1.696466)
		(width 0.254)
		(layer "F.Cu")
		(net "GND")
	)
	(segment
		(start 101.051868 -33.698434)
		(end 101.132386 -33.698434)
		(width 0.254)
		(layer "F.Cu")
		(net "GND")
	)
	(segment
		(start 112.213644 -36.3474)
		(end 112.634522 -36.768278)
		(width 0.254)
		(layer "F.Cu")
		(net "GND")
	)
	(segment
		(start 82.538062 -41.063672)
		(end 82.538062 -41.077388)
		(width 0.254)
		(layer "F.Cu")
		(net "GND")
	)
	(segment
		(start 99.665028 -25.99563)
		(end 99.665028 -25.945846)
		(width 0.3048)
		(layer "F.Cu")
		(net "GND")
	)
	(segment
		(start 153.249884 -9.106662)
		(end 152.59812 -8.454898)
		(width 0.3048)
		(layer "F.Cu")
		(net "GND")
	)
	(segment
		(start 106.553254 -35.322002)
		(end 106.553 -35.322256)
		(width 0.254)
		(layer "F.Cu")
		(net "GND")
	)
	(segment
		(start 110.391448 -34.800794)
		(end 110.362746 -34.772092)
		(width 0.254)
		(layer "F.Cu")
		(net "GND")
	)
	(segment
		(start 98.989134 -36.33978)
		(end 98.989134 -36.40328)
		(width 0.3048)
		(layer "F.Cu")
		(net "GND")
	)
	(segment
		(start 90.31224 -39.599362)
		(end 90.274902 -39.6367)
		(width 0.254)
		(layer "F.Cu")
		(net "GND")
	)
	(segment
		(start 111.488728 -33.012634)
		(end 110.780068 -33.012634)
		(width 0.254)
		(layer "F.Cu")
		(net "GND")
	)
	(segment
		(start 107.673648 -26.560526)
		(end 107.673648 -26.561034)
		(width 0.254)
		(layer "F.Cu")
		(net "GND")
	)
	(segment
		(start 104.02824 -41.097962)
		(end 103.8606 -41.265602)
		(width 0.254)
		(layer "F.Cu")
		(net "GND")
	)
	(segment
		(start 90.361008 -31.558484)
		(end 90.000582 -31.91891)
		(width 0.3048)
		(layer "F.Cu")
		(net "GND")
	)
	(segment
		(start 94.651068 -33.698434)
		(end 94.651068 -34.399474)
		(width 0.3048)
		(layer "F.Cu")
		(net "GND")
	)
	(segment
		(start 141.849856 -9.897364)
		(end 141.849602 -9.89711)
		(width 0.254)
		(layer "F.Cu")
		(net "GND")
	)
	(segment
		(start 79.530194 -28.526994)
		(end 79.1464 -28.1432)
		(width 0.3048)
		(layer "F.Cu")
		(net "GND")
	)
	(segment
		(start 62.093602 -33.18637)
		(end 61.802772 -33.4772)
		(width 0.3048)
		(layer "F.Cu")
		(net "GND")
	)
	(segment
		(start 38.36797 -6.213602)
		(end 38.36797 -9.04748)
		(width 0.7112)
		(layer "F.Cu")
		(net "GND")
	)
	(segment
		(start 131.05003 -63.89243)
		(end 131.2164 -64.0588)
		(width 0.254)
		(layer "F.Cu")
		(net "GND")
	)
	(segment
		(start 174.93488 -64.0207)
		(end 174.93488 -64.03086)
		(width 0.254)
		(layer "F.Cu")
		(net "GND")
	)
	(segment
		(start 186.5376 -1.696466)
		(end 186.5376 -2.534158)
		(width 0.254)
		(layer "F.Cu")
		(net "GND")
	)
	(segment
		(start 110.780068 -33.012634)
		(end 110.749588 -32.982154)
		(width 0.254)
		(layer "F.Cu")
		(net "GND")
	)
	(segment
		(start 129.55016 -69.874384)
		(end 129.347976 -69.6722)
		(width 0.254)
		(layer "F.Cu")
		(net "GND")
	)
	(segment
		(start 112.625378 -70.584822)
		(end 112.522 -70.6882)
		(width 0.3048)
		(layer "F.Cu")
		(net "GND")
	)
	(segment
		(start 86.947248 -26.247598)
		(end 86.947248 -25.951434)
		(width 0.3048)
		(layer "F.Cu")
		(net "GND")
	)
	(segment
		(start 182.94985 -1.68402)
		(end 182.94985 -2.588768)
		(width 0.254)
		(layer "F.Cu")
		(net "GND")
	)
	(segment
		(start 90.241628 -27.45867)
		(end 90.21445 -27.485848)
		(width 0.3048)
		(layer "F.Cu")
		(net "GND")
	)
	(segment
		(start 166.998904 -31.933896)
		(end 165.284404 -31.933896)
		(width 0.508)
		(layer "F.Cu")
		(net "GND")
	)
	(segment
		(start 136.99744 -24.94788)
		(end 137.414 -25.36444)
		(width 0.3048)
		(layer "F.Cu")
		(net "GND")
	)
	(segment
		(start 110.391448 -43.807634)
		(end 110.391448 -43.807126)
		(width 0.254)
		(layer "F.Cu")
		(net "GND")
	)
	(segment
		(start 31.4452 -35.0012)
		(end 31.2166 -35.0012)
		(width 0.3048)
		(layer "F.Cu")
		(net "GND")
	)
	(segment
		(start 108.024676 -66.8655)
		(end 107.696 -66.536824)
		(width 0.3048)
		(layer "F.Cu")
		(net "GND")
	)
	(segment
		(start 84.845398 -45.014896)
		(end 84.815426 -45.014896)
		(width 0.3048)
		(layer "F.Cu")
		(net "GND")
	)
	(segment
		(start 147.50923 -47.66183)
		(end 147.928838 -48.081438)
		(width 0.3048)
		(layer "F.Cu")
		(net "GND")
	)
	(segment
		(start 135.8392 -9.03351)
		(end 135.265668 -8.459978)
		(width 0.3048)
		(layer "F.Cu")
		(net "GND")
	)
	(segment
		(start 149.5552 -52.2478)
		(end 150.4442 -51.3588)
		(width 0.3048)
		(layer "F.Cu")
		(net "GND")
	)
	(segment
		(start 130.750056 -3.027172)
		(end 130.64744 -3.129788)
		(width 0.3048)
		(layer "F.Cu")
		(net "GND")
	)
	(segment
		(start 82.6389 -29.252926)
		(end 82.885788 -29.499814)
		(width 0.3048)
		(layer "F.Cu")
		(net "GND")
	)
	(segment
		(start 87.011002 -37.12972)
		(end 87.09152 -37.12972)
		(width 0.254)
		(layer "F.Cu")
		(net "GND")
	)
	(segment
		(start 84.365846 -39.094156)
		(end 84.365846 -39.066724)
		(width 0.254)
		(layer "F.Cu")
		(net "GND")
	)
	(segment
		(start 81.933288 -28.135834)
		(end 82.237834 -28.135834)
		(width 0.254)
		(layer "F.Cu")
		(net "GND")
	)
	(segment
		(start 101.051868 -41.600374)
		(end 101.051868 -41.601136)
		(width 0.254)
		(layer "F.Cu")
		(net "GND")
	)
	(segment
		(start 66.367914 -9.116314)
		(end 66.8274 -9.5758)
		(width 0.7112)
		(layer "F.Cu")
		(net "GND")
	)
	(segment
		(start 113.1062 -69.9516)
		(end 112.625378 -70.432422)
		(width 0.3048)
		(layer "F.Cu")
		(net "GND")
	)
	(segment
		(start 141.249908 -9.897364)
		(end 141.249908 -9.158986)
		(width 0.254)
		(layer "F.Cu")
		(net "GND")
	)
	(segment
		(start 89.850468 -37.599874)
		(end 89.871296 -37.599874)
		(width 0.254)
		(layer "F.Cu")
		(net "GND")
	)
	(segment
		(start 33.6804 -40.259)
		(end 33.7058 -40.2844)
		(width 0.508)
		(layer "F.Cu")
		(net "GND")
	)
	(segment
		(start 87.457788 -40.716454)
		(end 87.388192 -40.716454)
		(width 0.254)
		(layer "F.Cu")
		(net "GND")
	)
	(segment
		(start 82.290412 -40.0558)
		(end 81.841086 -39.606474)
		(width 0.254)
		(layer "F.Cu")
		(net "GND")
	)
	(segment
		(start 147.50923 -47.5107)
		(end 147.50923 -47.37227)
		(width 0.3048)
		(layer "F.Cu")
		(net "GND")
	)
	(segment
		(start 132.850128 -62.59322)
		(end 132.850128 -63.441072)
		(width 0.254)
		(layer "F.Cu")
		(net "GND")
	)
	(segment
		(start 89.887806 -40.000174)
		(end 90.25128 -39.6367)
		(width 0.254)
		(layer "F.Cu")
		(net "GND")
	)
	(segment
		(start 43.5356 -32.0548)
		(end 42.10177 -32.0548)
		(width 0.2794)
		(layer "F.Cu")
		(net "GND")
	)
	(segment
		(start 104.026208 -45.734986)
		(end 103.672386 -45.381164)
		(width 0.254)
		(layer "F.Cu")
		(net "GND")
	)
	(segment
		(start 113.040922 -69.327522)
		(end 113.040922 -69.632322)
		(width 0.3048)
		(layer "F.Cu")
		(net "GND")
	)
	(segment
		(start 73.6092 -32.893)
		(end 72.8472 -32.893)
		(width 0.3048)
		(layer "F.Cu")
		(net "GND")
	)
	(segment
		(start 104.958388 -25.595326)
		(end 104.8131 -25.450038)
		(width 0.254)
		(layer "F.Cu")
		(net "GND")
	)
	(segment
		(start 160.528 -51.3969)
		(end 158.547308 -51.3969)
		(width 0.254)
		(layer "F.Cu")
		(net "GND")
	)
	(segment
		(start 17.349978 -6.195568)
		(end 17.35201 -6.1976)
		(width 0.7112)
		(layer "F.Cu")
		(net "GND")
	)
	(segment
		(start 79.273146 -66.496946)
		(end 79.121 -66.3448)
		(width 0.3048)
		(layer "F.Cu")
		(net "GND")
	)
	(segment
		(start 89.538048 -27.996134)
		(end 89.529666 -27.996134)
		(width 0.3048)
		(layer "F.Cu")
		(net "GND")
	)
	(segment
		(start 140.64996 -62.59322)
		(end 140.64996 -63.94704)
		(width 0.254)
		(layer "F.Cu")
		(net "GND")
	)
	(segment
		(start 42.10177 -26.05532)
		(end 44.19092 -26.05532)
		(width 0.2794)
		(layer "F.Cu")
		(net "GND")
	)
	(segment
		(start 140.99794 -22.95906)
		(end 140.99794 -23.9268)
		(width 0.3048)
		(layer "F.Cu")
		(net "GND")
	)
	(segment
		(start 45.4152 -32.568896)
		(end 45.4152 -32.4358)
		(width 0.381)
		(layer "F.Cu")
		(net "GND")
	)
	(segment
		(start 101.051868 -36.799774)
		(end 101.148642 -36.703)
		(width 0.3048)
		(layer "F.Cu")
		(net "GND")
	)
	(segment
		(start 146.950176 -69.55917)
		(end 146.719544 -69.328538)
		(width 0.254)
		(layer "F.Cu")
		(net "GND")
	)
	(segment
		(start 34.671 -25.089104)
		(end 34.671 -25.786842)
		(width 0.2794)
		(layer "F.Cu")
		(net "GND")
	)
	(segment
		(start 127.508 -22.606)
		(end 127.508 -21.263102)
		(width 0.508)
		(layer "F.Cu")
		(net "GND")
	)
	(segment
		(start 111.097568 -40.484806)
		(end 111.51108 -40.484806)
		(width 0.254)
		(layer "F.Cu")
		(net "GND")
	)
	(segment
		(start 36.37788 -32.0548)
		(end 34.6964 -32.0548)
		(width 0.2794)
		(layer "F.Cu")
		(net "GND")
	)
	(segment
		(start 85.4964 -46.618906)
		(end 85.552788 -46.675294)
		(width 0.254)
		(layer "F.Cu")
		(net "GND")
	)
	(segment
		(start 93.050868 -42.400474)
		(end 93.076014 -42.400474)
		(width 0.254)
		(layer "F.Cu")
		(net "GND")
	)
	(segment
		(start 79.248 -31.175706)
		(end 79.248 -31.1404)
		(width 0.254)
		(layer "F.Cu")
		(net "GND")
	)
	(segment
		(start 138.49858 -45.843444)
		(end 138.49858 -45.1612)
		(width 0.3048)
		(layer "F.Cu")
		(net "GND")
	)
	(segment
		(start 40.15867 -25.377394)
		(end 40.836596 -26.05532)
		(width 0.2794)
		(layer "F.Cu")
		(net "GND")
	)
	(segment
		(start 39.0398 -14.07541)
		(end 39.27221 -13.843)
		(width 0.508)
		(layer "F.Cu")
		(net "GND")
	)
	(segment
		(start 87.0585 -35.476942)
		(end 87.076788 -35.458654)
		(width 0.254)
		(layer "F.Cu")
		(net "GND")
	)
	(segment
		(start 91.433904 -48.012096)
		(end 91.7956 -47.6504)
		(width 0.254)
		(layer "F.Cu")
		(net "GND")
	)
	(segment
		(start 90.361008 -31.521654)
		(end 90.361008 -31.558484)
		(width 0.3048)
		(layer "F.Cu")
		(net "GND")
	)
	(segment
		(start 39.92245 -29.327348)
		(end 40.194738 -29.05506)
		(width 0.2794)
		(layer "F.Cu")
		(net "GND")
	)
	(segment
		(start 128.649984 -9.897364)
		(end 128.649984 -8.333994)
		(width 0.3048)
		(layer "F.Cu")
		(net "GND")
	)
	(segment
		(start 95.939102 -30.710378)
		(end 95.939102 -30.749494)
		(width 0.3048)
		(layer "F.Cu")
		(net "GND")
	)
	(segment
		(start 112.522 -70.6882)
		(end 111.9124 -70.6882)
		(width 0.3048)
		(layer "F.Cu")
		(net "GND")
	)
	(segment
		(start 142.494 -24.765)
		(end 142.49781 -24.765)
		(width 0.3048)
		(layer "F.Cu")
		(net "GND")
	)
	(segment
		(start 47.6504 -37.0586)
		(end 46.863 -37.0586)
		(width 0.508)
		(layer "F.Cu")
		(net "GND")
	)
	(segment
		(start 87.434928 -49.545494)
		(end 87.22233 -49.545494)
		(width 0.254)
		(layer "F.Cu")
		(net "GND")
	)
	(segment
		(start 90.940128 -28.135834)
		(end 90.868246 -28.135834)
		(width 0.3048)
		(layer "F.Cu")
		(net "GND")
	)
	(segment
		(start 98.062542 -48.402494)
		(end 97.709736 -48.7553)
		(width 0.254)
		(layer "F.Cu")
		(net "GND")
	)
	(segment
		(start 107.973114 -44.927774)
		(end 108.052108 -44.927774)
		(width 0.254)
		(layer "F.Cu")
		(net "GND")
	)
	(segment
		(start 97.127822 -47.117)
		(end 97.366328 -46.878494)
		(width 0.3048)
		(layer "F.Cu")
		(net "GND")
	)
	(segment
		(start 97.851468 -36.799774)
		(end 97.451418 -36.399724)
		(width 0.3048)
		(layer "F.Cu")
		(net "GND")
	)
	(segment
		(start 48.3616 -44.831)
		(end 48.3616 -44.958)
		(width 0.3048)
		(layer "F.Cu")
		(net "GND")
	)
	(segment
		(start 87.457788 -41.417494)
		(end 87.45728 -41.416986)
		(width 0.254)
		(layer "F.Cu")
		(net "GND")
	)
	(segment
		(start 90.122248 -45.227494)
		(end 90.122248 -45.354494)
		(width 0.254)
		(layer "F.Cu")
		(net "GND")
	)
	(segment
		(start 145.603468 -8.80491)
		(end 145.603468 -8.245348)
		(width 0.254)
		(layer "F.Cu")
		(net "GND")
	)
	(segment
		(start 143.34998 -70.806564)
		(end 143.34998 -69.933566)
		(width 0.254)
		(layer "F.Cu")
		(net "GND")
	)
	(segment
		(start 107.6706 -65.405)
		(end 107.6706 -65.544954)
		(width 0.3048)
		(layer "F.Cu")
		(net "GND")
	)
	(segment
		(start 105.4862 -51.965606)
		(end 105.4862 -52.373784)
		(width 0.254)
		(layer "F.Cu")
		(net "GND")
	)
	(segment
		(start 81.768188 -49.319434)
		(end 82.461608 -49.319434)
		(width 0.254)
		(layer "F.Cu")
		(net "GND")
	)
	(segment
		(start 95.618808 -30.390084)
		(end 95.939102 -30.710378)
		(width 0.3048)
		(layer "F.Cu")
		(net "GND")
	)
	(segment
		(start 89.1032 -35.1282)
		(end 89.0905 -35.1282)
		(width 0.254)
		(layer "F.Cu")
		(net "GND")
	)
	(segment
		(start 92.210128 -26.393394)
		(end 91.777566 -26.393394)
		(width 0.3048)
		(layer "F.Cu")
		(net "GND")
	)
	(segment
		(start 149.99843 -46.22673)
		(end 149.99843 -45.1612)
		(width 0.3048)
		(layer "F.Cu")
		(net "GND")
	)
	(segment
		(start 95.692468 -46.185074)
		(end 95.380048 -46.497494)
		(width 0.3048)
		(layer "F.Cu")
		(net "GND")
	)
	(segment
		(start 83.647788 -29.499814)
		(end 83.763866 -29.499814)
		(width 0.3048)
		(layer "F.Cu")
		(net "GND")
	)
	(segment
		(start 92.664788 -28.186634)
		(end 92.753434 -28.186634)
		(width 0.3048)
		(layer "F.Cu")
		(net "GND")
	)
	(segment
		(start 171.250102 -63.446914)
		(end 171.357544 -63.554356)
		(width 0.254)
		(layer "F.Cu")
		(net "GND")
	)
	(segment
		(start 108.433108 -35.697414)
		(end 108.741718 -36.006024)
		(width 0.254)
		(layer "F.Cu")
		(net "GND")
	)
	(segment
		(start 66.34988 -6.195568)
		(end 66.367914 -6.213602)
		(width 0.7112)
		(layer "F.Cu")
		(net "GND")
	)
	(segment
		(start 4.2672 -50.8762)
		(end 3.683 -50.292)
		(width 0.3048)
		(layer "F.Cu")
		(net "GND")
	)
	(segment
		(start 135.255 -2.910078)
		(end 135.255 -3.405378)
		(width 0.254)
		(layer "F.Cu")
		(net "GND")
	)
	(segment
		(start 101.051868 -41.601136)
		(end 101.421692 -41.97096)
		(width 0.254)
		(layer "F.Cu")
		(net "GND")
	)
	(segment
		(start 87.45728 -36.76396)
		(end 87.09152 -37.12972)
		(width 0.254)
		(layer "F.Cu")
		(net "GND")
	)
	(segment
		(start 101.4222 -42.770806)
		(end 101.051868 -42.400474)
		(width 0.3048)
		(layer "F.Cu")
		(net "GND")
	)
	(segment
		(start 92.248228 -39.200074)
		(end 92.6338 -38.814502)
		(width 0.3048)
		(layer "F.Cu")
		(net "GND")
	)
	(segment
		(start 98.649028 -38.399974)
		(end 98.649028 -39.200074)
		(width 0.3048)
		(layer "F.Cu")
		(net "GND")
	)
	(segment
		(start 95.692468 -46.047914)
		(end 95.380048 -45.735494)
		(width 0.3048)
		(layer "F.Cu")
		(net "GND")
	)
	(segment
		(start 89.835228 -40.015414)
		(end 89.850468 -40.000174)
		(width 0.254)
		(layer "F.Cu")
		(net "GND")
	)
	(segment
		(start 111.961168 -29.339794)
		(end 113.083594 -29.339794)
		(width 0.3048)
		(layer "F.Cu")
		(net "GND")
	)
	(segment
		(start 86.286594 -29.1338)
		(end 85.789262 -29.1338)
		(width 0.3048)
		(layer "F.Cu")
		(net "GND")
	)
	(segment
		(start 69.542914 -49.08804)
		(end 69.30644 -49.08804)
		(width 0.3048)
		(layer "F.Cu")
		(net "GND")
	)
	(segment
		(start 63.369444 -42.7863)
		(end 62.333886 -42.7863)
		(width 0.3048)
		(layer "F.Cu")
		(net "GND")
	)
	(segment
		(start 174.55007 -70.806564)
		(end 174.55007 -69.434964)
		(width 0.254)
		(layer "F.Cu")
		(net "GND")
	)
	(segment
		(start 79.643986 -42.168064)
		(end 79.925418 -42.168064)
		(width 0.254)
		(layer "F.Cu")
		(net "GND")
	)
	(segment
		(start 85.171788 -44.689014)
		(end 85.171788 -44.688506)
		(width 0.3048)
		(layer "F.Cu")
		(net "GND")
	)
	(segment
		(start 94.651068 -42.400474)
		(end 95.448628 -42.400474)
		(width 0.254)
		(layer "F.Cu")
		(net "GND")
	)
	(segment
		(start 81.836768 -33.380934)
		(end 81.836768 -33.380426)
		(width 0.254)
		(layer "F.Cu")
		(net "GND")
	)
	(segment
		(start 42.367962 -8.97001)
		(end 42.872914 -9.474962)
		(width 0.7112)
		(layer "F.Cu")
		(net "GND")
	)
	(segment
		(start 133.7818 -8.665718)
		(end 133.7818 -8.434578)
		(width 0.3048)
		(layer "F.Cu")
		(net "GND")
	)
	(segment
		(start 79.738728 -27.714194)
		(end 79.738728 -27.770328)
		(width 0.3048)
		(layer "F.Cu")
		(net "GND")
	)
	(segment
		(start 90.241628 -26.956766)
		(end 90.018108 -26.733246)
		(width 0.2032)
		(layer "F.Cu")
		(net "GND")
	)
	(segment
		(start 179.050188 -63.429896)
		(end 179.70246 -64.082168)
		(width 0.254)
		(layer "F.Cu")
		(net "GND")
	)
	(segment
		(start 109.779816 -41.854374)
		(end 110.012988 -41.854374)
		(width 0.254)
		(layer "F.Cu")
		(net "GND")
	)
	(segment
		(start 182.5498 -32.1564)
		(end 182.3212 -32.1564)
		(width 0.508)
		(layer "F.Cu")
		(net "GND")
	)
	(segment
		(start 127.8128 -39.37)
		(end 127.762 -39.37)
		(width 0.3048)
		(layer "F.Cu")
		(net "GND")
	)
	(segment
		(start 106.528108 -33.009586)
		(end 106.181906 -33.355788)
		(width 0.254)
		(layer "F.Cu")
		(net "GND")
	)
	(segment
		(start 69.596 -57.15)
		(end 69.596 -56.5912)
		(width 0.3048)
		(layer "F.Cu")
		(net "GND")
	)
	(segment
		(start 138.15314 -25.36444)
		(end 138.49858 -25.019)
		(width 0.3048)
		(layer "F.Cu")
		(net "GND")
	)
	(segment
		(start 34.684462 -25.786842)
		(end 34.671 -25.786842)
		(width 0.2794)
		(layer "F.Cu")
		(net "GND")
	)
	(segment
		(start 68.8848 -9.6012)
		(end 68.834 -9.6012)
		(width 0.7112)
		(layer "F.Cu")
		(net "GND")
	)
	(segment
		(start 82.59064 -49.448466)
		(end 82.504788 -49.362614)
		(width 0.254)
		(layer "F.Cu")
		(net "GND")
	)
	(segment
		(start 21.368004 -9.101328)
		(end 21.368004 -6.213602)
		(width 0.7112)
		(layer "F.Cu")
		(net "GND")
	)
	(segment
		(start 91.450668 -27.658314)
		(end 91.450668 -28.149296)
		(width 0.3048)
		(layer "F.Cu")
		(net "GND")
	)
	(segment
		(start 86.593934 -32.771334)
		(end 86.17712 -32.35452)
		(width 0.3048)
		(layer "F.Cu")
		(net "GND")
	)
	(segment
		(start 96.6216 -34.029142)
		(end 96.251268 -34.399474)
		(width 0.3048)
		(layer "F.Cu")
		(net "GND")
	)
	(segment
		(start 39.0398 -15.367)
		(end 39.0398 -14.07541)
		(width 0.508)
		(layer "F.Cu")
		(net "GND")
	)
	(segment
		(start 143.949928 -2.95275)
		(end 143.77416 -3.128518)
		(width 0.3048)
		(layer "F.Cu")
		(net "GND")
	)
	(segment
		(start 108.0643 -40.955214)
		(end 108.052108 -40.955214)
		(width 0.254)
		(layer "F.Cu")
		(net "GND")
	)
	(segment
		(start 176.04994 -9.897364)
		(end 176.04994 -8.559038)
		(width 0.254)
		(layer "F.Cu")
		(net "GND")
	)
	(segment
		(start 87.122 -31.496)
		(end 87.477346 -31.140654)
		(width 0.3048)
		(layer "F.Cu")
		(net "GND")
	)
	(segment
		(start 94.651068 -36.792408)
		(end 95.0468 -36.396676)
		(width 0.3048)
		(layer "F.Cu")
		(net "GND")
	)
	(segment
		(start 138.549888 -2.509266)
		(end 139.065 -3.024378)
		(width 0.254)
		(layer "F.Cu")
		(net "GND")
	)
	(segment
		(start 109.913928 -44.318174)
		(end 109.913928 -44.317666)
		(width 0.254)
		(layer "F.Cu")
		(net "GND")
	)
	(segment
		(start 53.349906 -8.941562)
		(end 52.7304 -9.561068)
		(width 0.7112)
		(layer "F.Cu")
		(net "GND")
	)
	(segment
		(start 79.861156 -46.662086)
		(end 79.601568 -46.662086)
		(width 0.254)
		(layer "F.Cu")
		(net "GND")
	)
	(segment
		(start 96.6216 -34.017712)
		(end 96.6216 -34.029142)
		(width 0.3048)
		(layer "F.Cu")
		(net "GND")
	)
	(segment
		(start 42.10177 -24.55545)
		(end 40.18407 -24.55545)
		(width 0.2794)
		(layer "F.Cu")
		(net "GND")
	)
	(segment
		(start 99.451668 -35.998404)
		(end 99.822 -35.628072)
		(width 0.3048)
		(layer "F.Cu")
		(net "GND")
	)
	(segment
		(start 110.4138 -47.091346)
		(end 110.414308 -47.090838)
		(width 0.254)
		(layer "F.Cu")
		(net "GND")
	)
	(segment
		(start 51.054 -17.7546)
		(end 50.7492 -17.4498)
		(width 0.508)
		(layer "F.Cu")
		(net "GND")
	)
	(segment
		(start 88.735154 -37.8714)
		(end 88.580722 -37.8714)
		(width 0.254)
		(layer "F.Cu")
		(net "GND")
	)
	(segment
		(start 85.864192 -49.618392)
		(end 85.864192 -49.8475)
		(width 0.254)
		(layer "F.Cu")
		(net "GND")
	)
	(segment
		(start 187.149994 -69.979794)
		(end 186.56554 -69.39534)
		(width 0.254)
		(layer "F.Cu")
		(net "GND")
	)
	(segment
		(start 174.850044 -62.59322)
		(end 174.850044 -63.935864)
		(width 0.254)
		(layer "F.Cu")
		(net "GND")
	)
	(segment
		(start 186.56554 -69.39534)
		(end 186.56554 -69.36994)
		(width 0.254)
		(layer "F.Cu")
		(net "GND")
	)
	(segment
		(start 144.99844 -22.71141)
		(end 144.96161 -22.67458)
		(width 0.3048)
		(layer "F.Cu")
		(net "GND")
	)
	(segment
		(start 110.4138 -33.4772)
		(end 110.749588 -33.141412)
		(width 0.254)
		(layer "F.Cu")
		(net "GND")
	)
	(segment
		(start 82.461608 -49.319434)
		(end 82.504788 -49.362614)
		(width 0.254)
		(layer "F.Cu")
		(net "GND")
	)
	(segment
		(start 140.1064 -53.2638)
		(end 140.1064 -52.1716)
		(width 0.3048)
		(layer "F.Cu")
		(net "GND")
	)
	(segment
		(start 176.5046 -46.0756)
		(end 177.2666 -46.0756)
		(width 0.3048)
		(layer "F.Cu")
		(net "GND")
	)
	(segment
		(start 112.392968 -31.442914)
		(end 112.098328 -31.737554)
		(width 0.254)
		(layer "F.Cu")
		(net "GND")
	)
	(segment
		(start 86.741508 -52.46624)
		(end 86.528148 -52.6796)
		(width 0.254)
		(layer "F.Cu")
		(net "GND")
	)
	(segment
		(start 65.367916 -8.963152)
		(end 64.77 -9.561068)
		(width 0.7112)
		(layer "F.Cu")
		(net "GND")
	)
	(segment
		(start 88.135968 -44.973494)
		(end 88.135968 -45.02658)
		(width 0.254)
		(layer "F.Cu")
		(net "GND")
	)
	(segment
		(start 87.457788 -36.743894)
		(end 87.0585 -36.344606)
		(width 0.254)
		(layer "F.Cu")
		(net "GND")
	)
	(segment
		(start 35.845496 -24.55545)
		(end 35.844226 -24.55672)
		(width 0.2794)
		(layer "F.Cu")
		(net "GND")
	)
	(segment
		(start 165.90264 -64.04102)
		(end 166.0144 -64.04102)
		(width 0.3048)
		(layer "F.Cu")
		(net "GND")
	)
	(segment
		(start 110.053628 -37.391594)
		(end 110.749588 -37.483034)
		(width 0.254)
		(layer "F.Cu")
		(net "GND")
	)
	(segment
		(start 79.601568 -46.662594)
		(end 79.601568 -46.662086)
		(width 0.254)
		(layer "F.Cu")
		(net "GND")
	)
	(segment
		(start 86.269576 -38.729666)
		(end 85.958934 -39.040308)
		(width 0.254)
		(layer "F.Cu")
		(net "GND")
	)
	(segment
		(start 87.99322 -45.610272)
		(end 87.772748 -45.3898)
		(width 0.254)
		(layer "F.Cu")
		(net "GND")
	)
	(segment
		(start 91.088718 -41.992296)
		(end 91.450668 -42.354246)
		(width 0.254)
		(layer "F.Cu")
		(net "GND")
	)
	(segment
		(start 79.189834 -30.091634)
		(end 79.601568 -30.091634)
		(width 0.3048)
		(layer "F.Cu")
		(net "GND")
	)
	(segment
		(start 95.3516 -9.24687)
		(end 95.3516 -9.5758)
		(width 0.7112)
		(layer "F.Cu")
		(net "GND")
	)
	(segment
		(start 85.301328 -52.448714)
		(end 85.0392 -52.710842)
		(width 0.254)
		(layer "F.Cu")
		(net "GND")
	)
	(segment
		(start 92.620592 -29.616654)
		(end 92.893134 -29.344112)
		(width 0.3048)
		(layer "F.Cu")
		(net "GND")
	)
	(segment
		(start 24.335994 -59.419998)
		(end 24.86533 -59.419998)
		(width 0.2032)
		(layer "F.Cu")
		(net "GND")
	)
	(segment
		(start 38.813994 -22.146006)
		(end 38.813994 -21.4122)
		(width 0.2794)
		(layer "F.Cu")
		(net "GND")
	)
	(segment
		(start 177.850038 -8.657082)
		(end 178.03876 -8.46836)
		(width 0.254)
		(layer "F.Cu")
		(net "GND")
	)
	(segment
		(start 89.007188 -38.143434)
		(end 88.735154 -37.8714)
		(width 0.254)
		(layer "F.Cu")
		(net "GND")
	)
	(segment
		(start 142.49781 -24.765)
		(end 142.49781 -23.9268)
		(width 0.3048)
		(layer "F.Cu")
		(net "GND")
	)
	(segment
		(start 41.656 -52.07)
		(end 38.6588 -52.07)
		(width 0.3048)
		(layer "F.Cu")
		(net "GND")
	)
	(segment
		(start 88.760046 -35.458654)
		(end 88.600788 -35.458654)
		(width 0.254)
		(layer "F.Cu")
		(net "GND")
	)
	(segment
		(start 46.355 -21.8948)
		(end 45.9994 -21.5392)
		(width 0.3048)
		(layer "F.Cu")
		(net "GND")
	)
	(segment
		(start 70.349872 -6.195568)
		(end 70.367906 -6.213602)
		(width 0.7112)
		(layer "F.Cu")
		(net "GND")
	)
	(segment
		(start 95.885 -39.631112)
		(end 95.885 -39.624)
		(width 0.3048)
		(layer "F.Cu")
		(net "GND")
	)
	(segment
		(start 54.88559 -9.487662)
		(end 54.88559 -9.562846)
		(width 0.7112)
		(layer "F.Cu")
		(net "GND")
	)
	(segment
		(start 183.850026 -9.115552)
		(end 184.315862 -8.649716)
		(width 0.254)
		(layer "F.Cu")
		(net "GND")
	)
	(segment
		(start 52.8066 -53.90642)
		(end 52.30368 -54.40934)
		(width 0.3048)
		(layer "F.Cu")
		(net "GND")
	)
	(segment
		(start 172.449998 -9.063482)
		(end 173.04512 -8.46836)
		(width 0.254)
		(layer "F.Cu")
		(net "GND")
	)
	(segment
		(start 106.467148 -41.655746)
		(end 106.11739 -41.305988)
		(width 0.254)
		(layer "F.Cu")
		(net "GND")
	)
	(segment
		(start 141.397736 -25.146)
		(end 142.113 -25.146)
		(width 0.3048)
		(layer "F.Cu")
		(net "GND")
	)
	(segment
		(start 90.122248 -45.354494)
		(end 90.122248 -45.373798)
		(width 0.254)
		(layer "F.Cu")
		(net "GND")
	)
	(segment
		(start 82.1817 -36.094416)
		(end 82.1817 -36.070032)
		(width 0.254)
		(layer "F.Cu")
		(net "GND")
	)
	(segment
		(start 81.343754 -37.508688)
		(end 81.343754 -37.720016)
		(width 0.254)
		(layer "F.Cu")
		(net "GND")
	)
	(segment
		(start 176.650396 -63.651384)
		(end 176.24044 -64.06134)
		(width 0.254)
		(layer "F.Cu")
		(net "GND")
	)
	(segment
		(start 38.813994 -21.4122)
		(end 38.813994 -20.830794)
		(width 0.2794)
		(layer "F.Cu")
		(net "GND")
	)
	(segment
		(start 111.148368 -27.714194)
		(end 111.961168 -27.714194)
		(width 0.254)
		(layer "F.Cu")
		(net "GND")
	)
	(segment
		(start 24.335994 -57.420002)
		(end 25.206198 -57.420002)
		(width 0.2032)
		(layer "F.Cu")
		(net "GND")
	)
	(segment
		(start 110.012988 -41.854374)
		(end 110.053628 -41.895014)
		(width 0.254)
		(layer "F.Cu")
		(net "GND")
	)
	(segment
		(start 94.041468 -27.996134)
		(end 94.041468 -27.952446)
		(width 0.3048)
		(layer "F.Cu")
		(net "GND")
	)
	(segment
		(start 91.450668 -34.399474)
		(end 91.245944 -34.604198)
		(width 0.254)
		(layer "F.Cu")
		(net "GND")
	)
	(segment
		(start 135.550148 -70.806564)
		(end 135.550148 -69.975222)
		(width 0.254)
		(layer "F.Cu")
		(net "GND")
	)
	(segment
		(start 98.90252 -33.0454)
		(end 98.90252 -33.444434)
		(width 0.254)
		(layer "F.Cu")
		(net "GND")
	)
	(segment
		(start 55.86476 -41.73728)
		(end 55.86476 -41.2115)
		(width 0.3048)
		(layer "F.Cu")
		(net "GND")
	)
	(segment
		(start 97.391728 -25.951434)
		(end 97.08134 -25.6413)
		(width 0.254)
		(layer "F.Cu")
		(net "GND")
	)
	(segment
		(start 65.349882 -6.195568)
		(end 65.367916 -6.213602)
		(width 0.7112)
		(layer "F.Cu")
		(net "GND")
	)
	(segment
		(start 6.35 -51.0032)
		(end 6.3246 -50.9778)
		(width 0.254)
		(layer "F.Cu")
		(net "GND")
	)
	(segment
		(start 79.738728 -29.339794)
		(end 79.225394 -29.339794)
		(width 0.3048)
		(layer "F.Cu")
		(net "GND")
	)
	(segment
		(start 17.35201 -9.100058)
		(end 16.891 -9.561068)
		(width 0.7112)
		(layer "F.Cu")
		(net "GND")
	)
	(segment
		(start 82.3468 -40.0812)
		(end 82.3214 -40.0812)
		(width 0.254)
		(layer "F.Cu")
		(net "GND")
	)
	(segment
		(start 99.452938 -39.199566)
		(end 99.824032 -39.57066)
		(width 0.3048)
		(layer "F.Cu")
		(net "GND")
	)
	(segment
		(start 94.171008 -28.125674)
		(end 94.041468 -27.996134)
		(width 0.3048)
		(layer "F.Cu")
		(net "GND")
	)
	(segment
		(start 152.59812 -8.454898)
		(end 152.49144 -8.454898)
		(width 0.3048)
		(layer "F.Cu")
		(net "GND")
	)
	(segment
		(start 151.4983 -23.0251)
		(end 151.59863 -22.92477)
		(width 0.3048)
		(layer "F.Cu")
		(net "GND")
	)
	(segment
		(start 80.381094 -67.7418)
		(end 79.273146 -66.633852)
		(width 0.3048)
		(layer "F.Cu")
		(net "GND")
	)
	(segment
		(start 42.872914 -9.474962)
		(end 42.872914 -9.573006)
		(width 0.7112)
		(layer "F.Cu")
		(net "GND")
	)
	(segment
		(start 136.99744 -23.9268)
		(end 136.99744 -24.94788)
		(width 0.3048)
		(layer "F.Cu")
		(net "GND")
	)
	(segment
		(start 41.402 -34.5567)
		(end 42.1005 -34.5567)
		(width 0.2794)
		(layer "F.Cu")
		(net "GND")
	)
	(segment
		(start 82.885788 -40.716454)
		(end 82.885788 -40.715946)
		(width 0.254)
		(layer "F.Cu")
		(net "GND")
	)
	(segment
		(start 26.367994 -6.213602)
		(end 26.34996 -6.195568)
		(width 0.7112)
		(layer "F.Cu")
		(net "GND")
	)
	(segment
		(start 177.850038 -9.897364)
		(end 177.850038 -8.657082)
		(width 0.254)
		(layer "F.Cu")
		(net "GND")
	)
	(segment
		(start 89.871296 -37.599874)
		(end 90.246962 -37.97554)
		(width 0.254)
		(layer "F.Cu")
		(net "GND")
	)
	(segment
		(start 85.171788 -45.390054)
		(end 85.171788 -45.371258)
		(width 0.3048)
		(layer "F.Cu")
		(net "GND")
	)
	(segment
		(start 90.648028 -44.701714)
		(end 90.122248 -45.227494)
		(width 0.254)
		(layer "F.Cu")
		(net "GND")
	)
	(segment
		(start 87.477346 -31.140654)
		(end 87.673688 -31.140654)
		(width 0.3048)
		(layer "F.Cu")
		(net "GND")
	)
	(segment
		(start 51.0286 -44.958)
		(end 51.3461 -44.6405)
		(width 0.3556)
		(layer "F.Cu")
		(net "GND")
	)
	(segment
		(start 102.779068 -37.683186)
		(end 102.795832 -37.683186)
		(width 0.3048)
		(layer "F.Cu")
		(net "GND")
	)
	(segment
		(start 95.618808 -33.426654)
		(end 94.922848 -33.426654)
		(width 0.3048)
		(layer "F.Cu")
		(net "GND")
	)
	(segment
		(start 82.641694 -36.743894)
		(end 82.1817 -36.2839)
		(width 0.254)
		(layer "F.Cu")
		(net "GND")
	)
	(segment
		(start 92.631768 -46.116494)
		(end 93.393768 -45.354494)
		(width 0.254)
		(layer "F.Cu")
		(net "GND")
	)
	(segment
		(start 138.850116 -63.867284)
		(end 138.557 -64.1604)
		(width 0.254)
		(layer "F.Cu")
		(net "GND")
	)
	(segment
		(start 83.884008 -25.951434)
		(end 84.284566 -25.951434)
		(width 0.254)
		(layer "F.Cu")
		(net "GND")
	)
	(segment
		(start 95.9612 -31.537402)
		(end 95.9612 -31.483046)
		(width 0.3048)
		(layer "F.Cu")
		(net "GND")
	)
	(segment
		(start 172.749972 -70.806564)
		(end 172.749972 -69.464428)
		(width 0.254)
		(layer "F.Cu")
		(net "GND")
	)
	(segment
		(start 91.407488 -45.766482)
		(end 91.716606 -46.0756)
		(width 0.254)
		(layer "F.Cu")
		(net "GND")
	)
	(segment
		(start 26.367994 -9.070086)
		(end 26.367994 -6.213602)
		(width 0.7112)
		(layer "F.Cu")
		(net "GND")
	)
	(segment
		(start 6.35 -51.7652)
		(end 6.35 -51.0032)
		(width 0.254)
		(layer "F.Cu")
		(net "GND")
	)
	(segment
		(start 109.863128 -31.511494)
		(end 109.857286 -31.511494)
		(width 0.254)
		(layer "F.Cu")
		(net "GND")
	)
	(segment
		(start 84.074 -31.531306)
		(end 84.074 -31.88208)
		(width 0.3048)
		(layer "F.Cu")
		(net "GND")
	)
	(segment
		(start 100.457508 -25.951434)
		(end 100.439474 -25.9334)
		(width 0.254)
		(layer "F.Cu")
		(net "GND")
	)
	(segment
		(start 110.749588 -37.483034)
		(end 110.749588 -37.482526)
		(width 0.254)
		(layer "F.Cu")
		(net "GND")
	)
	(segment
		(start 131.350004 -70.806564)
		(end 131.350004 -69.474334)
		(width 0.254)
		(layer "F.Cu")
		(net "GND")
	)
	(segment
		(start 166.150036 -69.616828)
		(end 165.872414 -69.339206)
		(width 0.3048)
		(layer "F.Cu")
		(net "GND")
	)
	(segment
		(start 80.043528 -47.343314)
		(end 80.122268 -47.422054)
		(width 0.254)
		(layer "F.Cu")
		(net "GND")
	)
	(segment
		(start 25.019 -49.7332)
		(end 24.7142 -49.7332)
		(width 0.3048)
		(layer "F.Cu")
		(net "GND")
	)
	(segment
		(start 98.649028 -42.400474)
		(end 98.555302 -42.4942)
		(width 0.254)
		(layer "F.Cu")
		(net "GND")
	)
	(segment
		(start 134.62 -14.859)
		(end 134.62 -15.748)
		(width 0.3048)
		(layer "F.Cu")
		(net "GND")
	)
	(segment
		(start 181.44998 -9.897364)
		(end 181.44998 -8.95604)
		(width 0.254)
		(layer "F.Cu")
		(net "GND")
	)
	(segment
		(start 71.6788 -54.419246)
		(end 71.6788 -55.626)
		(width 0.3048)
		(layer "F.Cu")
		(net "GND")
	)
	(segment
		(start 79.601568 -31.529274)
		(end 79.95158 -31.879286)
		(width 0.254)
		(layer "F.Cu")
		(net "GND")
	)
	(segment
		(start 141.849602 -9.89711)
		(end 141.849602 -9.000744)
		(width 0.254)
		(layer "F.Cu")
		(net "GND")
	)
	(segment
		(start 98.298 -28.243022)
		(end 98.298 -28.5242)
		(width 0.254)
		(layer "F.Cu")
		(net "GND")
	)
	(segment
		(start 103.520748 -25.618948)
		(end 103.5177 -25.6159)
		(width 0.254)
		(layer "F.Cu")
		(net "GND")
	)
	(segment
		(start 78.867 -60.4012)
		(end 79.629 -60.4012)
		(width 0.3048)
		(layer "F.Cu")
		(net "GND")
	)
	(segment
		(start 80.17256 -42.415206)
		(end 80.107536 -42.350182)
		(width 0.254)
		(layer "F.Cu")
		(net "GND")
	)
	(segment
		(start 56.863234 -30.701234)
		(end 56.209946 -30.701234)
		(width 0.3048)
		(layer "F.Cu")
		(net "GND")
	)
	(segment
		(start 69.367908 -6.213602)
		(end 69.367908 -9.118092)
		(width 0.7112)
		(layer "F.Cu")
		(net "GND")
	)
	(segment
		(start 108.741718 -36.006024)
		(end 108.804202 -36.006024)
		(width 0.254)
		(layer "F.Cu")
		(net "GND")
	)
	(segment
		(start 154.15006 -1.68402)
		(end 154.15006 -2.867152)
		(width 0.3048)
		(layer "F.Cu")
		(net "GND")
	)
	(segment
		(start 86.558882 -34.32175)
		(end 86.692486 -34.455354)
		(width 0.254)
		(layer "F.Cu")
		(net "GND")
	)
	(segment
		(start 30.349952 -6.195568)
		(end 30.349952 -9.05002)
		(width 0.7112)
		(layer "F.Cu")
		(net "GND")
	)
	(segment
		(start 80.551528 -26.088594)
		(end 80.551528 -26.001726)
		(width 0.3048)
		(layer "F.Cu")
		(net "GND")
	)
	(segment
		(start 183.20004 -48.26)
		(end 182.1688 -48.26)
		(width 0.3048)
		(layer "F.Cu")
		(net "GND")
	)
	(segment
		(start 182.3212 -32.1564)
		(end 181.7878 -31.623)
		(width 0.508)
		(layer "F.Cu")
		(net "GND")
	)
	(segment
		(start 131.350004 -69.474334)
		(end 131.248658 -69.372988)
		(width 0.254)
		(layer "F.Cu")
		(net "GND")
	)
	(segment
		(start 78.5368 -58.6486)
		(end 78.01737 -59.16803)
		(width 0.3048)
		(layer "F.Cu")
		(net "GND")
	)
	(segment
		(start 95.618808 -29.616146)
		(end 95.965772 -29.269182)
		(width 0.3048)
		(layer "F.Cu")
		(net "GND")
	)
	(segment
		(start 79.701136 -43.698414)
		(end 79.601568 -43.598846)
		(width 0.254)
		(layer "F.Cu")
		(net "GND")
	)
	(segment
		(start 96.319848 -30.378654)
		(end 96.319848 -30.392624)
		(width 0.3048)
		(layer "F.Cu")
		(net "GND")
	)
	(segment
		(start 87.457788 -28.135834)
		(end 87.450168 -28.128214)
		(width 0.3048)
		(layer "F.Cu")
		(net "GND")
	)
	(segment
		(start 79.427578 -40.535606)
		(end 79.2099 -40.317928)
		(width 0.254)
		(layer "F.Cu")
		(net "GND")
	)
	(segment
		(start 131.05003 -62.59322)
		(end 131.05003 -63.89243)
		(width 0.254)
		(layer "F.Cu")
		(net "GND")
	)
	(segment
		(start 186.817 -48.26)
		(end 187.198 -47.879)
		(width 0.3048)
		(layer "F.Cu")
		(net "GND")
	)
	(segment
		(start 90.241628 -26.957274)
		(end 90.241628 -27.45867)
		(width 0.3048)
		(layer "F.Cu")
		(net "GND")
	)
	(segment
		(start 147.249896 -9.897364)
		(end 147.249896 -8.593074)
		(width 0.254)
		(layer "F.Cu")
		(net "GND")
	)
	(segment
		(start 95.954088 -25.951434)
		(end 95.903288 -26.002234)
		(width 0.254)
		(layer "F.Cu")
		(net "GND")
	)
	(segment
		(start 93.0656 -28.4988)
		(end 92.709746 -28.854654)
		(width 0.3048)
		(layer "F.Cu")
		(net "GND")
	)
	(segment
		(start 82.584036 -30.785054)
		(end 82.883502 -31.08452)
		(width 0.254)
		(layer "F.Cu")
		(net "GND")
	)
	(segment
		(start 110.335568 -52.311554)
		(end 110.335568 -52.654708)
		(width 0.254)
		(layer "F.Cu")
		(net "GND")
	)
	(segment
		(start 135.849868 -9.897364)
		(end 135.849868 -9.03351)
		(width 0.3048)
		(layer "F.Cu")
		(net "GND")
	)
	(segment
		(start 34.367978 -9.054846)
		(end 34.8742 -9.561068)
		(width 0.7112)
		(layer "F.Cu")
		(net "GND")
	)
	(segment
		(start 53.10124 -45.93336)
		(end 53.3527 -45.6819)
		(width 0.3048)
		(layer "F.Cu")
		(net "GND")
	)
	(segment
		(start 110.605062 -47.097188)
		(end 110.605062 -47.090838)
		(width 0.254)
		(layer "F.Cu")
		(net "GND")
	)
	(segment
		(start 171.6024 -69.3674)
		(end 171.5516 -69.3674)
		(width 0.254)
		(layer "F.Cu")
		(net "GND")
	)
	(segment
		(start 88.9 -45.1358)
		(end 88.9 -44.951142)
		(width 0.254)
		(layer "F.Cu")
		(net "GND")
	)
	(segment
		(start 129.4892 -44.0182)
		(end 129.921 -44.0182)
		(width 0.3048)
		(layer "F.Cu")
		(net "GND")
	)
	(segment
		(start 5.969 -51.7652)
		(end 6.35 -51.7652)
		(width 0.254)
		(layer "F.Cu")
		(net "GND")
	)
	(segment
		(start 95.618808 -28.865068)
		(end 95.965772 -29.212032)
		(width 0.3048)
		(layer "F.Cu")
		(net "GND")
	)
	(segment
		(start 70.013576 -12.827)
		(end 69.596 -13.244576)
		(width 0.3048)
		(layer "F.Cu")
		(net "GND")
	)
	(segment
		(start 80.122268 -47.422054)
		(end 81.097628 -47.422054)
		(width 0.254)
		(layer "F.Cu")
		(net "GND")
	)
	(segment
		(start 81.646268 -32.869378)
		(end 81.361534 -33.154112)
		(width 0.254)
		(layer "F.Cu")
		(net "GND")
	)
	(segment
		(start 90.27795 -36.429696)
		(end 90.256868 -36.429696)
		(width 0.254)
		(layer "F.Cu")
		(net "GND")
	)
	(segment
		(start 104.623108 -43.642534)
		(end 104.623108 -43.62577)
		(width 0.254)
		(layer "F.Cu")
		(net "GND")
	)
	(segment
		(start 32.4612 -39.1668)
		(end 33.5534 -40.259)
		(width 0.508)
		(layer "F.Cu")
		(net "GND")
	)
	(segment
		(start 135.938768 -64.1604)
		(end 135.914892 -64.1604)
		(width 0.254)
		(layer "F.Cu")
		(net "GND")
	)
	(segment
		(start 57.349898 -9.084818)
		(end 56.862472 -9.572244)
		(width 0.7112)
		(layer "F.Cu")
		(net "GND")
	)
	(segment
		(start 27.7368 -58.8264)
		(end 27.686 -58.7756)
		(width 0.508)
		(layer "F.Cu")
		(net "GND")
	)
	(segment
		(start 89.09939 -28.854654)
		(end 89.240868 -28.996132)
		(width 0.3048)
		(layer "F.Cu")
		(net "GND")
	)
	(segment
		(start 89.71788 -42.532554)
		(end 89.370154 -42.532554)
		(width 0.3048)
		(layer "F.Cu")
		(net "GND")
	)
	(segment
		(start 89.3064 -42.415206)
		(end 89.007188 -42.115994)
		(width 0.3048)
		(layer "F.Cu")
		(net "GND")
	)
	(segment
		(start 89.850468 -40.000174)
		(end 89.887806 -40.000174)
		(width 0.254)
		(layer "F.Cu")
		(net "GND")
	)
	(segment
		(start 101.669088 -28.186634)
		(end 101.669088 -27.743912)
		(width 0.254)
		(layer "F.Cu")
		(net "GND")
	)
	(segment
		(start 140.99794 -45.1612)
		(end 140.99794 -44.323)
		(width 0.3048)
		(layer "F.Cu")
		(net "GND")
	)
	(segment
		(start 107.2134 -39.365682)
		(end 107.2134 -39.360602)
		(width 0.3048)
		(layer "F.Cu")
		(net "GND")
	)
	(segment
		(start 175.150018 -2.64668)
		(end 174.816008 -2.98069)
		(width 0.254)
		(layer "F.Cu")
		(net "GND")
	)
	(segment
		(start 89.48039 -29.235654)
		(end 89.240868 -28.996132)
		(width 0.3048)
		(layer "F.Cu")
		(net "GND")
	)
	(segment
		(start 86.314788 -46.705012)
		(end 85.852 -47.1678)
		(width 0.3048)
		(layer "F.Cu")
		(net "GND")
	)
	(segment
		(start 179.5526 -69.504814)
		(end 179.5526 -69.342)
		(width 0.254)
		(layer "F.Cu")
		(net "GND")
	)
	(segment
		(start 128.949958 -3.05562)
		(end 128.7272 -3.278378)
		(width 0.3048)
		(layer "F.Cu")
		(net "GND")
	)
	(segment
		(start 25.367996 -9.212072)
		(end 25.367996 -6.213602)
		(width 0.7112)
		(layer "F.Cu")
		(net "GND")
	)
	(segment
		(start 96.72955 -34.017712)
		(end 97.048828 -33.698434)
		(width 0.3048)
		(layer "F.Cu")
		(net "GND")
	)
	(segment
		(start 86.695788 -33.472374)
		(end 86.558882 -33.60928)
		(width 0.254)
		(layer "F.Cu")
		(net "GND")
	)
	(segment
		(start 50.349912 -9.03478)
		(end 50.8762 -9.561068)
		(width 0.7112)
		(layer "F.Cu")
		(net "GND")
	)
	(segment
		(start 44.1198 -61.214)
		(end 44.7548 -61.214)
		(width 0.508)
		(layer "F.Cu")
		(net "GND")
	)
	(segment
		(start 46.8122 -19.939)
		(end 46.5836 -20.1676)
		(width 0.3048)
		(layer "F.Cu")
		(net "GND")
	)
	(segment
		(start 113.370614 -30.4292)
		(end 112.666018 -31.133796)
		(width 0.254)
		(layer "F.Cu")
		(net "GND")
	)
	(segment
		(start 107.671108 -37.302694)
		(end 108.052108 -37.683694)
		(width 0.2032)
		(layer "F.Cu")
		(net "GND")
	)
	(segment
		(start 55.86857 -47.23003)
		(end 55.2958 -47.8028)
		(width 0.3048)
		(layer "F.Cu")
		(net "GND")
	)
	(segment
		(start 107.605068 -38.968934)
		(end 107.671108 -38.968934)
		(width 0.3048)
		(layer "F.Cu")
		(net "GND")
	)
	(segment
		(start 61.0108 -33.4772)
		(end 60.198 -32.6644)
		(width 0.3048)
		(layer "F.Cu")
		(net "GND")
	)
	(segment
		(start 110.053628 -46.398434)
		(end 110.053628 -46.397926)
		(width 0.254)
		(layer "F.Cu")
		(net "GND")
	)
	(segment
		(start 199.136 -7.874)
		(end 198.5518 -7.2898)
		(width 0.3048)
		(layer "F.Cu")
		(net "GND")
	)
	(segment
		(start 85.034628 -27.996134)
		(end 85.023452 -27.996134)
		(width 0.254)
		(layer "F.Cu")
		(net "GND")
	)
	(segment
		(start 88.130888 -27.382724)
		(end 88.411304 -27.66314)
		(width 0.3048)
		(layer "F.Cu")
		(net "GND")
	)
	(segment
		(start 62.865 -9.467088)
		(end 62.865 -9.561068)
		(width 0.7112)
		(layer "F.Cu")
		(net "GND")
	)
	(segment
		(start 37.367972 -9.040876)
		(end 36.84778 -9.561068)
		(width 0.7112)
		(layer "F.Cu")
		(net "GND")
	)
	(segment
		(start 80.885792 -35.801554)
		(end 80.8863 -35.801046)
		(width 0.254)
		(layer "F.Cu")
		(net "GND")
	)
	(segment
		(start 189.249812 -8.45439)
		(end 189.1792 -8.383778)
		(width 0.254)
		(layer "F.Cu")
		(net "GND")
	)
	(segment
		(start 79.1464 -39.095934)
		(end 79.121 -39.070534)
		(width 0.254)
		(layer "F.Cu")
		(net "GND")
	)
	(segment
		(start 153.249884 -9.897364)
		(end 153.249884 -9.89076)
		(width 0.254)
		(layer "F.Cu")
		(net "GND")
	)
	(segment
		(start 87.99322 -45.610526)
		(end 87.99322 -45.610272)
		(width 0.254)
		(layer "F.Cu")
		(net "GND")
	)
	(segment
		(start 126.499874 -17.090644)
		(end 127.199898 -17.790668)
		(width 0.508)
		(layer "F.Cu")
		(net "GND")
	)
	(segment
		(start 187.149994 -3.001772)
		(end 187.149994 -1.68402)
		(width 0.254)
		(layer "F.Cu")
		(net "GND")
	)
	(segment
		(start 93.67774 -47.292514)
		(end 93.728286 -47.292514)
		(width 0.254)
		(layer "F.Cu")
		(net "GND")
	)
	(segment
		(start 82.885788 -41.417494)
		(end 82.88528 -41.416986)
		(width 0.254)
		(layer "F.Cu")
		(net "GND")
	)
	(segment
		(start 144.96161 -22.67458)
		(end 144.96161 -22.6314)
		(width 0.3048)
		(layer "F.Cu")
		(net "GND")
	)
	(segment
		(start 182.1688 -48.26)
		(end 182.118 -48.3108)
		(width 0.3048)
		(layer "F.Cu")
		(net "GND")
	)
	(segment
		(start 109.863128 -45.019214)
		(end 109.863128 -44.368466)
		(width 0.254)
		(layer "F.Cu")
		(net "GND")
	)
	(segment
		(start 50.0888 -17.526)
		(end 50.0126 -17.4498)
		(width 0.3048)
		(layer "F.Cu")
		(net "GND")
	)
	(segment
		(start 97.851468 -42.400474)
		(end 97.480882 -42.77106)
		(width 0.254)
		(layer "F.Cu")
		(net "GND")
	)
	(segment
		(start 58.8264 -32.6644)
		(end 56.863234 -30.701234)
		(width 0.3048)
		(layer "F.Cu")
		(net "GND")
	)
	(segment
		(start 170.815 -28.956)
		(end 172.1866 -28.956)
		(width 0.508)
		(layer "F.Cu")
		(net "GND")
	)
	(segment
		(start 97.950528 -33.698434)
		(end 97.950528 -33.697926)
		(width 0.254)
		(layer "F.Cu")
		(net "GND")
	)
	(segment
		(start 132.813044 -37.79393)
		(end 133.2738 -37.333174)
		(width 0.3048)
		(layer "F.Cu")
		(net "GND")
	)
	(segment
		(start 60.259722 -45.556678)
		(end 60.615068 -45.201586)
		(width 0.3048)
		(layer "F.Cu")
		(net "GND")
	)
	(segment
		(start 141.550136 -70.806564)
		(end 141.550136 -69.904864)
		(width 0.3048)
		(layer "F.Cu")
		(net "GND")
	)
	(segment
		(start 86.896448 -26.896314)
		(end 86.896448 -26.298398)
		(width 0.3048)
		(layer "F.Cu")
		(net "GND")
	)
	(segment
		(start 72.8472 -32.893)
		(end 72.842374 -32.888174)
		(width 0.3048)
		(layer "F.Cu")
		(net "GND")
	)
	(segment
		(start 129.250186 -63.806324)
		(end 128.985518 -64.070992)
		(width 0.254)
		(layer "F.Cu")
		(net "GND")
	)
	(segment
		(start 102.550468 -33.698434)
		(end 102.9589 -33.290002)
		(width 0.254)
		(layer "F.Cu")
		(net "GND")
	)
	(segment
		(start 109.913928 -35.311334)
		(end 109.913928 -35.310826)
		(width 0.254)
		(layer "F.Cu")
		(net "GND")
	)
	(segment
		(start 36.37788 -26.05532)
		(end 34.95294 -26.05532)
		(width 0.2794)
		(layer "F.Cu")
		(net "GND")
	)
	(segment
		(start 104.242108 -40.955214)
		(end 104.09936 -41.097962)
		(width 0.254)
		(layer "F.Cu")
		(net "GND")
	)
	(segment
		(start 107.945428 -32.131)
		(end 107.945428 -32.024828)
		(width 0.254)
		(layer "F.Cu")
		(net "GND")
	)
	(segment
		(start 152.6032 -11.7094)
		(end 152.5778 -11.684)
		(width 0.3048)
		(layer "F.Cu")
		(net "GND")
	)
	(segment
		(start 41.148 -37.309806)
		(end 41.148 -34.8107)
		(width 0.2794)
		(layer "F.Cu")
		(net "GND")
	)
	(segment
		(start 42.10177 -20.05457)
		(end 42.10177 -17.71523)
		(width 0.2794)
		(layer "F.Cu")
		(net "GND")
	)
	(segment
		(start 108.875068 -50.134774)
		(end 109.17809 -50.134774)
		(width 0.3048)
		(layer "F.Cu")
		(net "GND")
	)
	(segment
		(start 137.349992 -69.5452)
		(end 137.143998 -69.339206)
		(width 0.3048)
		(layer "F.Cu")
		(net "GND")
	)
	(segment
		(start 132.850128 -63.441072)
		(end 132.5372 -63.754)
		(width 0.254)
		(layer "F.Cu")
		(net "GND")
	)
	(segment
		(start 30.9118 -35.306)
		(end 30.607 -35.306)
		(width 0.3048)
		(layer "F.Cu")
		(net "GND")
	)
	(segment
		(start 34.95294 -26.05532)
		(end 34.684462 -25.786842)
		(width 0.2794)
		(layer "F.Cu")
		(net "GND")
	)
	(segment
		(start 174.249842 -8.941816)
		(end 174.7266 -8.465058)
		(width 0.254)
		(layer "F.Cu")
		(net "GND")
	)
	(segment
		(start 140.7668 -52.7812)
		(end 141.0462 -52.7812)
		(width 0.3048)
		(layer "F.Cu")
		(net "GND")
	)
	(segment
		(start 94.333568 -32.283654)
		(end 94.333568 -32.344106)
		(width 0.3048)
		(layer "F.Cu")
		(net "GND")
	)
	(segment
		(start 110.205774 -32.736028)
		(end 110.240572 -32.736028)
		(width 0.254)
		(layer "F.Cu")
		(net "GND")
	)
	(segment
		(start 138.49858 -23.9268)
		(end 138.49858 -23.010114)
		(width 0.3048)
		(layer "F.Cu")
		(net "GND")
	)
	(segment
		(start 81.788 -67.1322)
		(end 81.1784 -67.7418)
		(width 0.3048)
		(layer "F.Cu")
		(net "GND")
	)
	(segment
		(start 42.367962 -6.213602)
		(end 42.367962 -8.97001)
		(width 0.7112)
		(layer "F.Cu")
		(net "GND")
	)
	(segment
		(start 86.276434 -25.951434)
		(end 86.233 -25.908)
		(width 0.3048)
		(layer "F.Cu")
		(net "GND")
	)
	(segment
		(start 170.35018 -69.99224)
		(end 169.672 -69.31406)
		(width 0.254)
		(layer "F.Cu")
		(net "GND")
	)
	(segment
		(start 75.6412 -49.7078)
		(end 74.422 -49.7078)
		(width 0.3048)
		(layer "F.Cu")
		(net "GND")
	)
	(segment
		(start 111.65586 -44.566586)
		(end 110.683548 -44.566586)
		(width 0.254)
		(layer "F.Cu")
		(net "GND")
	)
	(segment
		(start 140.119608 -53.277008)
		(end 140.1064 -53.2638)
		(width 0.3048)
		(layer "F.Cu")
		(net "GND")
	)
	(segment
		(start 187.749942 -69.463412)
		(end 187.918852 -69.294502)
		(width 0.254)
		(layer "F.Cu")
		(net "GND")
	)
	(segment
		(start 108.024168 -25.951434)
		(end 107.673648 -26.301954)
		(width 0.254)
		(layer "F.Cu")
		(net "GND")
	)
	(segment
		(start 65.367916 -6.213602)
		(end 65.367916 -8.963152)
		(width 0.7112)
		(layer "F.Cu")
		(net "GND")
	)
	(segment
		(start 111.097568 -35.984434)
		(end 110.491016 -36.09594)
		(width 0.254)
		(layer "F.Cu")
		(net "GND")
	)
	(segment
		(start 153.3652 -30.29458)
		(end 152.2222 -30.29458)
		(width 0.3048)
		(layer "F.Cu")
		(net "GND")
	)
	(segment
		(start 145.4404 -69.73316)
		(end 145.4404 -69.4182)
		(width 0.254)
		(layer "F.Cu")
		(net "GND")
	)
	(segment
		(start 110.602268 -44.485306)
		(end 110.358428 -44.729146)
		(width 0.254)
		(layer "F.Cu")
		(net "GND")
	)
	(segment
		(start 172.150024 -70.806564)
		(end 172.150024 -69.915024)
		(width 0.254)
		(layer "F.Cu")
		(net "GND")
	)
	(segment
		(start 79.601568 -30.091634)
		(end 80.495648 -30.091634)
		(width 0.3048)
		(layer "F.Cu")
		(net "GND")
	)
	(segment
		(start 112.666018 -31.133796)
		(end 112.653318 -31.133796)
		(width 0.254)
		(layer "F.Cu")
		(net "GND")
	)
	(segment
		(start 84.582 -53.528468)
		(end 84.582 -53.555392)
		(width 0.254)
		(layer "F.Cu")
		(net "GND")
	)
	(segment
		(start 93.974412 -28.885388)
		(end 93.978476 -28.881324)
		(width 0.3048)
		(layer "F.Cu")
		(net "GND")
	)
	(segment
		(start 111.082836 -37.149278)
		(end 111.099092 -37.149278)
		(width 0.254)
		(layer "F.Cu")
		(net "GND")
	)
	(segment
		(start 95.903288 -26.895806)
		(end 95.903288 -26.896314)
		(width 0.254)
		(layer "F.Cu")
		(net "GND")
	)
	(segment
		(start 70.8152 -9.4996)
		(end 70.8152 -9.5758)
		(width 0.7112)
		(layer "F.Cu")
		(net "GND")
	)
	(segment
		(start 132.1308 -30.29458)
		(end 130.81 -30.29458)
		(width 0.3048)
		(layer "F.Cu")
		(net "GND")
	)
	(segment
		(start 106.528108 -36.982654)
		(end 106.413554 -36.8681)
		(width 0.254)
		(layer "F.Cu")
		(net "GND")
	)
	(segment
		(start 85.687408 -29.235654)
		(end 84.724748 -29.235654)
		(width 0.3048)
		(layer "F.Cu")
		(net "GND")
	)
	(segment
		(start 53.10124 -46.2915)
		(end 53.10124 -45.93336)
		(width 0.3048)
		(layer "F.Cu")
		(net "GND")
	)
	(segment
		(start 17.35201 -6.1976)
		(end 17.35201 -9.100058)
		(width 0.7112)
		(layer "F.Cu")
		(net "GND")
	)
	(segment
		(start 103.099108 -34.996374)
		(end 103.099108 -35.697414)
		(width 0.3048)
		(layer "F.Cu")
		(net "GND")
	)
	(segment
		(start 100.249228 -35.999674)
		(end 99.877626 -35.628072)
		(width 0.3048)
		(layer "F.Cu")
		(net "GND")
	)
	(segment
		(start 81.788 -34.374328)
		(end 81.963514 -34.549842)
		(width 0.254)
		(layer "F.Cu")
		(net "GND")
	)
	(segment
		(start 109.3724 -41.786302)
		(end 109.711744 -41.786302)
		(width 0.254)
		(layer "F.Cu")
		(net "GND")
	)
	(segment
		(start 103.861108 -35.697414)
		(end 103.863648 -35.697414)
		(width 0.3048)
		(layer "F.Cu")
		(net "GND")
	)
	(segment
		(start 131.949952 -69.962268)
		(end 132.53466 -69.37756)
		(width 0.254)
		(layer "F.Cu")
		(net "GND")
	)
	(segment
		(start 40.18407 -24.55545)
		(end 40.15867 -24.58085)
		(width 0.2794)
		(layer "F.Cu")
		(net "GND")
	)
	(segment
		(start 86.674198 -44.689014)
		(end 86.32825 -45.034962)
		(width 0.254)
		(layer "F.Cu")
		(net "GND")
	)
	(segment
		(start 106.172508 -28.414726)
		(end 106.577384 -28.819602)
		(width 0.254)
		(layer "F.Cu")
		(net "GND")
	)
	(segment
		(start 79.95158 -31.879286)
		(end 80.211168 -31.879286)
		(width 0.254)
		(layer "F.Cu")
		(net "GND")
	)
	(segment
		(start 96.17075 -34.479992)
		(end 96.251268 -34.399474)
		(width 0.3048)
		(layer "F.Cu")
		(net "GND")
	)
	(segment
		(start 110.335568 -52.654708)
		(end 110.987078 -53.306218)
		(width 0.254)
		(layer "F.Cu")
		(net "GND")
	)
	(segment
		(start 186.250072 -63.446914)
		(end 186.673998 -63.87084)
		(width 0.254)
		(layer "F.Cu")
		(net "GND")
	)
	(segment
		(start 106.909108 -34.996374)
		(end 106.9086 -34.996374)
		(width 0.254)
		(layer "F.Cu")
		(net "GND")
	)
	(segment
		(start 70.367906 -6.213602)
		(end 70.367906 -9.052306)
		(width 0.7112)
		(layer "F.Cu")
		(net "GND")
	)
	(segment
		(start 107.549188 -27.995626)
		(end 107.549188 -27.996134)
		(width 0.254)
		(layer "F.Cu")
		(net "GND")
	)
	(segment
		(start 34.417 -39.4462)
		(end 34.417 -39.5732)
		(width 0.508)
		(layer "F.Cu")
		(net "GND")
	)
	(segment
		(start 24.7142 -49.7332)
		(end 24.3586 -50.0888)
		(width 0.3048)
		(layer "F.Cu")
		(net "GND")
	)
	(segment
		(start 137.050018 -63.745618)
		(end 137.3886 -64.0842)
		(width 0.254)
		(layer "F.Cu")
		(net "GND")
	)
	(segment
		(start 95.965772 -29.269182)
		(end 95.965772 -29.212032)
		(width 0.3048)
		(layer "F.Cu")
		(net "GND")
	)
	(segment
		(start 103.099616 -43.642026)
		(end 103.163878 -43.642026)
		(width 0.254)
		(layer "F.Cu")
		(net "GND")
	)
	(segment
		(start 42.10177 -21.55444)
		(end 38.956234 -21.55444)
		(width 0.2794)
		(layer "F.Cu")
		(net "GND")
	)
	(segment
		(start 79.738728 -26.088594)
		(end 79.738728 -26.042874)
		(width 0.3048)
		(layer "F.Cu")
		(net "GND")
	)
	(segment
		(start 146.950176 -70.806564)
		(end 146.950176 -69.55917)
		(width 0.254)
		(layer "F.Cu")
		(net "GND")
	)
	(segment
		(start 102.779068 -36.982654)
		(end 102.779068 -36.982146)
		(width 0.3048)
		(layer "F.Cu")
		(net "GND")
	)
	(segment
		(start 80.546448 -38.835838)
		(end 80.695292 -38.686994)
		(width 0.254)
		(layer "F.Cu")
		(net "GND")
	)
	(segment
		(start 43.8912 -18.415)
		(end 42.7482 -17.272)
		(width 0.3048)
		(layer "F.Cu")
		(net "GND")
	)
	(segment
		(start 53.349906 -6.195568)
		(end 53.349906 -8.941562)
		(width 0.7112)
		(layer "F.Cu")
		(net "GND")
	)
	(segment
		(start 107.2134 -39.360602)
		(end 107.280202 -39.2938)
		(width 0.3048)
		(layer "F.Cu")
		(net "GND")
	)
	(segment
		(start 173.049946 -62.59322)
		(end 173.049946 -63.982346)
		(width 0.254)
		(layer "F.Cu")
		(net "GND")
	)
	(segment
		(start 47.4472 -18.415)
		(end 46.5328 -18.415)
		(width 0.3048)
		(layer "F.Cu")
		(net "GND")
	)
	(segment
		(start 80.495648 -30.091634)
		(end 80.546448 -30.142434)
		(width 0.3048)
		(layer "F.Cu")
		(net "GND")
	)
	(segment
		(start 177.8762 -69.631814)
		(end 177.8762 -69.3674)
		(width 0.254)
		(layer "F.Cu")
		(net "GND")
	)
	(segment
		(start 133.8707 -46.4947)
		(end 133.7564 -46.609)
		(width 0.3048)
		(layer "F.Cu")
		(net "GND")
	)
	(segment
		(start 91.806776 -46.116494)
		(end 92.631768 -46.116494)
		(width 0.254)
		(layer "F.Cu")
		(net "GND")
	)
	(segment
		(start 176.403 -58.0898)
		(end 176.4284 -58.1152)
		(width 0.3048)
		(layer "F.Cu")
		(net "GND")
	)
	(segment
		(start 107.643168 -27.901646)
		(end 107.549188 -27.995626)
		(width 0.254)
		(layer "F.Cu")
		(net "GND")
	)
	(segment
		(start 134.050024 -9.897364)
		(end 134.050024 -8.933942)
		(width 0.3048)
		(layer "F.Cu")
		(net "GND")
	)
	(segment
		(start 184.449974 -64.094868)
		(end 184.3913 -64.153542)
		(width 0.254)
		(layer "F.Cu")
		(net "GND")
	)
	(segment
		(start 139.44981 -9.897364)
		(end 139.44981 -8.997188)
		(width 0.254)
		(layer "F.Cu")
		(net "GND")
	)
	(segment
		(start 170.35018 -70.806564)
		(end 170.35018 -69.99224)
		(width 0.254)
		(layer "F.Cu")
		(net "GND")
	)
	(segment
		(start 134.62 -15.748)
		(end 134.35076 -16.01724)
		(width 0.3048)
		(layer "F.Cu")
		(net "GND")
	)
	(segment
		(start 49.349914 -6.195568)
		(end 49.349914 -9.080754)
		(width 0.7112)
		(layer "F.Cu")
		(net "GND")
	)
	(segment
		(start 140.64488 -3.049778)
		(end 140.64488 -3.123438)
		(width 0.254)
		(layer "F.Cu")
		(net "GND")
	)
	(segment
		(start 55.6768 -40.26916)
		(end 55.6768 -39.878)
		(width 0.3556)
		(layer "F.Cu")
		(net "GND")
	)
	(segment
		(start 134.949946 -2.605024)
		(end 135.255 -2.910078)
		(width 0.254)
		(layer "F.Cu")
		(net "GND")
	)
	(segment
		(start 110.053628 -32.189674)
		(end 109.883448 -32.019494)
		(width 0.254)
		(layer "F.Cu")
		(net "GND")
	)
	(segment
		(start 191.056514 -36.376102)
		(end 191.056514 -37.239702)
		(width 0.2032)
		(layer "F.Cu")
		(net "GND")
	)
	(segment
		(start 165.250114 -62.59322)
		(end 165.250114 -63.388494)
		(width 0.3048)
		(layer "F.Cu")
		(net "GND")
	)
	(segment
		(start 85.128608 -27.300174)
		(end 84.768436 -27.660346)
		(width 0.254)
		(layer "F.Cu")
		(net "GND")
	)
	(segment
		(start 103.325168 -45.0342)
		(end 103.672132 -45.381164)
		(width 0.254)
		(layer "F.Cu")
		(net "GND")
	)
	(segment
		(start 82.59064 -49.472596)
		(end 82.59064 -49.448466)
		(width 0.254)
		(layer "F.Cu")
		(net "GND")
	)
	(segment
		(start 152.23236 -36.79444)
		(end 152.1968 -36.83)
		(width 0.3048)
		(layer "F.Cu")
		(net "GND")
	)
	(segment
		(start 105.766108 -33.710626)
		(end 106.109262 -33.367472)
		(width 0.254)
		(layer "F.Cu")
		(net "GND")
	)
	(segment
		(start 81.366868 -39.037514)
		(end 81.366868 -38.944296)
		(width 0.254)
		(layer "F.Cu")
		(net "GND")
	)
	(segment
		(start 98.544888 -27.996134)
		(end 98.54438 -27.996134)
		(width 0.254)
		(layer "F.Cu")
		(net "GND")
	)
	(segment
		(start 164.719 -41.9608)
		(end 164.719 -41.372028)
		(width 0.3048)
		(layer "F.Cu")
		(net "GND")
	)
	(segment
		(start 38.9128 -15.494)
		(end 39.0398 -15.367)
		(width 0.508)
		(layer "F.Cu")
		(net "GND")
	)
	(segment
		(start 92.753434 -28.186634)
		(end 93.0656 -28.4988)
		(width 0.3048)
		(layer "F.Cu")
		(net "GND")
	)
	(segment
		(start 93.728286 -47.241968)
		(end 93.728286 -47.292514)
		(width 0.254)
		(layer "F.Cu")
		(net "GND")
	)
	(segment
		(start 109.96803 -28.472892)
		(end 110.053628 -28.387294)
		(width 0.254)
		(layer "F.Cu")
		(net "GND")
	)
	(segment
		(start 81.646268 -32.001714)
		(end 81.554828 -31.910274)
		(width 0.254)
		(layer "F.Cu")
		(net "GND")
	)
	(segment
		(start 86.8807 -49.892458)
		(end 86.875366 -49.892458)
		(width 0.254)
		(layer "F.Cu")
		(net "GND")
	)
	(segment
		(start 85.958934 -39.141908)
		(end 85.958934 -39.065708)
		(width 0.254)
		(layer "F.Cu")
		(net "GND")
	)
	(segment
		(start 79.601568 -43.598846)
		(end 79.601568 -43.599354)
		(width 0.254)
		(layer "F.Cu")
		(net "GND")
	)
	(segment
		(start 129.347976 -69.6722)
		(end 129.347976 -69.290184)
		(width 0.254)
		(layer "F.Cu")
		(net "GND")
	)
	(segment
		(start 182.049928 -9.897364)
		(end 182.049928 -8.82015)
		(width 0.254)
		(layer "F.Cu")
		(net "GND")
	)
	(segment
		(start 45.9994 -21.5392)
		(end 45.974 -21.5392)
		(width 0.3048)
		(layer "F.Cu")
		(net "GND")
	)
	(segment
		(start 140.950188 -70.806564)
		(end 140.950188 -69.444108)
		(width 0.3048)
		(layer "F.Cu")
		(net "GND")
	)
	(segment
		(start 91.242388 -50.2158)
		(end 91.706954 -50.2158)
		(width 0.254)
		(layer "F.Cu")
		(net "GND")
	)
	(segment
		(start 86.314788 -39.431214)
		(end 86.314788 -39.430706)
		(width 0.254)
		(layer "F.Cu")
		(net "GND")
	)
	(segment
		(start 94.651068 -35.199574)
		(end 94.278704 -34.82721)
		(width 0.3048)
		(layer "F.Cu")
		(net "GND")
	)
	(segment
		(start 90.361008 -29.235654)
		(end 90.361262 -29.235908)
		(width 0.3048)
		(layer "F.Cu")
		(net "GND")
	)
	(segment
		(start 137.349992 -70.806564)
		(end 137.349992 -69.5452)
		(width 0.3048)
		(layer "F.Cu")
		(net "GND")
	)
	(segment
		(start 46.710854 -19.60245)
		(end 46.5582 -19.449796)
		(width 0.3048)
		(layer "F.Cu")
		(net "GND")
	)
	(segment
		(start 90.030808 -50.213514)
		(end 89.543128 -50.213514)
		(width 0.254)
		(layer "F.Cu")
		(net "GND")
	)
	(segment
		(start 95.7072 -45.3644)
		(end 95.7072 -45.300646)
		(width 0.3048)
		(layer "F.Cu")
		(net "GND")
	)
	(segment
		(start 90.6272 -48.145446)
		(end 90.6272 -48.514)
		(width 0.254)
		(layer "F.Cu")
		(net "GND")
	)
	(segment
		(start 82.504788 -42.702734)
		(end 82.829908 -43.027854)
		(width 0.254)
		(layer "F.Cu")
		(net "GND")
	)
	(segment
		(start 168.0464 -39.8018)
		(end 168.021 -39.8272)
		(width 0.508)
		(layer "F.Cu")
		(net "GND")
	)
	(segment
		(start 87.388192 -40.716454)
		(end 87.07755 -41.027096)
		(width 0.254)
		(layer "F.Cu")
		(net "GND")
	)
	(segment
		(start 74.4982 -41.6052)
		(end 75.437238 -41.6052)
		(width 0.3048)
		(layer "F.Cu")
		(net "GND")
	)
	(segment
		(start 106.909108 -39.669974)
		(end 107.2134 -39.365682)
		(width 0.3048)
		(layer "F.Cu")
		(net "GND")
	)
	(segment
		(start 142.49781 -44.29887)
		(end 142.49781 -45.1612)
		(width 0.3048)
		(layer "F.Cu")
		(net "GND")
	)
	(segment
		(start 115.8748 -70.2056)
		(end 115.8748 -69.9516)
		(width 0.3048)
		(layer "F.Cu")
		(net "GND")
	)
	(segment
		(start 112.098328 -40.741346)
		(end 111.76762 -40.741346)
		(width 0.254)
		(layer "F.Cu")
		(net "GND")
	)
	(segment
		(start 101.669088 -27.743912)
		(end 101.7778 -27.6352)
		(width 0.254)
		(layer "F.Cu")
		(net "GND")
	)
	(segment
		(start 83.266788 -31.467806)
		(end 82.883502 -31.08452)
		(width 0.254)
		(layer "F.Cu")
		(net "GND")
	)
	(segment
		(start 138.38809 -46.602904)
		(end 138.38809 -45.953934)
		(width 0.3048)
		(layer "F.Cu")
		(net "GND")
	)
	(segment
		(start 102.779068 -36.982146)
		(end 103.12146 -36.639754)
		(width 0.3048)
		(layer "F.Cu")
		(net "GND")
	)
	(segment
		(start 81.788 -67.1322)
		(end 81.788 -66.3448)
		(width 0.3048)
		(layer "F.Cu")
		(net "GND")
	)
	(segment
		(start 90.648028 -40.000174)
		(end 90.321892 -39.674038)
		(width 0.254)
		(layer "F.Cu")
		(net "GND")
	)
	(segment
		(start 50.7492 -17.4498)
		(end 50.0126 -17.4498)
		(width 0.508)
		(layer "F.Cu")
		(net "GND")
	)
	(segment
		(start 182.94985 -2.588768)
		(end 182.65394 -2.884678)
		(width 0.254)
		(layer "F.Cu")
		(net "GND")
	)
	(segment
		(start 181.150006 -2.767584)
		(end 181.356 -2.973578)
		(width 0.254)
		(layer "F.Cu")
		(net "GND")
	)
	(segment
		(start 173.049946 -63.982346)
		(end 173.2026 -64.135)
		(width 0.254)
		(layer "F.Cu")
		(net "GND")
	)
	(segment
		(start 82.9564 -47.7012)
		(end 82.9564 -47.686722)
		(width 0.254)
		(layer "F.Cu")
		(net "GND")
	)
	(segment
		(start 91.407488 -45.735494)
		(end 91.407488 -45.766482)
		(width 0.254)
		(layer "F.Cu")
		(net "GND")
	)
	(segment
		(start 80.62341 -37.935916)
		(end 81.127854 -37.935916)
		(width 0.254)
		(layer "F.Cu")
		(net "GND")
	)
	(segment
		(start 105.4608 -21.5138)
		(end 105.2322 -21.7424)
		(width 0.381)
		(layer "F.Cu")
		(net "GND")
	)
	(segment
		(start 83.763866 -29.499814)
		(end 84.05114 -29.21254)
		(width 0.3048)
		(layer "F.Cu")
		(net "GND")
	)
	(segment
		(start 87.267034 -31.496)
		(end 87.122 -31.496)
		(width 0.3048)
		(layer "F.Cu")
		(net "GND")
	)
	(segment
		(start 46.8122 -19.939)
		(end 46.710854 -19.837654)
		(width 0.3048)
		(layer "F.Cu")
		(net "GND")
	)
	(segment
		(start 86.896448 -26.298398)
		(end 86.947248 -26.247598)
		(width 0.3048)
		(layer "F.Cu")
		(net "GND")
	)
	(segment
		(start 91.768168 -46.077886)
		(end 91.806776 -46.116494)
		(width 0.254)
		(layer "F.Cu")
		(net "GND")
	)
	(segment
		(start 153.249884 -9.89076)
		(end 153.249884 -9.106662)
		(width 0.3048)
		(layer "F.Cu")
		(net "GND")
	)
	(segment
		(start 81.785968 -30.602174)
		(end 81.785968 -30.122114)
		(width 0.3048)
		(layer "F.Cu")
		(net "GND")
	)
	(segment
		(start 91.245944 -34.604198)
		(end 91.245944 -34.611056)
		(width 0.254)
		(layer "F.Cu")
		(net "GND")
	)
	(segment
		(start 110.749588 -33.141412)
		(end 110.749588 -32.982154)
		(width 0.254)
		(layer "F.Cu")
		(net "GND")
	)
	(segment
		(start 184.15 -54.2798)
		(end 184.15 -55.1688)
		(width 0.3048)
		(layer "F.Cu")
		(net "GND")
	)
	(segment
		(start 109.913928 -34.290254)
		(end 109.913928 -34.723832)
		(width 0.254)
		(layer "F.Cu")
		(net "GND")
	)
	(segment
		(start 136.750044 -3.02133)
		(end 136.642856 -3.128518)
		(width 0.3048)
		(layer "F.Cu")
		(net "GND")
	)
	(segment
		(start 44.19092 -26.05532)
		(end 44.323 -26.1874)
		(width 0.2794)
		(layer "F.Cu")
		(net "GND")
	)
	(segment
		(start 177.54981 -3.046476)
		(end 177.673762 -3.170428)
		(width 0.254)
		(layer "F.Cu")
		(net "GND")
	)
	(segment
		(start 91.242388 -50.741834)
		(end 91.242388 -50.2158)
		(width 0.254)
		(layer "F.Cu")
		(net "GND")
	)
	(segment
		(start 58.349896 -9.05129)
		(end 58.87212 -9.573514)
		(width 0.7112)
		(layer "F.Cu")
		(net "GND")
	)
	(segment
		(start 110.335568 -51.498754)
		(end 110.335568 -52.311554)
		(width 0.254)
		(layer "F.Cu")
		(net "GND")
	)
	(segment
		(start 90.013028 -26.408126)
		(end 90.013028 -25.951434)
		(width 0.2032)
		(layer "F.Cu")
		(net "GND")
	)
	(segment
		(start 90.648028 -34.399474)
		(end 90.660474 -34.399474)
		(width 0.254)
		(layer "F.Cu")
		(net "GND")
	)
	(segment
		(start 185.64987 -9.897364)
		(end 185.64987 -9.120886)
		(width 0.254)
		(layer "F.Cu")
		(net "GND")
	)
	(segment
		(start 88.135968 -48.021494)
		(end 88.598248 -47.559214)
		(width 0.254)
		(layer "F.Cu")
		(net "GND")
	)
	(segment
		(start 81.785968 -43.96994)
		(end 82.08391 -43.671998)
		(width 0.254)
		(layer "F.Cu")
		(net "GND")
	)
	(segment
		(start 146.649948 -63.693548)
		(end 147.0152 -64.0588)
		(width 0.254)
		(layer "F.Cu")
		(net "GND")
	)
	(segment
		(start 113.5888 -30.4292)
		(end 113.370614 -30.4292)
		(width 0.254)
		(layer "F.Cu")
		(net "GND")
	)
	(segment
		(start 82.215228 -35.748214)
		(end 82.504788 -35.458654)
		(width 0.254)
		(layer "F.Cu")
		(net "GND")
	)
	(segment
		(start 176.650396 -62.593474)
		(end 176.650396 -63.651384)
		(width 0.254)
		(layer "F.Cu")
		(net "GND")
	)
	(segment
		(start 14.605 -54.4322)
		(end 13.716 -54.4322)
		(width 0.508)
		(layer "F.Cu")
		(net "GND")
	)
	(segment
		(start 46.355 -22.2758)
		(end 46.355 -21.8948)
		(width 0.3048)
		(layer "F.Cu")
		(net "GND")
	)
	(segment
		(start 89.171272 -37.444934)
		(end 89.177622 -37.451284)
		(width 0.254)
		(layer "F.Cu")
		(net "GND")
	)
	(segment
		(start 141.4272 -47.4472)
		(end 141.4272 -47.238412)
		(width 0.508)
		(layer "F.Cu")
		(net "GND")
	)
	(segment
		(start 98.649028 -39.961058)
		(end 98.3107 -39.62273)
		(width 0.3048)
		(layer "F.Cu")
		(net "GND")
	)
	(segment
		(start 93.340428 -27.996134)
		(end 93.340428 -27.880818)
		(width 0.3048)
		(layer "F.Cu")
		(net "GND")
	)
	(segment
		(start 136.750044 -1.68402)
		(end 136.750044 -3.02133)
		(width 0.3048)
		(layer "F.Cu")
		(net "GND")
	)
	(segment
		(start 92.993972 -35.199574)
		(end 92.6084 -34.814002)
		(width 0.3048)
		(layer "F.Cu")
		(net "GND")
	)
	(segment
		(start 153.849578 -9.89711)
		(end 153.849578 -8.934958)
		(width 0.3048)
		(layer "F.Cu")
		(net "GND")
	)
	(segment
		(start 42.7482 -17.272)
		(end 42.545 -17.272)
		(width 0.3048)
		(layer "F.Cu")
		(net "GND")
	)
	(segment
		(start 103.480108 -37.683694)
		(end 103.480108 -37.683186)
		(width 0.3048)
		(layer "F.Cu")
		(net "GND")
	)
	(segment
		(start 81.308448 -39.095426)
		(end 81.146142 -39.095426)
		(width 0.254)
		(layer "F.Cu")
		(net "GND")
	)
	(segment
		(start 96.251268 -36.799774)
		(end 96.251268 -36.797996)
		(width 0.3048)
		(layer "F.Cu")
		(net "GND")
	)
	(segment
		(start 109.893862 -35.29076)
		(end 109.893862 -34.800286)
		(width 0.254)
		(layer "F.Cu")
		(net "GND")
	)
	(segment
		(start 79.601568 -36.032694)
		(end 79.568548 -35.999674)
		(width 0.254)
		(layer "F.Cu")
		(net "GND")
	)
	(segment
		(start 81.100168 -35.811206)
		(end 81.090008 -35.801046)
		(width 0.254)
		(layer "F.Cu")
		(net "GND")
	)
	(segment
		(start 176.949862 -1.68402)
		(end 176.949862 -2.807716)
		(width 0.254)
		(layer "F.Cu")
		(net "GND")
	)
	(segment
		(start 88.387428 -25.639268)
		(end 88.19642 -25.44826)
		(width 0.3048)
		(layer "F.Cu")
		(net "GND")
	)
	(segment
		(start 82.052922 -47.592234)
		(end 82.242406 -47.781718)
		(width 0.254)
		(layer "F.Cu")
		(net "GND")
	)
	(segment
		(start 173.34992 -1.68402)
		(end 173.34992 -2.463038)
		(width 0.254)
		(layer "F.Cu")
		(net "GND")
	)
	(segment
		(start 101.752654 -36.703)
		(end 101.849428 -36.799774)
		(width 0.3048)
		(layer "F.Cu")
		(net "GND")
	)
	(segment
		(start 45.349922 -9.092184)
		(end 44.86656 -9.575546)
		(width 0.7112)
		(layer "F.Cu")
		(net "GND")
	)
	(segment
		(start 161.61766 -35.4838)
		(end 162.433 -34.66846)
		(width 0.508)
		(layer "F.Cu")
		(net "GND")
	)
	(segment
		(start 83.038442 -29.083)
		(end 83.266788 -28.854654)
		(width 0.254)
		(layer "F.Cu")
		(net "GND")
	)
	(segment
		(start 103.172006 -42.941494)
		(end 103.518208 -43.287696)
		(width 0.254)
		(layer "F.Cu")
		(net "GND")
	)
	(segment
		(start 90.648028 -36.059618)
		(end 90.27795 -36.429696)
		(width 0.254)
		(layer "F.Cu")
		(net "GND")
	)
	(segment
		(start 93.472 -42.776902)
		(end 93.472 -42.799)
		(width 0.254)
		(layer "F.Cu")
		(net "GND")
	)
	(segment
		(start 42.570908 -40.813736)
		(end 42.592752 -40.813736)
		(width 0.3048)
		(layer "F.Cu")
		(net "GND")
	)
	(segment
		(start 98.238564 -41.18737)
		(end 98.241358 -41.18737)
		(width 0.3048)
		(layer "F.Cu")
		(net "GND")
	)
	(segment
		(start 145.150078 -70.023482)
		(end 145.4404 -69.73316)
		(width 0.254)
		(layer "F.Cu")
		(net "GND")
	)
	(segment
		(start 138.772646 -22.440646)
		(end 138.772646 -22.736048)
		(width 0.3048)
		(layer "F.Cu")
		(net "GND")
	)
	(segment
		(start 150.64105 -41.29405)
		(end 149.5552 -40.2082)
		(width 0.3048)
		(layer "F.Cu")
		(net "GND")
	)
	(segment
		(start 79.60106 -40.535606)
		(end 79.427578 -40.535606)
		(width 0.254)
		(layer "F.Cu")
		(net "GND")
	)
	(segment
		(start 86.364826 -43.403774)
		(end 86.6902 -43.0784)
		(width 0.254)
		(layer "F.Cu")
		(net "GND")
	)
	(segment
		(start 97.480882 -42.77106)
		(end 97.421192 -42.77106)
		(width 0.254)
		(layer "F.Cu")
		(net "GND")
	)
	(segment
		(start 73.3679 -9.1059)
		(end 72.8726 -9.6012)
		(width 0.7112)
		(layer "F.Cu")
		(net "GND")
	)
	(segment
		(start 97.957894 -32.665924)
		(end 97.957894 -32.673036)
		(width 0.254)
		(layer "F.Cu")
		(net "GND")
	)
	(segment
		(start 81.788 -34.084006)
		(end 81.788 -34.374328)
		(width 0.254)
		(layer "F.Cu")
		(net "GND")
	)
	(segment
		(start 85.0392 -53.071268)
		(end 84.582 -53.528468)
		(width 0.254)
		(layer "F.Cu")
		(net "GND")
	)
	(segment
		(start 26.871676 -9.573768)
		(end 26.367994 -9.070086)
		(width 0.7112)
		(layer "F.Cu")
		(net "GND")
	)
	(segment
		(start 40.936926 -27.55519)
		(end 40.882316 -27.6098)
		(width 0.2794)
		(layer "F.Cu")
		(net "GND")
	)
	(segment
		(start 69.596 -56.5912)
		(end 69.7738 -56.4134)
		(width 0.3048)
		(layer "F.Cu")
		(net "GND")
	)
	(segment
		(start 92.202254 -42.3545)
		(end 92.248228 -42.400474)
		(width 0.254)
		(layer "F.Cu")
		(net "GND")
	)
	(segment
		(start 96.270826 -26.895806)
		(end 95.903288 -26.895806)
		(width 0.254)
		(layer "F.Cu")
		(net "GND")
	)
	(segment
		(start 108.745528 -50.264314)
		(end 108.875068 -50.134774)
		(width 0.3048)
		(layer "F.Cu")
		(net "GND")
	)
	(segment
		(start 86.695788 -37.444934)
		(end 87.011002 -37.12972)
		(width 0.254)
		(layer "F.Cu")
		(net "GND")
	)
	(segment
		(start 85.0773 -41.72712)
		(end 84.95538 -41.84904)
		(width 0.254)
		(layer "F.Cu")
		(net "GND")
	)
	(segment
		(start 88.651588 -50.404014)
		(end 88.67013 -50.404014)
		(width 0.254)
		(layer "F.Cu")
		(net "GND")
	)
	(segment
		(start 85.552788 -31.486094)
		(end 84.790788 -31.486094)
		(width 0.3048)
		(layer "F.Cu")
		(net "GND")
	)
	(segment
		(start 89.659968 -31.521654)
		(end 89.659968 -31.578296)
		(width 0.3048)
		(layer "F.Cu")
		(net "GND")
	)
	(segment
		(start 94.333568 -29.235654)
		(end 94.333568 -29.235146)
		(width 0.3048)
		(layer "F.Cu")
		(net "GND")
	)
	(segment
		(start 87.958168 -50.655728)
		(end 87.842598 -50.771298)
		(width 0.254)
		(layer "F.Cu")
		(net "GND")
	)
	(segment
		(start 109.863128 -44.368466)
		(end 109.913928 -44.317666)
		(width 0.254)
		(layer "F.Cu")
		(net "GND")
	)
	(segment
		(start 186.436 -51.435)
		(end 186.436 -52.07)
		(width 0.3048)
		(layer "F.Cu")
		(net "GND")
	)
	(segment
		(start 86.741508 -52.448714)
		(end 86.741508 -52.46624)
		(width 0.254)
		(layer "F.Cu")
		(net "GND")
	)
	(segment
		(start 80.540606 -27.714194)
		(end 80.1116 -28.1432)
		(width 0.3048)
		(layer "F.Cu")
		(net "GND")
	)
	(segment
		(start 88.920828 -37.444934)
		(end 89.171272 -37.444934)
		(width 0.254)
		(layer "F.Cu")
		(net "GND")
	)
	(segment
		(start 151.59863 -22.92477)
		(end 151.59863 -22.764496)
		(width 0.3048)
		(layer "F.Cu")
		(net "GND")
	)
	(segment
		(start 132.5372 -63.754)
		(end 132.5372 -64.23025)
		(width 0.254)
		(layer "F.Cu")
		(net "GND")
	)
	(segment
		(start 105.766108 -37.683694)
		(end 105.766108 -37.718492)
		(width 0.254)
		(layer "F.Cu")
		(net "GND")
	)
	(segment
		(start 104.026208 -45.735494)
		(end 104.026208 -45.734986)
		(width 0.254)
		(layer "F.Cu")
		(net "GND")
	)
	(segment
		(start 92.347288 -29.616654)
		(end 92.620592 -29.616654)
		(width 0.3048)
		(layer "F.Cu")
		(net "GND")
	)
	(segment
		(start 89.538048 -27.996134)
		(end 90.107008 -27.996134)
		(width 0.3048)
		(layer "F.Cu")
		(net "GND")
	)
	(segment
		(start 147.892516 -46.988984)
		(end 147.892516 -46.561502)
		(width 0.3048)
		(layer "F.Cu")
		(net "GND")
	)
	(segment
		(start 69.1642 -30.3022)
		(end 68.307712 -29.445712)
		(width 0.3048)
		(layer "F.Cu")
		(net "GND")
	)
	(segment
		(start 83.266788 -31.486094)
		(end 83.266788 -31.467806)
		(width 0.254)
		(layer "F.Cu")
		(net "GND")
	)
	(segment
		(start 93.4974 -41.151302)
		(end 93.4974 -41.1988)
		(width 0.3048)
		(layer "F.Cu")
		(net "GND")
	)
	(segment
		(start 99.451668 -35.999674)
		(end 99.451668 -35.998404)
		(width 0.3048)
		(layer "F.Cu")
		(net "GND")
	)
	(segment
		(start 81.785968 -44.109894)
		(end 81.785968 -43.96994)
		(width 0.254)
		(layer "F.Cu")
		(net "GND")
	)
	(segment
		(start 79.637128 -42.161206)
		(end 79.643986 -42.168064)
		(width 0.254)
		(layer "F.Cu")
		(net "GND")
	)
	(segment
		(start 96.17075 -35.119056)
		(end 96.17075 -34.479992)
		(width 0.3048)
		(layer "F.Cu")
		(net "GND")
	)
	(segment
		(start 109.931708 -33.581594)
		(end 110.309406 -33.581594)
		(width 0.254)
		(layer "F.Cu")
		(net "GND")
	)
	(segment
		(start 82.9564 -47.686722)
		(end 83.266788 -47.376334)
		(width 0.254)
		(layer "F.Cu")
		(net "GND")
	)
	(segment
		(start 177.25009 -63.56731)
		(end 177.7492 -64.06642)
		(width 0.254)
		(layer "F.Cu")
		(net "GND")
	)
	(segment
		(start 22.824948 -9.613646)
		(end 22.368002 -9.1567)
		(width 0.7112)
		(layer "F.Cu")
		(net "GND")
	)
	(segment
		(start 103.861108 -43.642026)
		(end 104.243632 -43.259502)
		(width 0.254)
		(layer "F.Cu")
		(net "GND")
	)
	(segment
		(start 107.673648 -26.301954)
		(end 107.673648 -26.560526)
		(width 0.254)
		(layer "F.Cu")
		(net "GND")
	)
	(segment
		(start 189.249812 -9.897364)
		(end 189.249812 -8.45439)
		(width 0.254)
		(layer "F.Cu")
		(net "GND")
	)
	(segment
		(start 90.593672 -50.264314)
		(end 90.0938 -50.764186)
		(width 0.254)
		(layer "F.Cu")
		(net "GND")
	)
	(segment
		(start 87.838788 -41.798494)
		(end 87.457788 -41.417494)
		(width 0.254)
		(layer "F.Cu")
		(net "GND")
	)
	(segment
		(start 173.34992 -2.463038)
		(end 173.04512 -2.767838)
		(width 0.254)
		(layer "F.Cu")
		(net "GND")
	)
	(segment
		(start 95.448628 -39.200074)
		(end 95.449898 -39.200074)
		(width 0.3048)
		(layer "F.Cu")
		(net "GND")
	)
	(segment
		(start 99.271836 -27.404314)
		(end 99.233482 -27.442668)
		(width 0.254)
		(layer "F.Cu")
		(net "GND")
	)
	(segment
		(start 143.649954 -9.897364)
		(end 143.649954 -8.475472)
		(width 0.254)
		(layer "F.Cu")
		(net "GND")
	)
	(segment
		(start 80.950308 -28.295854)
		(end 80.264254 -28.295854)
		(width 0.3048)
		(layer "F.Cu")
		(net "GND")
	)
	(segment
		(start 91.755468 -50.264314)
		(end 92.108528 -49.911254)
		(width 0.254)
		(layer "F.Cu")
		(net "GND")
	)
	(segment
		(start 59.128914 -20.89404)
		(end 58.363104 -20.89404)
		(width 0.3048)
		(layer "F.Cu")
		(net "GND")
	)
	(segment
		(start 107.696 -66.4972)
		(end 107.3658 -66.167)
		(width 0.3048)
		(layer "F.Cu")
		(net "GND")
	)
	(segment
		(start 132.588 -21.64588)
		(end 132.588 -20.1168)
		(width 0.3048)
		(layer "F.Cu")
		(net "GND")
	)
	(segment
		(start 130.750056 -1.68402)
		(end 130.750056 -3.027172)
		(width 0.3048)
		(layer "F.Cu")
		(net "GND")
	)
	(segment
		(start 84.815426 -45.014896)
		(end 84.795868 -45.014896)
		(width 0.3048)
		(layer "F.Cu")
		(net "GND")
	)
	(segment
		(start 109.896656 -41.037002)
		(end 109.563408 -41.037002)
		(width 0.254)
		(layer "F.Cu")
		(net "GND")
	)
	(segment
		(start 144.250156 -63.4492)
		(end 143.8402 -63.859156)
		(width 0.254)
		(layer "F.Cu")
		(net "GND")
	)
	(segment
		(start 88.600788 -34.757614)
		(end 88.600788 -35.458654)
		(width 0.254)
		(layer "F.Cu")
		(net "GND")
	)
	(segment
		(start 132.1308 -37.79393)
		(end 132.813044 -37.79393)
		(width 0.3048)
		(layer "F.Cu")
		(net "GND")
	)
	(segment
		(start 106.553 -35.322256)
		(end 106.552746 -35.322256)
		(width 0.254)
		(layer "F.Cu")
		(net "GND")
	)
	(segment
		(start 96.9137 -29.8196)
		(end 97.409 -30.3149)
		(width 0.2032)
		(layer "F.Cu")
		(net "GND")
	)
	(segment
		(start 91.450668 -28.149296)
		(end 91.425268 -28.174696)
		(width 0.3048)
		(layer "F.Cu")
		(net "GND")
	)
	(segment
		(start 183.134 -35.6108)
		(end 183.1848 -35.56)
		(width 0.3048)
		(layer "F.Cu")
		(net "GND")
	)
	(segment
		(start 97.950528 -33.697926)
		(end 98.649028 -33.697926)
		(width 0.254)
		(layer "F.Cu")
		(net "GND")
	)
	(segment
		(start 80.602328 -42.415206)
		(end 80.17256 -42.415206)
		(width 0.254)
		(layer "F.Cu")
		(net "GND")
	)
	(segment
		(start 82.504788 -47.376334)
		(end 82.504788 -47.519336)
		(width 0.254)
		(layer "F.Cu")
		(net "GND")
	)
	(segment
		(start 72.842374 -32.888174)
		(end 72.445626 -32.888174)
		(width 0.3048)
		(layer "F.Cu")
		(net "GND")
	)
	(segment
		(start 53.3527 -45.6819)
		(end 54.3179 -45.6819)
		(width 0.3048)
		(layer "F.Cu")
		(net "GND")
	)
	(segment
		(start 84.849208 -50.404014)
		(end 84.150708 -50.404014)
		(width 0.254)
		(layer "F.Cu")
		(net "GND")
	)
	(segment
		(start 119.6086 -62.357)
		(end 118.7958 -62.357)
		(width 0.508)
		(layer "F.Cu")
		(net "GND")
	)
	(segment
		(start 98.3107 -39.5986)
		(end 98.298 -39.5859)
		(width 0.3048)
		(layer "F.Cu")
		(net "GND")
	)
	(segment
		(start 80.602328 -42.415714)
		(end 80.602328 -42.415206)
		(width 0.254)
		(layer "F.Cu")
		(net "GND")
	)
	(segment
		(start 130.449828 -8.379206)
		(end 130.30327 -8.232648)
		(width 0.254)
		(layer "F.Cu")
		(net "GND")
	)
	(segment
		(start 145.4658 -69.3928)
		(end 145.4658 -69.3674)
		(width 0.254)
		(layer "F.Cu")
		(net "GND")
	)
	(segment
		(start 84.028788 -38.730174)
		(end 84.029296 -38.730174)
		(width 0.254)
		(layer "F.Cu")
		(net "GND")
	)
	(segment
		(start 110.145322 -46.397926)
		(end 110.51667 -46.026578)
		(width 0.254)
		(layer "F.Cu")
		(net "GND")
	)
	(segment
		(start 103.563928 -33.426654)
		(end 103.427276 -33.290002)
		(width 0.254)
		(layer "F.Cu")
		(net "GND")
	)
	(segment
		(start 185.64987 -9.120886)
		(end 186.302396 -8.46836)
		(width 0.254)
		(layer "F.Cu")
		(net "GND")
	)
	(segment
		(start 89.850468 -42.400474)
		(end 89.84996 -42.400474)
		(width 0.3048)
		(layer "F.Cu")
		(net "GND")
	)
	(segment
		(start 94.651068 -42.400474)
		(end 93.848428 -42.400474)
		(width 0.254)
		(layer "F.Cu")
		(net "GND")
	)
	(segment
		(start 47.217838 -33.959038)
		(end 46.632876 -34.544)
		(width 0.3048)
		(layer "F.Cu")
		(net "GND")
	)
	(segment
		(start 147.249896 -8.593074)
		(end 147.0914 -8.434578)
		(width 0.254)
		(layer "F.Cu")
		(net "GND")
	)
	(segment
		(start 88.744298 -27.996134)
		(end 88.411304 -27.66314)
		(width 0.3048)
		(layer "F.Cu")
		(net "GND")
	)
	(segment
		(start 37.349938 -6.195568)
		(end 37.367972 -6.213602)
		(width 0.7112)
		(layer "F.Cu")
		(net "GND")
	)
	(segment
		(start 99.824032 -39.57066)
		(end 99.874832 -39.57066)
		(width 0.3048)
		(layer "F.Cu")
		(net "GND")
	)
	(segment
		(start 109.673136 -40.515794)
		(end 109.357668 -40.831262)
		(width 0.254)
		(layer "F.Cu")
		(net "GND")
	)
	(segment
		(start 80.043528 -33.833054)
		(end 79.982822 -33.89376)
		(width 0.254)
		(layer "F.Cu")
		(net "GND")
	)
	(segment
		(start 112.76076 -30.11424)
		(end 112.27816 -30.11424)
		(width 0.254)
		(layer "F.Cu")
		(net "GND")
	)
	(segment
		(start 153.8732 -3.125978)
		(end 153.8478 -3.151378)
		(width 0.3048)
		(layer "F.Cu")
		(net "GND")
	)
	(segment
		(start 100.347526 -36.097972)
		(end 100.249228 -35.999674)
		(width 0.3048)
		(layer "F.Cu")
		(net "GND")
	)
	(segment
		(start 112.098328 -30.294072)
		(end 112.098328 -30.297374)
		(width 0.254)
		(layer "F.Cu")
		(net "GND")
	)
	(segment
		(start 66.4718 -12.573)
		(end 66.4718 -11.4554)
		(width 0.3048)
		(layer "F.Cu")
		(net "GND")
	)
	(segment
		(start 80.602328 -37.914834)
		(end 80.62341 -37.935916)
		(width 0.254)
		(layer "F.Cu")
		(net "GND")
	)
	(segment
		(start 111.097568 -40.485314)
		(end 111.097568 -40.484806)
		(width 0.254)
		(layer "F.Cu")
		(net "GND")
	)
	(segment
		(start 76.53528 -48.81372)
		(end 75.6412 -49.7078)
		(width 0.3048)
		(layer "F.Cu")
		(net "GND")
	)
	(segment
		(start 150.10765 -46.33595)
		(end 149.99843 -46.22673)
		(width 0.3048)
		(layer "F.Cu")
		(net "GND")
	)
	(segment
		(start 80.58277 -40.304974)
		(end 80.57515 -40.312594)
		(width 0.2032)
		(layer "F.Cu")
		(net "GND")
	)
	(segment
		(start 81.646268 -46.210474)
		(end 81.646268 -46.209966)
		(width 0.254)
		(layer "F.Cu")
		(net "GND")
	)
	(segment
		(start 98.244914 -36.39312)
		(end 97.851468 -35.999674)
		(width 0.3048)
		(layer "F.Cu")
		(net "GND")
	)
	(segment
		(start 107.617768 -26.616406)
		(end 107.617768 -27.274266)
		(width 0.3048)
		(layer "F.Cu")
		(net "GND")
	)
	(segment
		(start 104.432608 -28.120594)
		(end 104.447848 -28.135834)
		(width 0.254)
		(layer "F.Cu")
		(net "GND")
	)
	(segment
		(start 140.349986 -1.68402)
		(end 140.349986 -2.754884)
		(width 0.254)
		(layer "F.Cu")
		(net "GND")
	)
	(segment
		(start 135.208264 -55.960264)
		(end 135.001 -55.753)
		(width 0.3048)
		(layer "F.Cu")
		(net "GND")
	)
	(segment
		(start 94.333568 -32.344106)
		(end 93.632528 -33.045146)
		(width 0.3048)
		(layer "F.Cu")
		(net "GND")
	)
	(segment
		(start 106.528108 -41.656254)
		(end 106.5276 -41.655746)
		(width 0.254)
		(layer "F.Cu")
		(net "GND")
	)
	(segment
		(start 54.243732 -25.019)
		(end 54.007512 -25.019)
		(width 0.3048)
		(layer "F.Cu")
		(net "GND")
	)
	(segment
		(start 91.450668 -35.999674)
		(end 91.506802 -35.999674)
		(width 0.254)
		(layer "F.Cu")
		(net "GND")
	)
	(segment
		(start 184.449974 -62.59322)
		(end 184.449974 -64.094868)
		(width 0.254)
		(layer "F.Cu")
		(net "GND")
	)
	(segment
		(start 143.949928 -1.68402)
		(end 143.949928 -2.95275)
		(width 0.3048)
		(layer "F.Cu")
		(net "GND")
	)
	(segment
		(start 47.6504 -37.0586)
		(end 48.472598 -37.0586)
		(width 0.508)
		(layer "F.Cu")
		(net "GND")
	)
	(segment
		(start 74.5236 -38.481)
		(end 74.5236 -39.1414)
		(width 0.3048)
		(layer "F.Cu")
		(net "GND")
	)
	(segment
		(start 107.400852 -27.996134)
		(end 107.549188 -27.996134)
		(width 0.254)
		(layer "F.Cu")
		(net "GND")
	)
	(segment
		(start 129.8448 -44.0944)
		(end 129.921 -44.0182)
		(width 0.3048)
		(layer "F.Cu")
		(net "GND")
	)
	(segment
		(start 63.6016 -42.554144)
		(end 63.369444 -42.7863)
		(width 0.3048)
		(layer "F.Cu")
		(net "GND")
	)
	(segment
		(start 180.850032 -64.083692)
		(end 180.9369 -64.17056)
		(width 0.254)
		(layer "F.Cu")
		(net "GND")
	)
	(segment
		(start 188.05017 -62.59322)
		(end 188.05017 -64.0588)
		(width 0.254)
		(layer "F.Cu")
		(net "GND")
	)
	(segment
		(start 164.665914 -69.61886)
		(end 164.665914 -69.37756)
		(width 0.3048)
		(layer "F.Cu")
		(net "GND")
	)
	(segment
		(start 170.688 -28.829)
		(end 170.815 -28.956)
		(width 0.508)
		(layer "F.Cu")
		(net "GND")
	)
	(segment
		(start 112.653318 -31.133796)
		(end 112.392968 -31.394146)
		(width 0.254)
		(layer "F.Cu")
		(net "GND")
	)
	(segment
		(start 86.695788 -44.689014)
		(end 86.674198 -44.689014)
		(width 0.254)
		(layer "F.Cu")
		(net "GND")
	)
	(segment
		(start 146.349974 -1.68402)
		(end 146.349974 -2.465832)
		(width 0.3048)
		(layer "F.Cu")
		(net "GND")
	)
	(segment
		(start 141.27988 -44.04106)
		(end 142.24 -44.04106)
		(width 0.3048)
		(layer "F.Cu")
		(net "GND")
	)
	(segment
		(start 63.8302 -33.02)
		(end 62.259972 -33.02)
		(width 0.3048)
		(layer "F.Cu")
		(net "GND")
	)
	(segment
		(start 90.36304 -37.97554)
		(end 90.28684 -37.97554)
		(width 0.254)
		(layer "F.Cu")
		(net "GND")
	)
	(segment
		(start 145.4404 -69.4182)
		(end 145.4658 -69.3928)
		(width 0.254)
		(layer "F.Cu")
		(net "GND")
	)
	(segment
		(start 133.8707 -45.2882)
		(end 133.8707 -46.4947)
		(width 0.3048)
		(layer "F.Cu")
		(net "GND")
	)
	(segment
		(start 103.786178 -37.989256)
		(end 103.786178 -37.993066)
		(width 0.3048)
		(layer "F.Cu")
		(net "GND")
	)
	(segment
		(start 86.17712 -32.35452)
		(end 86.17712 -31.732982)
		(width 0.3048)
		(layer "F.Cu")
		(net "GND")
	)
	(segment
		(start 38.956234 -21.55444)
		(end 38.813994 -21.4122)
		(width 0.2794)
		(layer "F.Cu")
		(net "GND")
	)
	(segment
		(start 138.418316 -46.6344)
		(end 138.418316 -46.63313)
		(width 0.3048)
		(layer "F.Cu")
		(net "GND")
	)
	(segment
		(start 91.706954 -50.2158)
		(end 91.755468 -50.264314)
		(width 0.254)
		(layer "F.Cu")
		(net "GND")
	)
	(segment
		(start 103.479346 -36.077652)
		(end 103.099108 -35.697414)
		(width 0.3048)
		(layer "F.Cu")
		(net "GND")
	)
	(segment
		(start 110.053628 -46.397926)
		(end 110.145322 -46.397926)
		(width 0.254)
		(layer "F.Cu")
		(net "GND")
	)
	(segment
		(start 86.230968 -50.264314)
		(end 86.230968 -50.213768)
		(width 0.254)
		(layer "F.Cu")
		(net "GND")
	)
	(segment
		(start 110.186978 -45.696886)
		(end 110.51667 -46.026578)
		(width 0.254)
		(layer "F.Cu")
		(net "GND")
	)
	(segment
		(start 103.861108 -42.941494)
		(end 103.938832 -42.941494)
		(width 0.254)
		(layer "F.Cu")
		(net "GND")
	)
	(segment
		(start 47.6504 -37.0586)
		(end 47.6504 -36.3474)
		(width 0.508)
		(layer "F.Cu")
		(net "GND")
	)
	(segment
		(start 45.2374 -30.4546)
		(end 44.79544 -30.4546)
		(width 0.3048)
		(layer "F.Cu")
		(net "GND")
	)
	(segment
		(start 109.913928 -35.310826)
		(end 109.893862 -35.29076)
		(width 0.254)
		(layer "F.Cu")
		(net "GND")
	)
	(segment
		(start 95.633032 -28.135834)
		(end 95.9612 -28.464002)
		(width 0.3048)
		(layer "F.Cu")
		(net "GND")
	)
	(segment
		(start 172.1866 -28.956)
		(end 172.3136 -29.083)
		(width 0.508)
		(layer "F.Cu")
		(net "GND")
	)
	(segment
		(start 84.409788 -37.444934)
		(end 84.104988 -37.140134)
		(width 0.254)
		(layer "F.Cu")
		(net "GND")
	)
	(segment
		(start 107.67314 -44.6278)
		(end 107.973114 -44.927774)
		(width 0.254)
		(layer "F.Cu")
		(net "GND")
	)
	(segment
		(start 103.861616 -39.669974)
		(end 104.14 -39.948358)
		(width 0.3048)
		(layer "F.Cu")
		(net "GND")
	)
	(segment
		(start 99.238308 -27.447494)
		(end 99.233482 -27.442668)
		(width 0.254)
		(layer "F.Cu")
		(net "GND")
	)
	(segment
		(start 109.931708 -42.587926)
		(end 110.053628 -42.466006)
		(width 0.254)
		(layer "F.Cu")
		(net "GND")
	)
	(segment
		(start 95.921068 -27.658314)
		(end 95.954088 -27.658314)
		(width 0.3048)
		(layer "F.Cu")
		(net "GND")
	)
	(segment
		(start 93.979746 -28.881324)
		(end 93.979238 -28.881324)
		(width 0.3048)
		(layer "F.Cu")
		(net "GND")
	)
	(segment
		(start 152.5778 -11.492484)
		(end 153.249884 -10.8204)
		(width 0.3048)
		(layer "F.Cu")
		(net "GND")
	)
	(segment
		(start 18.36801 -9.133078)
		(end 18.796 -9.561068)
		(width 0.7112)
		(layer "F.Cu")
		(net "GND")
	)
	(segment
		(start 98.832416 -36.616386)
		(end 98.832416 -36.615878)
		(width 0.3048)
		(layer "F.Cu")
		(net "GND")
	)
	(segment
		(start 81.618328 -48.780954)
		(end 81.785968 -48.613314)
		(width 0.254)
		(layer "F.Cu")
		(net "GND")
	)
	(segment
		(start 141.8082 -46.857412)
		(end 141.8082 -46.791372)
		(width 0.508)
		(layer "F.Cu")
		(net "GND")
	)
	(segment
		(start 108.066332 -53.219096)
		(end 108.113068 -53.219096)
		(width 0.254)
		(layer "F.Cu")
		(net "GND")
	)
	(segment
		(start 103.5177 -25.6159)
		(end 103.5177 -25.449784)
		(width 0.254)
		(layer "F.Cu")
		(net "GND")
	)
	(segment
		(start 87.422228 -41.416986)
		(end 87.049864 -41.044622)
		(width 0.254)
		(layer "F.Cu")
		(net "GND")
	)
	(segment
		(start 158.547308 -51.3969)
		(end 158.433008 -51.2826)
		(width 0.254)
		(layer "F.Cu")
		(net "GND")
	)
	(segment
		(start 158.115 -22.5298)
		(end 158.623 -23.0378)
		(width 0.3048)
		(layer "F.Cu")
		(net "GND")
	)
	(segment
		(start 96.677734 -36.428172)
		(end 96.621092 -36.428172)
		(width 0.3048)
		(layer "F.Cu")
		(net "GND")
	)
	(segment
		(start 60.667392 -45.1612)
		(end 61.468 -45.1612)
		(width 0.3048)
		(layer "F.Cu")
		(net "GND")
	)
	(segment
		(start 91.765882 -46.0756)
		(end 91.768168 -46.077886)
		(width 0.254)
		(layer "F.Cu")
		(net "GND")
	)
	(segment
		(start 44.8818 -44.704)
		(end 45.6692 -44.704)
		(width 0.508)
		(layer "F.Cu")
		(net "GND")
	)
	(segment
		(start 90.0938 -50.764186)
		(end 90.0938 -50.7746)
		(width 0.254)
		(layer "F.Cu")
		(net "GND")
	)
	(segment
		(start 107.815888 -52.968652)
		(end 108.066332 -53.219096)
		(width 0.254)
		(layer "F.Cu")
		(net "GND")
	)
	(segment
		(start 141.986 -46.580552)
		(end 141.986 -46.613572)
		(width 0.3048)
		(layer "F.Cu")
		(net "GND")
	)
	(segment
		(start 90.648028 -38.399974)
		(end 90.648028 -38.260528)
		(width 0.254)
		(layer "F.Cu")
		(net "GND")
	)
	(segment
		(start 46.710854 -19.837654)
		(end 46.710854 -19.60245)
		(width 0.3048)
		(layer "F.Cu")
		(net "GND")
	)
	(segment
		(start 109.883448 -32.019494)
		(end 109.602016 -32.019494)
		(width 0.254)
		(layer "F.Cu")
		(net "GND")
	)
	(segment
		(start 85.18906 -35.85718)
		(end 85.18906 -35.856926)
		(width 0.254)
		(layer "F.Cu")
		(net "GND")
	)
	(segment
		(start 187.452 -16.6878)
		(end 187.2996 -16.5354)
		(width 0.3048)
		(layer "F.Cu")
		(net "GND")
	)
	(segment
		(start 89.701878 -37.451284)
		(end 89.850468 -37.599874)
		(width 0.254)
		(layer "F.Cu")
		(net "GND")
	)
	(segment
		(start 61.802772 -33.4772)
		(end 61.0108 -33.4772)
		(width 0.3048)
		(layer "F.Cu")
		(net "GND")
	)
	(segment
		(start 110.358428 -44.729146)
		(end 110.358428 -44.963334)
		(width 0.254)
		(layer "F.Cu")
		(net "GND")
	)
	(segment
		(start 103.325168 -44.973494)
		(end 103.325168 -45.0342)
		(width 0.254)
		(layer "F.Cu")
		(net "GND")
	)
	(segment
		(start 92.6338 -38.814502)
		(end 92.6338 -38.789102)
		(width 0.3048)
		(layer "F.Cu")
		(net "GND")
	)
	(segment
		(start 112.53724 -68.5165)
		(end 112.53724 -68.82384)
		(width 0.3048)
		(layer "F.Cu")
		(net "GND")
	)
	(segment
		(start 85.958934 -39.040308)
		(end 85.958934 -39.065708)
		(width 0.254)
		(layer "F.Cu")
		(net "GND")
	)
	(segment
		(start 82.349848 -9.148064)
		(end 82.828384 -9.6266)
		(width 0.7112)
		(layer "F.Cu")
		(net "GND")
	)
	(segment
		(start 101.4222 -42.7736)
		(end 101.4222 -42.770806)
		(width 0.3048)
		(layer "F.Cu")
		(net "GND")
	)
	(segment
		(start 53.6448 -24.656288)
		(end 53.6448 -23.495)
		(width 0.3048)
		(layer "F.Cu")
		(net "GND")
	)
	(segment
		(start 107.671108 -36.679124)
		(end 107.671108 -37.302694)
		(width 0.2032)
		(layer "F.Cu")
		(net "GND")
	)
	(segment
		(start 40.836596 -26.05532)
		(end 42.10177 -26.05532)
		(width 0.2794)
		(layer "F.Cu")
		(net "GND")
	)
	(segment
		(start 76.8604 -9.4996)
		(end 76.8604 -9.6012)
		(width 0.7112)
		(layer "F.Cu")
		(net "GND")
	)
	(segment
		(start 103.741728 -28.120594)
		(end 104.432608 -28.120594)
		(width 0.254)
		(layer "F.Cu")
		(net "GND")
	)
	(segment
		(start 18.349976 -6.195568)
		(end 18.36801 -6.213602)
		(width 0.7112)
		(layer "F.Cu")
		(net "GND")
	)
	(segment
		(start 95.962978 -30.749494)
		(end 95.939102 -30.749494)
		(width 0.3048)
		(layer "F.Cu")
		(net "GND")
	)
	(segment
		(start 96.251268 -39.99738)
		(end 95.885 -39.631112)
		(width 0.3048)
		(layer "F.Cu")
		(net "GND")
	)
	(segment
		(start 94.651068 -36.000944)
		(end 95.0468 -36.396676)
		(width 0.3048)
		(layer "F.Cu")
		(net "GND")
	)
	(segment
		(start 94.651068 -36.799774)
		(end 94.651068 -36.792408)
		(width 0.3048)
		(layer "F.Cu")
		(net "GND")
	)
	(segment
		(start 109.563408 -41.037002)
		(end 109.357668 -40.831262)
		(width 0.254)
		(layer "F.Cu")
		(net "GND")
	)
	(segment
		(start 84.14766 -31.95574)
		(end 84.321142 -31.95574)
		(width 0.3048)
		(layer "F.Cu")
		(net "GND")
	)
	(segment
		(start 87.434928 -47.329852)
		(end 87.434928 -47.259494)
		(width 0.254)
		(layer "F.Cu")
		(net "GND")
	)
	(segment
		(start 101.148642 -36.703)
		(end 101.752654 -36.703)
		(width 0.3048)
		(layer "F.Cu")
		(net "GND")
	)
	(segment
		(start 145.66138 -3.115818)
		(end 145.66138 -3.136138)
		(width 0.3048)
		(layer "F.Cu")
		(net "GND")
	)
	(segment
		(start 89.177622 -37.451284)
		(end 89.701878 -37.451284)
		(width 0.254)
		(layer "F.Cu")
		(net "GND")
	)
	(segment
		(start 104.9528 -39.298118)
		(end 104.9528 -39.317676)
		(width 0.3048)
		(layer "F.Cu")
		(net "GND")
	)
	(segment
		(start 90.0938 -50.812446)
		(end 90.0938 -50.7746)
		(width 0.254)
		(layer "F.Cu")
		(net "GND")
	)
	(segment
		(start 86.904068 -26.903934)
		(end 86.904068 -27.133296)
		(width 0.3048)
		(layer "F.Cu")
		(net "GND")
	)
	(segment
		(start 45.4152 -32.4358)
		(end 45.466 -32.385)
		(width 0.3048)
		(layer "F.Cu")
		(net "GND")
	)
	(segment
		(start 86.947248 -25.951434)
		(end 86.276434 -25.951434)
		(width 0.3048)
		(layer "F.Cu")
		(net "GND")
	)
	(segment
		(start 187.89777 -64.2112)
		(end 187.8965 -64.2112)
		(width 0.254)
		(layer "F.Cu")
		(net "GND")
	)
	(segment
		(start 78.349856 -9.148064)
		(end 78.828392 -9.6266)
		(width 0.7112)
		(layer "F.Cu")
		(net "GND")
	)
	(segment
		(start 176.04994 -8.559038)
		(end 176.1998 -8.409178)
		(width 0.254)
		(layer "F.Cu")
		(net "GND")
	)
	(segment
		(start 62.349888 -6.195568)
		(end 62.349888 -8.951976)
		(width 0.7112)
		(layer "F.Cu")
		(net "GND")
	)
	(segment
		(start 85.171788 -45.371258)
		(end 84.815426 -45.014896)
		(width 0.3048)
		(layer "F.Cu")
		(net "GND")
	)
	(segment
		(start 106.147108 -42.941748)
		(end 106.147108 -42.941494)
		(width 0.254)
		(layer "F.Cu")
		(net "GND")
	)
	(segment
		(start 29.367988 -9.054592)
		(end 28.85567 -9.56691)
		(width 0.7112)
		(layer "F.Cu")
		(net "GND")
	)
	(segment
		(start 185.09996 -50.82159)
		(end 185.82259 -50.82159)
		(width 0.3048)
		(layer "F.Cu")
		(net "GND")
	)
	(segment
		(start 82.504788 -30.785054)
		(end 82.584036 -30.785054)
		(width 0.254)
		(layer "F.Cu")
		(net "GND")
	)
	(segment
		(start 79.629 -60.4012)
		(end 79.6544 -60.3758)
		(width 0.3048)
		(layer "F.Cu")
		(net "GND")
	)
	(segment
		(start 46.5836 -20.1676)
		(end 46.5836 -20.939506)
		(width 0.3048)
		(layer "F.Cu")
		(net "GND")
	)
	(segment
		(start 153.249884 -10.8204)
		(end 153.249884 -9.897364)
		(width 0.3048)
		(layer "F.Cu")
		(net "GND")
	)
	(segment
		(start 95.618808 -31.879794)
		(end 95.9612 -31.537402)
		(width 0.3048)
		(layer "F.Cu")
		(net "GND")
	)
	(segment
		(start 60.651644 -45.176948)
		(end 60.667392 -45.1612)
		(width 0.3048)
		(layer "F.Cu")
		(net "GND")
	)
	(segment
		(start 56.16448 -42.037)
		(end 55.86476 -41.73728)
		(width 0.3048)
		(layer "F.Cu")
		(net "GND")
	)
	(segment
		(start 98.712528 -29.591254)
		(end 98.306128 -29.997654)
		(width 0.3048)
		(layer "F.Cu")
		(net "GND")
	)
	(segment
		(start 97.38233 -36.333176)
		(end 97.048828 -35.999674)
		(width 0.3048)
		(layer "F.Cu")
		(net "GND")
	)
	(segment
		(start 100.249228 -39.199566)
		(end 100.250498 -39.199566)
		(width 0.3048)
		(layer "F.Cu")
		(net "GND")
	)
	(segment
		(start 101.78923 -33.698434)
		(end 101.460808 -34.026856)
		(width 0.254)
		(layer "F.Cu")
		(net "GND")
	)
	(segment
		(start 41.367964 -9.076944)
		(end 40.868092 -9.576816)
		(width 0.7112)
		(layer "F.Cu")
		(net "GND")
	)
	(segment
		(start 104.14 -39.948358)
		(end 104.14 -40.0304)
		(width 0.3048)
		(layer "F.Cu")
		(net "GND")
	)
	(segment
		(start 85.4964 -46.4566)
		(end 85.4964 -46.618906)
		(width 0.254)
		(layer "F.Cu")
		(net "GND")
	)
	(segment
		(start 5.5626 -52.1716)
		(end 5.969 -51.7652)
		(width 0.254)
		(layer "F.Cu")
		(net "GND")
	)
	(segment
		(start 109.913928 -38.793674)
		(end 109.913928 -38.991032)
		(width 0.3048)
		(layer "F.Cu")
		(net "GND")
	)
	(segment
		(start 139.15009 -69.60489)
		(end 138.9126 -69.3674)
		(width 0.3048)
		(layer "F.Cu")
		(net "GND")
	)
	(segment
		(start 103.751888 -28.110434)
		(end 103.741728 -28.120594)
		(width 0.254)
		(layer "F.Cu")
		(net "GND")
	)
	(segment
		(start 109.87024 -65.29324)
		(end 109.2962 -64.7192)
		(width 0.3048)
		(layer "F.Cu")
		(net "GND")
	)
	(segment
		(start 79.601568 -31.529274)
		(end 79.248 -31.175706)
		(width 0.254)
		(layer "F.Cu")
		(net "GND")
	)
	(segment
		(start 105.468928 -28.135834)
		(end 106.121708 -28.135834)
		(width 0.254)
		(layer "F.Cu")
		(net "GND")
	)
	(segment
		(start 73.349866 -6.195568)
		(end 73.3679 -6.213602)
		(width 0.7112)
		(layer "F.Cu")
		(net "GND")
	)
	(segment
		(start 84.402168 -29.616654)
		(end 84.402168 -29.552646)
		(width 0.3048)
		(layer "F.Cu")
		(net "GND")
	)
	(segment
		(start 184.8612 -69.413374)
		(end 184.8612 -69.2912)
		(width 0.254)
		(layer "F.Cu")
		(net "GND")
	)
	(segment
		(start 93.632528 -29.220922)
		(end 93.968062 -28.885388)
		(width 0.3048)
		(layer "F.Cu")
		(net "GND")
	)
	(segment
		(start 103.863648 -35.697414)
		(end 104.19969 -36.033456)
		(width 0.3048)
		(layer "F.Cu")
		(net "GND")
	)
	(segment
		(start 80.211168 -31.879286)
		(end 80.211168 -31.879794)
		(width 0.254)
		(layer "F.Cu")
		(net "GND")
	)
	(segment
		(start 84.582 -53.555392)
		(end 84.575396 -53.561996)
		(width 0.254)
		(layer "F.Cu")
		(net "GND")
	)
	(segment
		(start 113.0046 -29.8704)
		(end 112.76076 -30.11424)
		(width 0.254)
		(layer "F.Cu")
		(net "GND")
	)
	(segment
		(start 100.306632 -28.135834)
		(end 100.7364 -28.565602)
		(width 0.254)
		(layer "F.Cu")
		(net "GND")
	)
	(segment
		(start 85.852 -47.342806)
		(end 86.149688 -47.640494)
		(width 0.254)
		(layer "F.Cu")
		(net "GND")
	)
	(segment
		(start 79.738728 -26.088594)
		(end 79.738728 -26.901394)
		(width 0.3048)
		(layer "F.Cu")
		(net "GND")
	)
	(segment
		(start 84.284566 -25.951434)
		(end 84.4804 -25.7556)
		(width 0.254)
		(layer "F.Cu")
		(net "GND")
	)
	(segment
		(start 91.7702 -46.921166)
		(end 91.7702 -46.863)
		(width 0.254)
		(layer "F.Cu")
		(net "GND")
	)
	(segment
		(start 106.51236 -45.628814)
		(end 106.187748 -45.304202)
		(width 0.254)
		(layer "F.Cu")
		(net "GND")
	)
	(segment
		(start 136.779 -20.6248)
		(end 136.9568 -20.6248)
		(width 0.3048)
		(layer "F.Cu")
		(net "GND")
	)
	(segment
		(start 149.5552 -40.2082)
		(end 149.5552 -36.83)
		(width 0.3048)
		(layer "F.Cu")
		(net "GND")
	)
	(segment
		(start 103.318056 -41.494202)
		(end 103.3018 -41.494202)
		(width 0.254)
		(layer "F.Cu")
		(net "GND")
	)
	(segment
		(start 110.602268 -44.485306)
		(end 110.602268 -44.485814)
		(width 0.254)
		(layer "F.Cu")
		(net "GND")
	)
	(segment
		(start 84.40928 -32.771334)
		(end 84.04098 -33.13938)
		(width 0.254)
		(layer "F.Cu")
		(net "GND")
	)
	(segment
		(start 158.623 -25.8826)
		(end 159.3342 -26.5938)
		(width 0.3048)
		(layer "F.Cu")
		(net "GND")
	)
	(segment
		(start 153.3652 -32.79394)
		(end 154.78506 -32.79394)
		(width 0.3048)
		(layer "F.Cu")
		(net "GND")
	)
	(segment
		(start 91.777566 -26.393394)
		(end 91.729814 -26.441146)
		(width 0.3048)
		(layer "F.Cu")
		(net "GND")
	)
	(segment
		(start 79.273146 -66.633852)
		(end 79.273146 -66.496946)
		(width 0.3048)
		(layer "F.Cu")
		(net "GND")
	)
	(segment
		(start 182.050182 -64.05499)
		(end 182.051198 -64.056006)
		(width 0.254)
		(layer "F.Cu")
		(net "GND")
	)
	(segment
		(start 98.712528 -28.938728)
		(end 98.712528 -29.591254)
		(width 0.3048)
		(layer "F.Cu")
		(net "GND")
	)
	(segment
		(start 192.456308 -34.1757)
		(end 192.576704 -34.296096)
		(width 0.2032)
		(layer "F.Cu")
		(net "GND")
	)
	(segment
		(start 104.14 -40.0304)
		(end 104.1654 -40.0558)
		(width 0.3048)
		(layer "F.Cu")
		(net "GND")
	)
	(segment
		(start 76.8731 -60.46724)
		(end 78.80096 -60.46724)
		(width 0.3048)
		(layer "F.Cu")
		(net "GND")
	)
	(segment
		(start 82.954368 -27.617674)
		(end 83.124548 -27.447494)
		(width 0.254)
		(layer "F.Cu")
		(net "GND")
	)
	(segment
		(start 103.480108 -36.982654)
		(end 103.480108 -36.982146)
		(width 0.3048)
		(layer "F.Cu")
		(net "GND")
	)
	(segment
		(start 50.7746 -39.1668)
		(end 49.744884 -40.196516)
		(width 0.3048)
		(layer "F.Cu")
		(net "GND")
	)
	(segment
		(start 82.88528 -41.416986)
		(end 82.87766 -41.416986)
		(width 0.254)
		(layer "F.Cu")
		(net "GND")
	)
	(segment
		(start 93.340428 -27.880818)
		(end 93.655134 -27.566112)
		(width 0.3048)
		(layer "F.Cu")
		(net "GND")
	)
	(segment
		(start 178.150012 -70.806564)
		(end 178.150012 -69.905626)
		(width 0.254)
		(layer "F.Cu")
		(net "GND")
	)
	(segment
		(start 89.421208 -46.878494)
		(end 88.8746 -47.425102)
		(width 0.254)
		(layer "F.Cu")
		(net "GND")
	)
	(segment
		(start 89.047828 -32.431228)
		(end 88.7984 -32.1818)
		(width 0.3048)
		(layer "F.Cu")
		(net "GND")
	)
	(segment
		(start 129.8448 -45.466)
		(end 129.8448 -44.704)
		(width 0.3048)
		(layer "F.Cu")
		(net "GND")
	)
	(segment
		(start 90.648028 -38.260528)
		(end 90.36304 -37.97554)
		(width 0.254)
		(layer "F.Cu")
		(net "GND")
	)
	(segment
		(start 25.367996 -6.213602)
		(end 25.349962 -6.195568)
		(width 0.7112)
		(layer "F.Cu")
		(net "GND")
	)
	(segment
		(start 100.992686 -39.199566)
		(end 100.621592 -39.57066)
		(width 0.3048)
		(layer "F.Cu")
		(net "GND")
	)
	(segment
		(start 38.349936 -6.195568)
		(end 38.36797 -6.213602)
		(width 0.7112)
		(layer "F.Cu")
		(net "GND")
	)
	(segment
		(start 131.350004 -2.543302)
		(end 131.934204 -3.127502)
		(width 0.3048)
		(layer "F.Cu")
		(net "GND")
	)
	(segment
		(start 110.414308 -47.090838)
		(end 110.605062 -47.090838)
		(width 0.254)
		(layer "F.Cu")
		(net "GND")
	)
	(segment
		(start 105.997248 -52.641246)
		(end 106.190288 -52.448206)
		(width 0.254)
		(layer "F.Cu")
		(net "GND")
	)
	(segment
		(start 165.250114 -63.388494)
		(end 165.90264 -64.04102)
		(width 0.3048)
		(layer "F.Cu")
		(net "GND")
	)
	(segment
		(start 97.9805 -32.609282)
		(end 97.9805 -32.643318)
		(width 0.254)
		(layer "F.Cu")
		(net "GND")
	)
	(segment
		(start 46.5582 -19.449796)
		(end 46.5582 -19.177)
		(width 0.3048)
		(layer "F.Cu")
		(net "GND")
	)
	(segment
		(start 90.300302 -44.3484)
		(end 90.648028 -44.000674)
		(width 0.254)
		(layer "F.Cu")
		(net "GND")
	)
	(segment
		(start 90.31224 -39.5732)
		(end 90.31224 -39.599362)
		(width 0.254)
		(layer "F.Cu")
		(net "GND")
	)
	(segment
		(start 36.37788 -23.05558)
		(end 37.90442 -23.05558)
		(width 0.2794)
		(layer "F.Cu")
		(net "GND")
	)
	(segment
		(start 101.986334 -27.6352)
		(end 102.347268 -27.996134)
		(width 0.254)
		(layer "F.Cu")
		(net "GND")
	)
	(segment
		(start 173.04512 -2.767838)
		(end 173.04512 -3.164078)
		(width 0.254)
		(layer "F.Cu")
		(net "GND")
	)
	(segment
		(start 40.15867 -24.58085)
		(end 40.15867 -25.377394)
		(width 0.2794)
		(layer "F.Cu")
		(net "GND")
	)
	(segment
		(start 68.834 -57.277)
		(end 69.469 -57.277)
		(width 0.3048)
		(layer "F.Cu")
		(net "GND")
	)
	(segment
		(start 140.1064 -52.1716)
		(end 140.1572 -52.1208)
		(width 0.3048)
		(layer "F.Cu")
		(net "GND")
	)
	(segment
		(start 90.018108 -26.733246)
		(end 90.018108 -26.413206)
		(width 0.2032)
		(layer "F.Cu")
		(net "GND")
	)
	(segment
		(start 82.989928 -26.088594)
		(end 83.0834 -25.995122)
		(width 0.254)
		(layer "F.Cu")
		(net "GND")
	)
	(segment
		(start 79.601568 -42.161206)
		(end 79.637128 -42.161206)
		(width 0.254)
		(layer "F.Cu")
		(net "GND")
	)
	(segment
		(start 110.053628 -32.888174)
		(end 110.205774 -32.736028)
		(width 0.254)
		(layer "F.Cu")
		(net "GND")
	)
	(segment
		(start 189.55004 -69.434964)
		(end 189.671198 -69.313806)
		(width 0.254)
		(layer "F.Cu")
		(net "GND")
	)
	(segment
		(start 87.07755 -41.027096)
		(end 87.06739 -41.027096)
		(width 0.254)
		(layer "F.Cu")
		(net "GND")
	)
	(segment
		(start 111.51108 -40.484806)
		(end 111.576104 -40.54983)
		(width 0.254)
		(layer "F.Cu")
		(net "GND")
	)
	(segment
		(start 97.9805 -32.643318)
		(end 97.957894 -32.665924)
		(width 0.254)
		(layer "F.Cu")
		(net "GND")
	)
	(segment
		(start 107.567984 -36.576)
		(end 107.671108 -36.679124)
		(width 0.2032)
		(layer "F.Cu")
		(net "GND")
	)
	(segment
		(start 86.558882 -33.60928)
		(end 86.558882 -34.32175)
		(width 0.254)
		(layer "F.Cu")
		(net "GND")
	)
	(segment
		(start 134.76224 -14.71676)
		(end 134.62 -14.859)
		(width 0.3048)
		(layer "F.Cu")
		(net "GND")
	)
	(segment
		(start 45.0088 -33.16605)
		(end 45.0088 -32.975296)
		(width 0.381)
		(layer "F.Cu")
		(net "GND")
	)
	(segment
		(start 90.122248 -47.640494)
		(end 90.6272 -48.145446)
		(width 0.254)
		(layer "F.Cu")
		(net "GND")
	)
	(segment
		(start 24.86533 -59.419998)
		(end 25.229312 -59.78398)
		(width 0.2032)
		(layer "F.Cu")
		(net "GND")
	)
	(segment
		(start 140.270992 -53.277008)
		(end 140.7668 -52.7812)
		(width 0.3048)
		(layer "F.Cu")
		(net "GND")
	)
	(segment
		(start 139.15009 -70.806564)
		(end 139.15009 -69.60489)
		(width 0.3048)
		(layer "F.Cu")
		(net "GND")
	)
	(segment
		(start 82.6389 -29.083)
		(end 83.038442 -29.083)
		(width 0.254)
		(layer "F.Cu")
		(net "GND")
	)
	(segment
		(start 86.528148 -52.6796)
		(end 86.3092 -52.6796)
		(width 0.254)
		(layer "F.Cu")
		(net "GND")
	)
	(segment
		(start 38.36797 -9.04748)
		(end 38.884352 -9.563862)
		(width 0.7112)
		(layer "F.Cu")
		(net "GND")
	)
	(segment
		(start 107.280202 -39.2938)
		(end 107.605068 -38.968934)
		(width 0.3048)
		(layer "F.Cu")
		(net "GND")
	)
	(segment
		(start 86.543642 -45.237908)
		(end 86.531196 -45.237908)
		(width 0.254)
		(layer "F.Cu")
		(net "GND")
	)
	(segment
		(start 95.903288 -26.002234)
		(end 95.903288 -26.895806)
		(width 0.254)
		(layer "F.Cu")
		(net "GND")
	)
	(segment
		(start 109.913928 -44.317666)
		(end 109.913928 -43.812206)
		(width 0.254)
		(layer "F.Cu")
		(net "GND")
	)
	(segment
		(start 60.065158 -45.556678)
		(end 60.259722 -45.556678)
		(width 0.3048)
		(layer "F.Cu")
		(net "GND")
	)
	(segment
		(start 85.01888 -45.97908)
		(end 85.4964 -46.4566)
		(width 0.254)
		(layer "F.Cu")
		(net "GND")
	)
	(segment
		(start 95.449898 -39.200074)
		(end 95.873824 -39.624)
		(width 0.3048)
		(layer "F.Cu")
		(net "GND")
	)
	(segment
		(start 22.368002 -9.1567)
		(end 22.368002 -6.213602)
		(width 0.7112)
		(layer "F.Cu")
		(net "GND")
	)
	(segment
		(start 166.4208 -24.13)
		(end 167.0558 -24.765)
		(width 0.508)
		(layer "F.Cu")
		(net "GND")
	)
	(segment
		(start 86.914228 -27.658314)
		(end 86.947248 -27.658314)
		(width 0.3048)
		(layer "F.Cu")
		(net "GND")
	)
	(segment
		(start 38.03777 -20.05457)
		(end 36.37788 -20.05457)
		(width 0.2794)
		(layer "F.Cu")
		(net "GND")
	)
	(segment
		(start 102.692708 -36.284154)
		(end 102.692708 -36.283646)
		(width 0.3048)
		(layer "F.Cu")
		(net "GND")
	)
	(segment
		(start 97.409 -30.3149)
		(end 97.409 -30.563566)
		(width 0.2032)
		(layer "F.Cu")
		(net "GND")
	)
	(segment
		(start 119.1514 -63.373)
		(end 119.6086 -62.9158)
		(width 0.508)
		(layer "F.Cu")
		(net "GND")
	)
	(segment
		(start 81.308448 -30.091634)
		(end 81.764632 -30.091634)
		(width 0.3048)
		(layer "F.Cu")
		(net "GND")
	)
	(segment
		(start 80.546448 -43.650154)
		(end 80.498188 -43.698414)
		(width 0.254)
		(layer "F.Cu")
		(net "GND")
	)
	(segment
		(start 122.649996 -17.090644)
		(end 126.499874 -17.090644)
		(width 0.508)
		(layer "F.Cu")
		(net "GND")
	)
	(segment
		(start 46.314106 -21.209)
		(end 46.3042 -21.209)
		(width 0.3048)
		(layer "F.Cu")
		(net "GND")
	)
	(segment
		(start 181.7878 -31.623)
		(end 181.7878 -31.5468)
		(width 0.508)
		(layer "F.Cu")
		(net "GND")
	)
	(segment
		(start 68.62445 -48.40605)
		(end 68.62445 -47.923958)
		(width 0.3048)
		(layer "F.Cu")
		(net "GND")
	)
	(segment
		(start 137.649966 -8.473694)
		(end 137.6553 -8.46836)
		(width 0.3048)
		(layer "F.Cu")
		(net "GND")
	)
	(segment
		(start 36.37788 -29.05506)
		(end 35.09264 -29.05506)
		(width 0.2794)
		(layer "F.Cu")
		(net "GND")
	)
	(segment
		(start 138.38809 -45.953934)
		(end 138.49858 -45.843444)
		(width 0.3048)
		(layer "F.Cu")
		(net "GND")
	)
	(segment
		(start 104.623108 -38.968934)
		(end 104.623616 -38.968934)
		(width 0.3048)
		(layer "F.Cu")
		(net "GND")
	)
	(segment
		(start 103.3018 -41.494202)
		(end 103.124 -41.316402)
		(width 0.254)
		(layer "F.Cu")
		(net "GND")
	)
	(segment
		(start 109.913928 -43.812206)
		(end 109.908848 -43.807126)
		(width 0.254)
		(layer "F.Cu")
		(net "GND")
	)
	(segment
		(start 46.34992 -6.195568)
		(end 46.34992 -9.06272)
		(width 0.7112)
		(layer "F.Cu")
		(net "GND")
	)
	(segment
		(start 145.450052 -9.897364)
		(end 145.450052 -8.958326)
		(width 0.254)
		(layer "F.Cu")
		(net "GND")
	)
	(segment
		(start 95.9612 -31.483046)
		(end 95.618808 -31.140654)
		(width 0.3048)
		(layer "F.Cu")
		(net "GND")
	)
	(segment
		(start 103.751888 -26.957274)
		(end 103.751888 -28.110434)
		(width 0.254)
		(layer "F.Cu")
		(net "GND")
	)
	(segment
		(start 93.632528 -31.521146)
		(end 93.6117 -31.521146)
		(width 0.3048)
		(layer "F.Cu")
		(net "GND")
	)
	(segment
		(start 35.09264 -29.05506)
		(end 34.73958 -28.702)
		(width 0.2794)
		(layer "F.Cu")
		(net "GND")
	)
	(segment
		(start 85.8647 -49.8475)
		(end 85.864192 -49.8475)
		(width 0.254)
		(layer "F.Cu")
		(net "GND")
	)
	(segment
		(start 112.27816 -30.11424)
		(end 112.098328 -30.294072)
		(width 0.254)
		(layer "F.Cu")
		(net "GND")
	)
	(segment
		(start 61.34989 -6.195568)
		(end 61.34989 -9.077198)
		(width 0.7112)
		(layer "F.Cu")
		(net "GND")
	)
	(segment
		(start 98.54438 -27.996134)
		(end 98.186494 -27.638248)
		(width 0.254)
		(layer "F.Cu")
		(net "GND")
	)
	(segment
		(start 106.181906 -33.355788)
		(end 106.109262 -33.355788)
		(width 0.254)
		(layer "F.Cu")
		(net "GND")
	)
	(segment
		(start 110.053628 -42.466006)
		(end 110.053628 -41.895014)
		(width 0.254)
		(layer "F.Cu")
		(net "GND")
	)
	(segment
		(start 95.7072 -45.300646)
		(end 95.380048 -44.973494)
		(width 0.3048)
		(layer "F.Cu")
		(net "GND")
	)
	(segment
		(start 90.648028 -44.000674)
		(end 90.648028 -43.200574)
		(width 0.254)
		(layer "F.Cu")
		(net "GND")
	)
	(segment
		(start 63.6016 -41.8084)
		(end 63.6016 -42.554144)
		(width 0.3048)
		(layer "F.Cu")
		(net "GND")
	)
	(segment
		(start 75.462638 -41.5798)
		(end 75.5015 -41.5798)
		(width 0.3048)
		(layer "F.Cu")
		(net "GND")
	)
	(segment
		(start 165.862 -23.622)
		(end 166.37 -24.13)
		(width 0.508)
		(layer "F.Cu")
		(net "GND")
	)
	(segment
		(start 79.738728 -28.526994)
		(end 79.530194 -28.526994)
		(width 0.3048)
		(layer "F.Cu")
		(net "GND")
	)
	(segment
		(start 109.461808 -26.896314)
		(end 109.527848 -26.896314)
		(width 0.254)
		(layer "F.Cu")
		(net "GND")
	)
	(segment
		(start 135.550148 -69.975222)
		(end 135.86587 -69.6595)
		(width 0.254)
		(layer "F.Cu")
		(net "GND")
	)
	(segment
		(start 154.78506 -32.79394)
		(end 155.702 -31.877)
		(width 0.3048)
		(layer "F.Cu")
		(net "GND")
	)
	(segment
		(start 96.081088 -44.990512)
		(end 95.7072 -45.3644)
		(width 0.3048)
		(layer "F.Cu")
		(net "GND")
	)
	(segment
		(start 109.913928 -38.991032)
		(end 109.63148 -39.27348)
		(width 0.3048)
		(layer "F.Cu")
		(net "GND")
	)
	(segment
		(start 87.673688 -30.378654)
		(end 88.0364 -30.741366)
		(width 0.3048)
		(layer "F.Cu")
		(net "GND")
	)
	(segment
		(start 79.26832 -47.76978)
		(end 79.601568 -48.102774)
		(width 0.254)
		(layer "F.Cu")
		(net "GND")
	)
	(segment
		(start 138.549888 -1.68402)
		(end 138.549888 -2.509266)
		(width 0.254)
		(layer "F.Cu")
		(net "GND")
	)
	(segment
		(start 90.361008 -32.279336)
		(end 90.000582 -31.91891)
		(width 0.3048)
		(layer "F.Cu")
		(net "GND")
	)
	(segment
		(start 44.8056 -44.6278)
		(end 44.8818 -44.704)
		(width 0.508)
		(layer "F.Cu")
		(net "GND")
	)
	(segment
		(start 144.250156 -62.59322)
		(end 144.250156 -63.4492)
		(width 0.254)
		(layer "F.Cu")
		(net "GND")
	)
	(segment
		(start 101.051868 -39.199566)
		(end 100.992686 -39.199566)
		(width 0.3048)
		(layer "F.Cu")
		(net "GND")
	)
	(segment
		(start 86.230968 -50.213768)
		(end 85.8647 -49.8475)
		(width 0.254)
		(layer "F.Cu")
		(net "GND")
	)
	(segment
		(start 167.0558 -33.782)
		(end 167.0558 -31.877)
		(width 0.508)
		(layer "F.Cu")
		(net "GND")
	)
	(segment
		(start 108.052108 -33.711134)
		(end 108.10113 -33.711134)
		(width 0.3048)
		(layer "F.Cu")
		(net "GND")
	)
	(segment
		(start 146.649948 -62.59322)
		(end 146.649948 -63.693548)
		(width 0.254)
		(layer "F.Cu")
		(net "GND")
	)
	(segment
		(start 81.841086 -39.606474)
		(end 81.785968 -39.606474)
		(width 0.254)
		(layer "F.Cu")
		(net "GND")
	)
	(segment
		(start 156.464 -26.8478)
		(end 155.702 -26.8478)
		(width 0.3048)
		(layer "F.Cu")
		(net "GND")
	)
	(segment
		(start 97.851468 -40.800274)
		(end 98.238564 -41.18737)
		(width 0.3048)
		(layer "F.Cu")
		(net "GND")
	)
	(segment
		(start 175.641 -57.5818)
		(end 176.403 -57.5818)
		(width 0.3048)
		(layer "F.Cu")
		(net "GND")
	)
	(segment
		(start 81.289398 -45.853096)
		(end 81.265268 -45.853096)
		(width 0.254)
		(layer "F.Cu")
		(net "GND")
	)
	(segment
		(start 49.744884 -43.103292)
		(end 49.7078 -43.140376)
		(width 0.3048)
		(layer "F.Cu")
		(net "GND")
	)
	(segment
		(start 54.349904 -8.951976)
		(end 54.88559 -9.487662)
		(width 0.7112)
		(layer "F.Cu")
		(net "GND")
	)
	(segment
		(start 177.25009 -62.59322)
		(end 177.25009 -63.56731)
		(width 0.254)
		(layer "F.Cu")
		(net "GND")
	)
	(segment
		(start 81.768188 -35.811714)
		(end 81.768188 -35.811206)
		(width 0.254)
		(layer "F.Cu")
		(net "GND")
	)
	(segment
		(start 106.51236 -43.307)
		(end 106.147108 -42.941748)
		(width 0.254)
		(layer "F.Cu")
		(net "GND")
	)
	(segment
		(start 112.53724 -68.82384)
		(end 113.040922 -69.327522)
		(width 0.3048)
		(layer "F.Cu")
		(net "GND")
	)
	(segment
		(start 80.208628 -46.314614)
		(end 79.861156 -46.662086)
		(width 0.254)
		(layer "F.Cu")
		(net "GND")
	)
	(segment
		(start 81.646268 -37.206174)
		(end 81.343754 -37.508688)
		(width 0.254)
		(layer "F.Cu")
		(net "GND")
	)
	(segment
		(start 95.692468 -46.107096)
		(end 95.692468 -46.185074)
		(width 0.3048)
		(layer "F.Cu")
		(net "GND")
	)
	(segment
		(start 136.45007 -62.59322)
		(end 136.45007 -63.649098)
		(width 0.254)
		(layer "F.Cu")
		(net "GND")
	)
	(segment
		(start 49.7078 -43.140376)
		(end 49.7078 -43.4848)
		(width 0.3048)
		(layer "F.Cu")
		(net "GND")
	)
	(segment
		(start 85.171788 -41.417494)
		(end 85.171788 -41.47693)
		(width 0.254)
		(layer "F.Cu")
		(net "GND")
	)
	(segment
		(start 94.333568 -29.235146)
		(end 93.979746 -28.881324)
		(width 0.3048)
		(layer "F.Cu")
		(net "GND")
	)
	(segment
		(start 88.600788 -38.729666)
		(end 88.519 -38.647878)
		(width 0.254)
		(layer "F.Cu")
		(net "GND")
	)
	(segment
		(start 87.252048 -50.264314)
		(end 87.252048 -50.263806)
		(width 0.254)
		(layer "F.Cu")
		(net "GND")
	)
	(segment
		(start 95.350076 -6.195568)
		(end 95.350076 -9.245346)
		(width 0.7112)
		(layer "F.Cu")
		(net "GND")
	)
	(segment
		(start 103.099108 -43.642534)
		(end 103.099616 -43.642026)
		(width 0.254)
		(layer "F.Cu")
		(net "GND")
	)
	(segment
		(start 86.436708 -28.135834)
		(end 86.914228 -27.658314)
		(width 0.3048)
		(layer "F.Cu")
		(net "GND")
	)
	(segment
		(start 89.352628 -50.404014)
		(end 89.337642 -50.404014)
		(width 0.254)
		(layer "F.Cu")
		(net "GND")
	)
	(segment
		(start 82.349848 -6.195568)
		(end 82.349848 -9.148064)
		(width 0.7112)
		(layer "F.Cu")
		(net "GND")
	)
	(segment
		(start 82.931 -47.7266)
		(end 82.9564 -47.7012)
		(width 0.254)
		(layer "F.Cu")
		(net "GND")
	)
	(segment
		(start 103.861108 -39.669974)
		(end 103.861616 -39.669974)
		(width 0.3048)
		(layer "F.Cu")
		(net "GND")
	)
	(segment
		(start 88.135968 -45.02658)
		(end 87.772748 -45.3898)
		(width 0.254)
		(layer "F.Cu")
		(net "GND")
	)
	(segment
		(start 142.1384 -2.85877)
		(end 141.845792 -3.151378)
		(width 0.3048)
		(layer "F.Cu")
		(net "GND")
	)
	(segment
		(start 110.335568 -25.526746)
		(end 110.241334 -25.432512)
		(width 0.3048)
		(layer "F.Cu")
		(net "GND")
	)
	(segment
		(start 79.09814 -29.99994)
		(end 79.189834 -30.091634)
		(width 0.3048)
		(layer "F.Cu")
		(net "GND")
	)
	(segment
		(start 104.9528 -39.317676)
		(end 104.981756 -39.346632)
		(width 0.3048)
		(layer "F.Cu")
		(net "GND")
	)
	(segment
		(start 91.646248 -33.382458)
		(end 91.976194 -33.052512)
		(width 0.3048)
		(layer "F.Cu")
		(net "GND")
	)
	(segment
		(start 94.333568 -31.521654)
		(end 94.333568 -31.48457)
		(width 0.3048)
		(layer "F.Cu")
		(net "GND")
	)
	(segment
		(start 93.076268 -42.40022)
		(end 93.076268 -42.403268)
		(width 0.254)
		(layer "F.Cu")
		(net "GND")
	)
	(segment
		(start 82.215228 -36.036504)
		(end 82.215228 -35.748214)
		(width 0.254)
		(layer "F.Cu")
		(net "GND")
	)
	(segment
		(start 107.643168 -27.300174)
		(end 107.643168 -27.901646)
		(width 0.254)
		(layer "F.Cu")
		(net "GND")
	)
	(segment
		(start 46.5836 -20.939506)
		(end 46.314106 -21.209)
		(width 0.3048)
		(layer "F.Cu")
		(net "GND")
	)
	(segment
		(start 164.349938 -70.806564)
		(end 164.349938 -69.934836)
		(width 0.3048)
		(layer "F.Cu")
		(net "GND")
	)
	(segment
		(start 127.508 -21.263102)
		(end 127.199898 -20.955)
		(width 0.508)
		(layer "F.Cu")
		(net "GND")
	)
	(segment
		(start 35.203384 -24.55672)
		(end 34.671 -25.089104)
		(width 0.2794)
		(layer "F.Cu")
		(net "GND")
	)
	(segment
		(start 75.1586 -39.1668)
		(end 74.4982 -39.1668)
		(width 0.3048)
		(layer "F.Cu")
		(net "GND")
	)
	(segment
		(start 184.28462 -3.088386)
		(end 184.28462 -3.176778)
		(width 0.254)
		(layer "F.Cu")
		(net "GND")
	)
	(segment
		(start 137.414 -25.36444)
		(end 138.15314 -25.36444)
		(width 0.3048)
		(layer "F.Cu")
		(net "GND")
	)
	(segment
		(start 41.148 -34.8107)
		(end 41.402 -34.5567)
		(width 0.2794)
		(layer "F.Cu")
		(net "GND")
	)
	(segment
		(start 90.361262 -29.235908)
		(end 90.830908 -29.235908)
		(width 0.3048)
		(layer "F.Cu")
		(net "GND")
	)
	(segment
		(start 17.9324 -52.907946)
		(end 18.322798 -53.298344)
		(width 0.3048)
		(layer "F.Cu")
		(net "GND")
	)
	(segment
		(start 85.39226 -36.06038)
		(end 85.18906 -35.85718)
		(width 0.254)
		(layer "F.Cu")
		(net "GND")
	)
	(segment
		(start 37.90442 -23.05558)
		(end 38.813994 -22.146006)
		(width 0.2794)
		(layer "F.Cu")
		(net "GND")
	)
	(segment
		(start 98.90252 -33.444434)
		(end 98.649028 -33.697926)
		(width 0.254)
		(layer "F.Cu")
		(net "GND")
	)
	(segment
		(start 80.57515 -40.312594)
		(end 79.869792 -40.312594)
		(width 0.2032)
		(layer "F.Cu")
		(net "GND")
	)
	(segment
		(start 54.356 -44.7548)
		(end 54.356 -45.6438)
		(width 0.508)
		(layer "F.Cu")
		(net "GND")
	)
	(segment
		(start 33.5534 -40.259)
		(end 33.6804 -40.259)
		(width 0.508)
		(layer "F.Cu")
		(net "GND")
	)
	(segment
		(start 82.954368 -28.135834)
		(end 82.954368 -28.196032)
		(width 0.254)
		(layer "F.Cu")
		(net "GND")
	)
	(segment
		(start 89.337642 -50.404014)
		(end 89.003886 -50.73777)
		(width 0.254)
		(layer "F.Cu")
		(net "GND")
	)
	(segment
		(start 136.449816 -8.435594)
		(end 136.4488 -8.434578)
		(width 0.3048)
		(layer "F.Cu")
		(net "GND")
	)
	(segment
		(start 81.097628 -33.914334)
		(end 81.016348 -33.833054)
		(width 0.254)
		(layer "F.Cu")
		(net "GND")
	)
	(segment
		(start 93.632528 -31.521654)
		(end 93.632528 -31.521146)
		(width 0.3048)
		(layer "F.Cu")
		(net "GND")
	)
	(segment
		(start 93.848428 -40.800274)
		(end 93.4974 -41.151302)
		(width 0.3048)
		(layer "F.Cu")
		(net "GND")
	)
	(segment
		(start 83.742022 -34.415222)
		(end 83.742022 -34.144712)
		(width 0.254)
		(layer "F.Cu")
		(net "GND")
	)
	(segment
		(start 88.600788 -38.730174)
		(end 88.600788 -38.729666)
		(width 0.254)
		(layer "F.Cu")
		(net "GND")
	)
	(segment
		(start 198.5518 -7.2898)
		(end 198.5518 -7.112)
		(width 0.3048)
		(layer "F.Cu")
		(net "GND")
	)
	(segment
		(start 81.971134 -40.112188)
		(end 81.768188 -40.315134)
		(width 0.254)
		(layer "F.Cu")
		(net "GND")
	)
	(segment
		(start 89.007188 -40.015414)
		(end 89.835228 -40.015414)
		(width 0.254)
		(layer "F.Cu")
		(net "GND")
	)
	(segment
		(start 69.349874 -6.195568)
		(end 69.367908 -6.213602)
		(width 0.7112)
		(layer "F.Cu")
		(net "GND")
	)
	(segment
		(start 94.734888 -28.125674)
		(end 94.171008 -28.125674)
		(width 0.3048)
		(layer "F.Cu")
		(net "GND")
	)
	(segment
		(start 86.692486 -34.455354)
		(end 86.61654 -34.455354)
		(width 0.254)
		(layer "F.Cu")
		(net "GND")
	)
	(segment
		(start 167.0558 -24.765)
		(end 167.0558 -26.67)
		(width 0.508)
		(layer "F.Cu")
		(net "GND")
	)
	(segment
		(start 136.45007 -63.649098)
		(end 135.938768 -64.1604)
		(width 0.254)
		(layer "F.Cu")
		(net "GND")
	)
	(segment
		(start 84.3534 -46.999906)
		(end 84.3534 -47.1424)
		(width 0.254)
		(layer "F.Cu")
		(net "GND")
	)
	(segment
		(start 112.098328 -40.741854)
		(end 112.098328 -40.741346)
		(width 0.254)
		(layer "F.Cu")
		(net "GND")
	)
	(segment
		(start 54.356 -45.6438)
		(end 54.3179 -45.6819)
		(width 0.508)
		(layer "F.Cu")
		(net "GND")
	)
	(segment
		(start 36.37788 -24.55545)
		(end 35.845496 -24.55545)
		(width 0.2794)
		(layer "F.Cu")
		(net "GND")
	)
	(segment
		(start 182.65013 -62.59322)
		(end 182.65013 -63.47333)
		(width 0.254)
		(layer "F.Cu")
		(net "GND")
	)
	(segment
		(start 90.018108 -26.413206)
		(end 90.013028 -26.408126)
		(width 0.2032)
		(layer "F.Cu")
		(net "GND")
	)
	(segment
		(start 119.6086 -62.9158)
		(end 119.6086 -62.357)
		(width 0.508)
		(layer "F.Cu")
		(net "GND")
	)
	(segment
		(start 128.649984 -8.333994)
		(end 128.651 -8.332978)
		(width 0.3048)
		(layer "F.Cu")
		(net "GND")
	)
	(segment
		(start 98.3107 -39.5732)
		(end 98.3107 -39.537894)
		(width 0.3048)
		(layer "F.Cu")
		(net "GND")
	)
	(segment
		(start 69.1642 -30.734)
		(end 69.1642 -30.3022)
		(width 0.3048)
		(layer "F.Cu")
		(net "GND")
	)
	(segment
		(start 81.9912 -34.899854)
		(end 81.9912 -34.577528)
		(width 0.254)
		(layer "F.Cu")
		(net "GND")
	)
	(segment
		(start 174.816008 -2.98069)
		(end 174.816008 -2.994406)
		(width 0.254)
		(layer "F.Cu")
		(net "GND")
	)
	(segment
		(start 83.429348 -50.304954)
		(end 83.429348 -50.63871)
		(width 0.254)
		(layer "F.Cu")
		(net "GND")
	)
	(segment
		(start 94.094808 -46.878494)
		(end 94.09176 -46.878494)
		(width 0.254)
		(layer "F.Cu")
		(net "GND")
	)
	(segment
		(start 103.480108 -40.955214)
		(end 103.550212 -40.955214)
		(width 0.254)
		(layer "F.Cu")
		(net "GND")
	)
	(segment
		(start 18.36801 -6.213602)
		(end 18.36801 -9.133078)
		(width 0.7112)
		(layer "F.Cu")
		(net "GND")
	)
	(segment
		(start 106.398568 -25.951434)
		(end 106.398568 -25.778968)
		(width 0.254)
		(layer "F.Cu")
		(net "GND")
	)
	(segment
		(start 141.849602 -9.000744)
		(end 142.40129 -8.449056)
		(width 0.254)
		(layer "F.Cu")
		(net "GND")
	)
	(segment
		(start 85.730588 -28.120594)
		(end 85.159088 -28.120594)
		(width 0.254)
		(layer "F.Cu")
		(net "GND")
	)
	(segment
		(start 81.364328 -26.088594)
		(end 82.177128 -26.088594)
		(width 0.254)
		(layer "F.Cu")
		(net "GND")
	)
	(segment
		(start 157.45587 -26.8478)
		(end 156.464 -26.8478)
		(width 0.3048)
		(layer "F.Cu")
		(net "GND")
	)
	(segment
		(start 88.161368 -27.913076)
		(end 88.411304 -27.66314)
		(width 0.3048)
		(layer "F.Cu")
		(net "GND")
	)
	(segment
		(start 145.150078 -70.806564)
		(end 145.150078 -70.023482)
		(width 0.254)
		(layer "F.Cu")
		(net "GND")
	)
	(segment
		(start 109.296708 -28.472892)
		(end 109.96803 -28.472892)
		(width 0.254)
		(layer "F.Cu")
		(net "GND")
	)
	(segment
		(start 97.048828 -36.799266)
		(end 96.677734 -36.428172)
		(width 0.3048)
		(layer "F.Cu")
		(net "GND")
	)
	(segment
		(start 168.021 -39.8272)
		(end 168.021 -40.61206)
		(width 0.508)
		(layer "F.Cu")
		(net "GND")
	)
	(segment
		(start 92.709746 -28.854654)
		(end 92.347288 -28.854654)
		(width 0.3048)
		(layer "F.Cu")
		(net "GND")
	)
	(segment
		(start 87.252048 -50.263806)
		(end 86.8807 -49.892458)
		(width 0.254)
		(layer "F.Cu")
		(net "GND")
	)
	(segment
		(start 98.067368 -46.116494)
		(end 98.067368 -46.158912)
		(width 0.3048)
		(layer "F.Cu")
		(net "GND")
	)
	(segment
		(start 82.052414 -48.613314)
		(end 81.785968 -48.613314)
		(width 0.254)
		(layer "F.Cu")
		(net "GND")
	)
	(segment
		(start 80.8863 -35.801046)
		(end 81.090008 -35.801046)
		(width 0.254)
		(layer "F.Cu")
		(net "GND")
	)
	(segment
		(start 54.349904 -6.195568)
		(end 54.349904 -8.951976)
		(width 0.7112)
		(layer "F.Cu")
		(net "GND")
	)
	(segment
		(start 89.84996 -42.400474)
		(end 89.71788 -42.532554)
		(width 0.3048)
		(layer "F.Cu")
		(net "GND")
	)
	(segment
		(start 96.393 -42.542206)
		(end 96.251268 -42.400474)
		(width 0.254)
		(layer "F.Cu")
		(net "GND")
	)
	(segment
		(start 111.961168 -27.714194)
		(end 112.981994 -27.714194)
		(width 0.3048)
		(layer "F.Cu")
		(net "GND")
	)
	(segment
		(start 84.028788 -31.486094)
		(end 84.074 -31.531306)
		(width 0.3048)
		(layer "F.Cu")
		(net "GND")
	)
	(segment
		(start 47.649638 -33.959038)
		(end 47.217838 -33.959038)
		(width 0.3048)
		(layer "F.Cu")
		(net "GND")
	)
	(segment
		(start 133.149848 -2.58826)
		(end 133.604 -3.042412)
		(width 0.3048)
		(layer "F.Cu")
		(net "GND")
	)
	(segment
		(start 108.364274 -40.65524)
		(end 108.0643 -40.955214)
		(width 0.254)
		(layer "F.Cu")
		(net "GND")
	)
	(segment
		(start 93.632528 -33.045146)
		(end 93.632528 -33.045654)
		(width 0.3048)
		(layer "F.Cu")
		(net "GND")
	)
	(segment
		(start 81.554828 -31.910274)
		(end 80.950308 -31.910274)
		(width 0.254)
		(layer "F.Cu")
		(net "GND")
	)
	(segment
		(start 29.367988 -6.213602)
		(end 29.367988 -9.054592)
		(width 0.7112)
		(layer "F.Cu")
		(net "GND")
	)
	(segment
		(start 175.150018 -1.68402)
		(end 175.150018 -2.64668)
		(width 0.254)
		(layer "F.Cu")
		(net "GND")
	)
	(segment
		(start 83.772248 -50.782474)
		(end 83.573112 -50.782474)
		(width 0.254)
		(layer "F.Cu")
		(net "GND")
	)
	(segment
		(start 107.815888 -52.448714)
		(end 107.815888 -52.968652)
		(width 0.254)
		(layer "F.Cu")
		(net "GND")
	)
	(segment
		(start 109.893862 -34.800286)
		(end 109.865668 -34.772092)
		(width 0.254)
		(layer "F.Cu")
		(net "GND")
	)
	(segment
		(start 87.45728 -41.416986)
		(end 87.422228 -41.416986)
		(width 0.254)
		(layer "F.Cu")
		(net "GND")
	)
	(segment
		(start 107.617768 -27.274266)
		(end 107.643168 -27.299666)
		(width 0.3048)
		(layer "F.Cu")
		(net "GND")
	)
	(segment
		(start 58.349896 -6.195568)
		(end 58.349896 -9.05129)
		(width 0.7112)
		(layer "F.Cu")
		(net "GND")
	)
	(segment
		(start 103.163878 -43.642026)
		(end 103.518208 -43.287696)
		(width 0.254)
		(layer "F.Cu")
		(net "GND")
	)
	(segment
		(start 171.85005 -9.897364)
		(end 171.85005 -8.603488)
		(width 0.254)
		(layer "F.Cu")
		(net "GND")
	)
	(segment
		(start 87.838788 -42.702734)
		(end 87.838788 -41.798494)
		(width 0.254)
		(layer "F.Cu")
		(net "GND")
	)
	(segment
		(start 79.458566 -46.519084)
		(end 79.458566 -46.21276)
		(width 0.254)
		(layer "F.Cu")
		(net "GND")
	)
	(segment
		(start 95.448628 -36.798504)
		(end 95.0468 -36.396676)
		(width 0.3048)
		(layer "F.Cu")
		(net "GND")
	)
	(segment
		(start 82.885788 -40.715946)
		(end 82.538062 -41.063672)
		(width 0.254)
		(layer "F.Cu")
		(net "GND")
	)
	(segment
		(start 22.368002 -6.213602)
		(end 22.349968 -6.195568)
		(width 0.7112)
		(layer "F.Cu")
		(net "GND")
	)
	(segment
		(start 139.015724 -8.563102)
		(end 139.015724 -8.416036)
		(width 0.254)
		(layer "F.Cu")
		(net "GND")
	)
	(segment
		(start 82.93227 -49.814226)
		(end 82.59064 -49.472596)
		(width 0.254)
		(layer "F.Cu")
		(net "GND")
	)
	(segment
		(start 141.249908 -9.158986)
		(end 140.5255 -8.434578)
		(width 0.254)
		(layer "F.Cu")
		(net "GND")
	)
	(segment
		(start 61.16701 -40.996108)
		(end 61.16701 -40.11549)
		(width 0.3048)
		(layer "F.Cu")
		(net "GND")
	)
	(segment
		(start 84.163408 -48.021494)
		(end 84.509102 -47.6758)
		(width 0.254)
		(layer "F.Cu")
		(net "GND")
	)
	(segment
		(start 88.135968 -45.735494)
		(end 88.13546 -45.734986)
		(width 0.254)
		(layer "F.Cu")
		(net "GND")
	)
	(segment
		(start 91.646248 -30.378654)
		(end 91.64574 -30.378146)
		(width 0.3048)
		(layer "F.Cu")
		(net "GND")
	)
	(segment
		(start 99.736148 -26.446734)
		(end 99.736148 -26.06675)
		(width 0.3048)
		(layer "F.Cu")
		(net "GND")
	)
	(segment
		(start 102.913434 -41.526968)
		(end 103.124 -41.316402)
		(width 0.254)
		(layer "F.Cu")
		(net "GND")
	)
	(segment
		(start 61.34989 -9.077198)
		(end 60.858146 -9.568942)
		(width 0.7112)
		(layer "F.Cu")
		(net "GND")
	)
	(segment
		(start 102.26675 -36.799774)
		(end 102.395528 -36.670996)
		(width 0.4064)
		(layer "F.Cu")
		(net "GND")
	)
	(segment
		(start 85.349842 -9.061958)
		(end 84.7598 -9.652)
		(width 0.7112)
		(layer "F.Cu")
		(net "GND")
	)
	(segment
		(start 96.647 -42.799)
		(end 96.393 -42.545)
		(width 0.254)
		(layer "F.Cu")
		(net "GND")
	)
	(segment
		(start 60.615068 -45.201586)
		(end 60.651644 -45.176948)
		(width 0.3048)
		(layer "F.Cu")
		(net "GND")
	)
	(segment
		(start 81.785968 -47.592234)
		(end 82.052922 -47.592234)
		(width 0.254)
		(layer "F.Cu")
		(net "GND")
	)
	(segment
		(start 176.650142 -62.59322)
		(end 176.650396 -62.593474)
		(width 0.254)
		(layer "F.Cu")
		(net "GND")
	)
	(segment
		(start 85.0392 -52.710842)
		(end 85.0392 -53.071268)
		(width 0.254)
		(layer "F.Cu")
		(net "GND")
	)
	(segment
		(start 104.6734 -34.946082)
		(end 104.623108 -34.996374)
		(width 0.3048)
		(layer "F.Cu")
		(net "GND")
	)
	(segment
		(start 103.048308 -27.996134)
		(end 102.347268 -27.996134)
		(width 0.254)
		(layer "F.Cu")
		(net "GND")
	)
	(segment
		(start 86.314788 -39.430706)
		(end 86.247732 -39.430706)
		(width 0.254)
		(layer "F.Cu")
		(net "GND")
	)
	(segment
		(start 141.4272 -47.238412)
		(end 141.8082 -46.857412)
		(width 0.508)
		(layer "F.Cu")
		(net "GND")
	)
	(segment
		(start 60.198 -32.6644)
		(end 58.8264 -32.6644)
		(width 0.3048)
		(layer "F.Cu")
		(net "GND")
	)
	(segment
		(start 82.290412 -40.112188)
		(end 81.971134 -40.112188)
		(width 0.254)
		(layer "F.Cu")
		(net "GND")
	)
	(segment
		(start 109.913928 -43.294554)
		(end 109.913928 -43.251374)
		(width 0.254)
		(layer "F.Cu")
		(net "GND")
	)
	(segment
		(start 81.305146 -45.853096)
		(end 81.289398 -45.853096)
		(width 0.254)
		(layer "F.Cu")
		(net "GND")
	)
	(segment
		(start 87.673688 -31.902654)
		(end 87.267034 -31.496)
		(width 0.3048)
		(layer "F.Cu")
		(net "GND")
	)
	(segment
		(start 87.45728 -36.744402)
		(end 87.45728 -36.76396)
		(width 0.254)
		(layer "F.Cu")
		(net "GND")
	)
	(segment
		(start 42.10177 -23.05558)
		(end 40.64889 -23.05558)
		(width 0.2794)
		(layer "F.Cu")
		(net "GND")
	)
	(segment
		(start 79.869792 -40.312594)
		(end 79.64678 -40.535606)
		(width 0.2032)
		(layer "F.Cu")
		(net "GND")
	)
	(segment
		(start 101.132386 -33.698434)
		(end 101.460808 -34.026856)
		(width 0.254)
		(layer "F.Cu")
		(net "GND")
	)
	(segment
		(start 133.75005 -69.94652)
		(end 134.19582 -69.50075)
		(width 0.254)
		(layer "F.Cu")
		(net "GND")
	)
	(segment
		(start 109.931708 -42.588434)
		(end 109.931708 -42.587926)
		(width 0.254)
		(layer "F.Cu")
		(net "GND")
	)
	(segment
		(start 82.504788 -47.519336)
		(end 82.242406 -47.781718)
		(width 0.254)
		(layer "F.Cu")
		(net "GND")
	)
	(segment
		(start 129.159 -43.688)
		(end 129.4892 -44.0182)
		(width 0.3048)
		(layer "F.Cu")
		(net "GND")
	)
	(segment
		(start 93.393768 -47.576486)
		(end 93.67774 -47.292514)
		(width 0.254)
		(layer "F.Cu")
		(net "GND")
	)
	(segment
		(start 95.448628 -37.599874)
		(end 95.448628 -36.799774)
		(width 0.3048)
		(layer "F.Cu")
		(net "GND")
	)
	(segment
		(start 89.804748 -52.448714)
		(end 89.804748 -52.891944)
		(width 0.254)
		(layer "F.Cu")
		(net "GND")
	)
	(segment
		(start 97.048828 -42.400474)
		(end 97.050606 -42.400474)
		(width 0.254)
		(layer "F.Cu")
		(net "GND")
	)
	(segment
		(start 37.9984 -28.20162)
		(end 38.27018 -28.4734)
		(width 0.2794)
		(layer "F.Cu")
		(net "GND")
	)
	(segment
		(start 85.171788 -36.743894)
		(end 85.171788 -36.280852)
		(width 0.254)
		(layer "F.Cu")
		(net "GND")
	)
	(segment
		(start 87.457788 -36.743894)
		(end 87.45728 -36.744402)
		(width 0.254)
		(layer "F.Cu")
		(net "GND")
	)
	(segment
		(start 79.225394 -29.339794)
		(end 79.0448 -29.1592)
		(width 0.3048)
		(layer "F.Cu")
		(net "GND")
	)
	(segment
		(start 182.65013 -63.47333)
		(end 183.22925 -64.05245)
		(width 0.254)
		(layer "F.Cu")
		(net "GND")
	)
	(segment
		(start 114.808 -70.6882)
		(end 115.3922 -70.6882)
		(width 0.3048)
		(layer "F.Cu")
		(net "GND")
	)
	(segment
		(start 87.958168 -50.279554)
		(end 87.958168 -50.655728)
		(width 0.254)
		(layer "F.Cu")
		(net "GND")
	)
	(segment
		(start 45.466 -32.385)
		(end 45.466 -30.6832)
		(width 0.3048)
		(layer "F.Cu")
		(net "GND")
	)
	(segment
		(start 93.248734 -32.671512)
		(end 93.622368 -33.045146)
		(width 0.3048)
		(layer "F.Cu")
		(net "GND")
	)
	(segment
		(start 171.250102 -62.59322)
		(end 171.250102 -63.446914)
		(width 0.254)
		(layer "F.Cu")
		(net "GND")
	)
	(segment
		(start 98.067368 -46.158912)
		(end 97.7011 -46.52518)
		(width 0.3048)
		(layer "F.Cu")
		(net "GND")
	)
	(segment
		(start 111.12246 -37.149278)
		(end 111.099092 -37.149278)
		(width 0.254)
		(layer "F.Cu")
		(net "GND")
	)
	(segment
		(start 111.488728 -37.516054)
		(end 111.488728 -37.515546)
		(width 0.254)
		(layer "F.Cu")
		(net "GND")
	)
	(segment
		(start 103.479346 -36.210494)
		(end 103.479346 -36.077652)
		(width 0.3048)
		(layer "F.Cu")
		(net "GND")
	)
	(segment
		(start 83.627468 -26.952194)
		(end 83.619848 -26.952194)
		(width 0.3048)
		(layer "F.Cu")
		(net "GND")
	)
	(segment
		(start 94.651068 -34.399474)
		(end 94.64929 -34.399474)
		(width 0.3048)
		(layer "F.Cu")
		(net "GND")
	)
	(segment
		(start 186.4614 -16.5354)
		(end 186.260486 -16.736314)
		(width 0.3048)
		(layer "F.Cu")
		(net "GND")
	)
	(segment
		(start 137.050018 -62.59322)
		(end 137.050018 -63.745618)
		(width 0.254)
		(layer "F.Cu")
		(net "GND")
	)
	(segment
		(start 140.1572 -51.3588)
		(end 140.1572 -52.1208)
		(width 0.3048)
		(layer "F.Cu")
		(net "GND")
	)
	(segment
		(start 34.417 -39.5732)
		(end 33.7058 -40.2844)
		(width 0.508)
		(layer "F.Cu")
		(net "GND")
	)
	(segment
		(start 86.314788 -38.729666)
		(end 86.269576 -38.729666)
		(width 0.254)
		(layer "F.Cu")
		(net "GND")
	)
	(segment
		(start 169.450004 -63.333884)
		(end 170.16222 -64.0461)
		(width 0.254)
		(layer "F.Cu")
		(net "GND")
	)
	(segment
		(start 142.450058 -62.59322)
		(end 142.450058 -64.066674)
		(width 0.254)
		(layer "F.Cu")
		(net "GND")
	)
	(segment
		(start 85.171788 -41.47693)
		(end 85.0773 -41.571418)
		(width 0.254)
		(layer "F.Cu")
		(net "GND")
	)
	(segment
		(start 88.0364 -30.741366)
		(end 88.0364 -30.7594)
		(width 0.3048)
		(layer "F.Cu")
		(net "GND")
	)
	(segment
		(start 111.76762 -40.741346)
		(end 111.576104 -40.54983)
		(width 0.254)
		(layer "F.Cu")
		(net "GND")
	)
	(segment
		(start 139.44981 -8.997188)
		(end 139.015724 -8.563102)
		(width 0.254)
		(layer "F.Cu")
		(net "GND")
	)
	(segment
		(start 91.450668 -40.800274)
		(end 91.44889 -40.800274)
		(width 0.254)
		(layer "F.Cu")
		(net "GND")
	)
	(segment
		(start 104.958388 -25.951434)
		(end 104.958388 -25.595326)
		(width 0.254)
		(layer "F.Cu")
		(net "GND")
	)
	(segment
		(start 111.656368 -44.567094)
		(end 111.65586 -44.566586)
		(width 0.254)
		(layer "F.Cu")
		(net "GND")
	)
	(segment
		(start 179.649882 -8.498586)
		(end 179.617878 -8.466582)
		(width 0.254)
		(layer "F.Cu")
		(net "GND")
	)
	(segment
		(start 150.4442 -51.3588)
		(end 151.257 -51.3588)
		(width 0.3048)
		(layer "F.Cu")
		(net "GND")
	)
	(segment
		(start 90.256868 -36.450778)
		(end 90.256868 -36.429696)
		(width 0.254)
		(layer "F.Cu")
		(net "GND")
	)
	(segment
		(start 106.121708 -28.135834)
		(end 106.172508 -28.186634)
		(width 0.254)
		(layer "F.Cu")
		(net "GND")
	)
	(segment
		(start 89.804748 -52.891944)
		(end 89.863168 -52.950364)
		(width 0.254)
		(layer "F.Cu")
		(net "GND")
	)
	(segment
		(start 93.622368 -33.045146)
		(end 93.632528 -33.045146)
		(width 0.3048)
		(layer "F.Cu")
		(net "GND")
	)
	(segment
		(start 34.367978 -6.213602)
		(end 34.367978 -9.054846)
		(width 0.7112)
		(layer "F.Cu")
		(net "GND")
	)
	(segment
		(start 56.8198 -42.037)
		(end 56.16448 -42.037)
		(width 0.3048)
		(layer "F.Cu")
		(net "GND")
	)
	(segment
		(start 85.448648 -49.202848)
		(end 85.864192 -49.618392)
		(width 0.254)
		(layer "F.Cu")
		(net "GND")
	)
	(segment
		(start 179.349908 -1.68402)
		(end 179.349908 -3.083306)
		(width 0.254)
		(layer "F.Cu")
		(net "GND")
	)
	(segment
		(start 171.549822 -1.68402)
		(end 171.549822 -2.98704)
		(width 0.254)
		(layer "F.Cu")
		(net "GND")
	)
	(segment
		(start 171.357544 -63.554356)
		(end 171.357544 -64.111124)
		(width 0.254)
		(layer "F.Cu")
		(net "GND")
	)
	(segment
		(start 85.852 -47.1678)
		(end 85.852 -47.342806)
		(width 0.254)
		(layer "F.Cu")
		(net "GND")
	)
	(segment
		(start 137.649966 -9.897364)
		(end 137.649966 -8.473694)
		(width 0.3048)
		(layer "F.Cu")
		(net "GND")
	)
	(segment
		(start 81.785968 -35.105086)
		(end 81.9912 -34.899854)
		(width 0.254)
		(layer "F.Cu")
		(net "GND")
	)
	(segment
		(start 176.949862 -2.807716)
		(end 176.3268 -3.430778)
		(width 0.254)
		(layer "F.Cu")
		(net "GND")
	)
	(segment
		(start 103.550212 -40.955214)
		(end 103.8606 -41.265602)
		(width 0.254)
		(layer "F.Cu")
		(net "GND")
	)
	(segment
		(start 92.682568 -52.448714)
		(end 92.787978 -52.554124)
		(width 0.254)
		(layer "F.Cu")
		(net "GND")
	)
	(segment
		(start 174.249842 -9.897364)
		(end 174.249842 -8.941816)
		(width 0.254)
		(layer "F.Cu")
		(net "GND")
	)
	(segment
		(start 87.06739 -41.027096)
		(end 87.049864 -41.044622)
		(width 0.254)
		(layer "F.Cu")
		(net "GND")
	)
	(segment
		(start 79.925418 -42.168064)
		(end 80.107536 -42.350182)
		(width 0.254)
		(layer "F.Cu")
		(net "GND")
	)
	(segment
		(start 106.5276 -41.655746)
		(end 106.467148 -41.655746)
		(width 0.254)
		(layer "F.Cu")
		(net "GND")
	)
	(segment
		(start 109.461808 -28.307792)
		(end 109.461808 -27.658314)
		(width 0.254)
		(layer "F.Cu")
		(net "GND")
	)
	(segment
		(start 109.913928 -47.788322)
		(end 110.605062 -47.097188)
		(width 0.254)
		(layer "F.Cu")
		(net "GND")
	)
	(segment
		(start 87.0585 -36.344606)
		(end 87.0585 -35.476942)
		(width 0.254)
		(layer "F.Cu")
		(net "GND")
	)
	(segment
		(start 158.623 -23.0378)
		(end 158.623 -25.8826)
		(width 0.3048)
		(layer "F.Cu")
		(net "GND")
	)
	(segment
		(start 136.9568 -20.6248)
		(end 138.772646 -22.440646)
		(width 0.3048)
		(layer "F.Cu")
		(net "GND")
	)
	(segment
		(start 21.368004 -6.213602)
		(end 21.34997 -6.195568)
		(width 0.7112)
		(layer "F.Cu")
		(net "GND")
	)
	(segment
		(start 102.692708 -36.283646)
		(end 102.765352 -36.283646)
		(width 0.3048)
		(layer "F.Cu")
		(net "GND")
	)
	(segment
		(start 134.949946 -1.68402)
		(end 134.949946 -2.605024)
		(width 0.254)
		(layer "F.Cu")
		(net "GND")
	)
	(segment
		(start 187.2742 -3.125978)
		(end 187.149994 -3.001772)
		(width 0.254)
		(layer "F.Cu")
		(net "GND")
	)
	(segment
		(start 146.96948 -3.085338)
		(end 146.96948 -3.138678)
		(width 0.3048)
		(layer "F.Cu")
		(net "GND")
	)
	(segment
		(start 51.3461 -44.6405)
		(end 51.80076 -44.6405)
		(width 0.3556)
		(layer "F.Cu")
		(net "GND")
	)
	(segment
		(start 86.531196 -45.237908)
		(end 86.32825 -45.034962)
		(width 0.254)
		(layer "F.Cu")
		(net "GND")
	)
	(segment
		(start 48.472598 -37.0586)
		(end 48.828198 -37.4142)
		(width 0.508)
		(layer "F.Cu")
		(net "GND")
	)
	(segment
		(start 89.0905 -35.1282)
		(end 88.760046 -35.458654)
		(width 0.254)
		(layer "F.Cu")
		(net "GND")
	)
	(segment
		(start 107.673648 -26.560526)
		(end 107.617768 -26.616406)
		(width 0.3048)
		(layer "F.Cu")
		(net "GND")
	)
	(segment
		(start 104.623108 -43.62577)
		(end 104.243632 -43.246294)
		(width 0.254)
		(layer "F.Cu")
		(net "GND")
	)
	(segment
		(start 92.131388 -27.447494)
		(end 91.661488 -27.447494)
		(width 0.3048)
		(layer "F.Cu")
		(net "GND")
	)
	(segment
		(start 109.603286 -31.765494)
		(end 109.603286 -32.018224)
		(width 0.254)
		(layer "F.Cu")
		(net "GND")
	)
	(segment
		(start 84.104988 -37.140134)
		(end 84.022184 -37.140134)
		(width 0.254)
		(layer "F.Cu")
		(net "GND")
	)
	(segment
		(start 82.829908 -43.027854)
		(end 82.905346 -43.027854)
		(width 0.254)
		(layer "F.Cu")
		(net "GND")
	)
	(segment
		(start 17.9324 -52.6288)
		(end 17.9324 -52.907946)
		(width 0.3048)
		(layer "F.Cu")
		(net "GND")
	)
	(segment
		(start 86.904068 -27.133296)
		(end 86.947248 -27.176476)
		(width 0.3048)
		(layer "F.Cu")
		(net "GND")
	)
	(segment
		(start 81.768188 -35.811206)
		(end 81.100168 -35.811206)
		(width 0.254)
		(layer "F.Cu")
		(net "GND")
	)
	(segment
		(start 94.041468 -27.952446)
		(end 93.655134 -27.566112)
		(width 0.3048)
		(layer "F.Cu")
		(net "GND")
	)
	(segment
		(start 46.632876 -34.544)
		(end 46.609 -34.544)
		(width 0.3048)
		(layer "F.Cu")
		(net "GND")
	)
	(segment
		(start 181.44998 -8.95604)
		(end 180.9623 -8.46836)
		(width 0.254)
		(layer "F.Cu")
		(net "GND")
	)
	(segment
		(start 172.8216 -69.3928)
		(end 172.8216 -69.3674)
		(width 0.254)
		(layer "F.Cu")
		(net "GND")
	)
	(segment
		(start 107.643168 -27.299666)
		(end 107.643168 -27.300174)
		(width 0.254)
		(layer "F.Cu")
		(net "GND")
	)
	(segment
		(start 138.850116 -62.59322)
		(end 138.850116 -63.867284)
		(width 0.254)
		(layer "F.Cu")
		(net "GND")
	)
	(segment
		(start 130.449828 -9.897364)
		(end 130.449828 -8.379206)
		(width 0.254)
		(layer "F.Cu")
		(net "GND")
	)
	(segment
		(start 91.39809 -48.012096)
		(end 91.433904 -48.012096)
		(width 0.254)
		(layer "F.Cu")
		(net "GND")
	)
	(segment
		(start 37.74059 -27.55519)
		(end 37.9984 -27.813)
		(width 0.2794)
		(layer "F.Cu")
		(net "GND")
	)
	(segment
		(start 97.409 -30.563566)
		(end 97.605088 -30.759654)
		(width 0.2032)
		(layer "F.Cu")
		(net "GND")
	)
	(segment
		(start 129.8448 -44.704)
		(end 129.8448 -44.0944)
		(width 0.3048)
		(layer "F.Cu")
		(net "GND")
	)
	(segment
		(start 77.349858 -6.195568)
		(end 77.349858 -9.010142)
		(width 0.7112)
		(layer "F.Cu")
		(net "GND")
	)
	(segment
		(start 40.15867 -23.5458)
		(end 40.15867 -24.58085)
		(width 0.2794)
		(layer "F.Cu")
		(net "GND")
	)
	(segment
		(start 84.029296 -38.730174)
		(end 84.365846 -39.066724)
		(width 0.254)
		(layer "F.Cu")
		(net "GND")
	)
	(segment
		(start 115.3922 -70.6882)
		(end 115.8748 -70.2056)
		(width 0.3048)
		(layer "F.Cu")
		(net "GND")
	)
	(segment
		(start 98.649028 -40.000174)
		(end 98.649028 -39.961058)
		(width 0.3048)
		(layer "F.Cu")
		(net "GND")
	)
	(segment
		(start 119.1514 -64.643)
		(end 119.1514 -63.373)
		(width 0.508)
		(layer "F.Cu")
		(net "GND")
	)
	(segment
		(start 134.050024 -8.933942)
		(end 133.7818 -8.665718)
		(width 0.3048)
		(layer "F.Cu")
		(net "GND")
	)
	(segment
		(start 86.61654 -34.455354)
		(end 86.314788 -34.757106)
		(width 0.254)
		(layer "F.Cu")
		(net "GND")
	)
	(segment
		(start 93.978476 -28.881324)
		(end 93.979238 -28.881324)
		(width 0.3048)
		(layer "F.Cu")
		(net "GND")
	)
	(segment
		(start 105.766108 -33.711134)
		(end 105.766108 -33.710626)
		(width 0.254)
		(layer "F.Cu")
		(net "GND")
	)
	(segment
		(start 110.309406 -33.581594)
		(end 110.4138 -33.4772)
		(width 0.254)
		(layer "F.Cu")
		(net "GND")
	)
	(segment
		(start 45.349922 -6.195568)
		(end 45.349922 -9.092184)
		(width 0.7112)
		(layer "F.Cu")
		(net "GND")
	)
	(segment
		(start 62.259972 -33.02)
		(end 62.093602 -33.18637)
		(width 0.3048)
		(layer "F.Cu")
		(net "GND")
	)
	(segment
		(start 97.653348 -28.186634)
		(end 97.843848 -27.996134)
		(width 0.254)
		(layer "F.Cu")
		(net "GND")
	)
	(segment
		(start 84.028788 -46.675294)
		(end 84.3534 -46.999906)
		(width 0.254)
		(layer "F.Cu")
		(net "GND")
	)
	(segment
		(start 90.648028 -35.999674)
		(end 90.648028 -36.059618)
		(width 0.254)
		(layer "F.Cu")
		(net "GND")
	)
	(segment
		(start 140.950188 -69.444108)
		(end 140.826236 -69.320156)
		(width 0.3048)
		(layer "F.Cu")
		(net "GND")
	)
	(segment
		(start 106.528108 -33.010094)
		(end 106.528108 -33.009586)
		(width 0.254)
		(layer "F.Cu")
		(net "GND")
	)
	(segment
		(start 101.849428 -41.599866)
		(end 101.792786 -41.599866)
		(width 0.254)
		(layer "F.Cu")
		(net "GND")
	)
	(segment
		(start 88.8746 -47.521368)
		(end 88.836754 -47.559214)
		(width 0.254)
		(layer "F.Cu")
		(net "GND")
	)
	(segment
		(start 96.319848 -30.392624)
		(end 95.962978 -30.749494)
		(width 0.3048)
		(layer "F.Cu")
		(net "GND")
	)
	(segment
		(start 182.65394 -2.884678)
		(end 182.65394 -3.136138)
		(width 0.254)
		(layer "F.Cu")
		(net "GND")
	)
	(segment
		(start 164.698172 -41.3512)
		(end 164.698172 -41.321228)
		(width 0.3048)
		(layer "F.Cu")
		(net "GND")
	)
	(segment
		(start 142.14983 -1.68402)
		(end 142.1384 -1.69545)
		(width 0.3048)
		(layer "F.Cu")
		(net "GND")
	)
	(segment
		(start 105.753662 -52.641246)
		(end 105.997248 -52.641246)
		(width 0.254)
		(layer "F.Cu")
		(net "GND")
	)
	(segment
		(start 98.649028 -33.697926)
		(end 98.649028 -33.698434)
		(width 0.254)
		(layer "F.Cu")
		(net "GND")
	)
	(segment
		(start 102.765352 -36.283646)
		(end 103.12146 -36.639754)
		(width 0.3048)
		(layer "F.Cu")
		(net "GND")
	)
	(segment
		(start 54.007512 -25.019)
		(end 53.6448 -24.656288)
		(width 0.3048)
		(layer "F.Cu")
		(net "GND")
	)
	(segment
		(start 129.55016 -70.806564)
		(end 129.55016 -69.874384)
		(width 0.254)
		(layer "F.Cu")
		(net "GND")
	)
	(segment
		(start 81.836768 -33.380426)
		(end 81.587848 -33.380426)
		(width 0.254)
		(layer "F.Cu")
		(net "GND")
	)
	(segment
		(start 90.246962 -37.97554)
		(end 90.28684 -37.97554)
		(width 0.254)
		(layer "F.Cu")
		(net "GND")
	)
	(segment
		(start 143.8402 -63.999364)
		(end 143.802354 -64.03721)
		(width 0.254)
		(layer "F.Cu")
		(net "GND")
	)
	(segment
		(start 95.443548 -28.135834)
		(end 95.921068 -27.658314)
		(width 0.3048)
		(layer "F.Cu")
		(net "GND")
	)
	(segment
		(start 78.349856 -6.195568)
		(end 78.349856 -9.148064)
		(width 0.7112)
		(layer "F.Cu")
		(net "GND")
	)
	(segment
		(start 100.968048 -28.333954)
		(end 100.7364 -28.565602)
		(width 0.254)
		(layer "F.Cu")
		(net "GND")
	)
	(segment
		(start 18.322798 -53.298344)
		(end 18.322798 -53.400198)
		(width 0.3048)
		(layer "F.Cu")
		(net "GND")
	)
	(segment
		(start 94.922848 -33.426654)
		(end 94.651068 -33.698434)
		(width 0.3048)
		(layer "F.Cu")
		(net "GND")
	)
	(segment
		(start 99.451668 -42.399966)
		(end 99.453954 -42.399966)
		(width 0.3048)
		(layer "F.Cu")
		(net "GND")
	)
	(segment
		(start 84.790788 -42.702734)
		(end 84.815934 -42.702734)
		(width 0.254)
		(layer "F.Cu")
		(net "GND")
	)
	(segment
		(start 183.850026 -9.897364)
		(end 183.850026 -9.115552)
		(width 0.254)
		(layer "F.Cu")
		(net "GND")
	)
	(segment
		(start 84.509102 -47.6758)
		(end 84.5312 -47.6758)
		(width 0.254)
		(layer "F.Cu")
		(net "GND")
	)
	(segment
		(start 82.177128 -26.088594)
		(end 82.989928 -26.088594)
		(width 0.254)
		(layer "F.Cu")
		(net "GND")
	)
	(segment
		(start 86.695788 -32.771334)
		(end 86.593934 -32.771334)
		(width 0.3048)
		(layer "F.Cu")
		(net "GND")
	)
	(segment
		(start 42.1005 -34.5567)
		(end 42.10177 -34.55543)
		(width 0.2794)
		(layer "F.Cu")
		(net "GND")
	)
	(segment
		(start 107.945428 -32.024828)
		(end 107.671108 -31.750508)
		(width 0.254)
		(layer "F.Cu")
		(net "GND")
	)
	(segment
		(start 182.050182 -62.59322)
		(end 182.050182 -64.05499)
		(width 0.254)
		(layer "F.Cu")
		(net "GND")
	)
	(segment
		(start 146.349974 -2.465832)
		(end 146.96948 -3.085338)
		(width 0.3048)
		(layer "F.Cu")
		(net "GND")
	)
	(segment
		(start 179.70246 -64.082168)
		(end 179.70246 -64.08674)
		(width 0.254)
		(layer "F.Cu")
		(net "GND")
	)
	(segment
		(start 134.19582 -69.50075)
		(end 134.19582 -69.37756)
		(width 0.254)
		(layer "F.Cu")
		(net "GND")
	)
	(segment
		(start 84.790788 -46.675294)
		(end 84.790788 -46.817788)
		(width 0.254)
		(layer "F.Cu")
		(net "GND")
	)
	(segment
		(start 97.843848 -27.980894)
		(end 98.186494 -27.638248)
		(width 0.254)
		(layer "F.Cu")
		(net "GND")
	)
	(segment
		(start 86.314788 -46.675294)
		(end 86.314788 -46.705012)
		(width 0.3048)
		(layer "F.Cu")
		(net "GND")
	)
	(segment
		(start 100.229162 -42.399966)
		(end 100.249228 -42.399966)
		(width 0.254)
		(layer "F.Cu")
		(net "GND")
	)
	(segment
		(start 147.928838 -49.135538)
		(end 148.2598 -49.4665)
		(width 0.3048)
		(layer "F.Cu")
		(net "GND")
	)
	(segment
		(start 14.6304 -54.4068)
		(end 14.605 -54.4322)
		(width 0.508)
		(layer "F.Cu")
		(net "GND")
	)
	(segment
		(start 109.17809 -50.134774)
		(end 109.202982 -50.109882)
		(width 0.3048)
		(layer "F.Cu")
		(net "GND")
	)
	(segment
		(start 42.349928 -6.195568)
		(end 42.367962 -6.213602)
		(width 0.7112)
		(layer "F.Cu")
		(net "GND")
	)
	(segment
		(start 100.439474 -25.9334)
		(end 99.677474 -25.9334)
		(width 0.254)
		(layer "F.Cu")
		(net "GND")
	)
	(segment
		(start 182.118 -48.3108)
		(end 182.118 -47.625)
		(width 0.3048)
		(layer "F.Cu")
		(net "GND")
	)
	(segment
		(start 133.9977 -45.1612)
		(end 133.8707 -45.2882)
		(width 0.3048)
		(layer "F.Cu")
		(net "GND")
	)
	(segment
		(start 179.649882 -9.897364)
		(end 179.649882 -8.498586)
		(width 0.254)
		(layer "F.Cu")
		(net "GND")
	)
	(segment
		(start 98.649028 -35.999674)
		(end 98.989134 -36.33978)
		(width 0.3048)
		(layer "F.Cu")
		(net "GND")
	)
	(segment
		(start 98.3107 -39.62273)
		(end 98.3107 -39.5986)
		(width 0.3048)
		(layer "F.Cu")
		(net "GND")
	)
	(segment
		(start 184.749948 -1.68402)
		(end 184.749948 -2.623058)
		(width 0.254)
		(layer "F.Cu")
		(net "GND")
	)
	(segment
		(start 78.5622 -58.6486)
		(end 78.5368 -58.6486)
		(width 0.3048)
		(layer "F.Cu")
		(net "GND")
	)
	(segment
		(start 57.16524 -42.38244)
		(end 56.8198 -42.037)
		(width 0.3048)
		(layer "F.Cu")
		(net "GND")
	)
	(segment
		(start 103.938832 -42.941494)
		(end 104.243632 -43.246294)
		(width 0.254)
		(layer "F.Cu")
		(net "GND")
	)
	(segment
		(start 86.896448 -26.896314)
		(end 86.904068 -26.903934)
		(width 0.3048)
		(layer "F.Cu")
		(net "GND")
	)
	(segment
		(start 91.506802 -35.999674)
		(end 91.878404 -35.628072)
		(width 0.254)
		(layer "F.Cu")
		(net "GND")
	)
	(segment
		(start 168.021 -40.61206)
		(end 168.239948 -40.831008)
		(width 0.508)
		(layer "F.Cu")
		(net "GND")
	)
	(segment
		(start 88.598248 -47.559214)
		(end 88.836754 -47.559214)
		(width 0.254)
		(layer "F.Cu")
		(net "GND")
	)
	(segment
		(start 109.913928 -43.251374)
		(end 110.605062 -42.56024)
		(width 0.254)
		(layer "F.Cu")
		(net "GND")
	)
	(segment
		(start 110.53572 -65.29324)
		(end 109.87024 -65.29324)
		(width 0.3048)
		(layer "F.Cu")
		(net "GND")
	)
	(segment
		(start 84.768436 -27.660346)
		(end 84.687664 -27.660346)
		(width 0.254)
		(layer "F.Cu")
		(net "GND")
	)
	(segment
		(start 100.95357 -36.097972)
		(end 100.347526 -36.097972)
		(width 0.3048)
		(layer "F.Cu")
		(net "GND")
	)
	(segment
		(start 138.86434 -56.46039)
		(end 139.8016 -56.46039)
		(width 0.3048)
		(layer "F.Cu")
		(net "GND")
	)
	(segment
		(start 90.660474 -34.399474)
		(end 91.059 -34.798)
		(width 0.254)
		(layer "F.Cu")
		(net "GND")
	)
	(segment
		(start 89.659968 -29.235654)
		(end 89.48039 -29.235654)
		(width 0.3048)
		(layer "F.Cu")
		(net "GND")
	)
	(segment
		(start 83.015074 -49.814226)
		(end 82.93227 -49.814226)
		(width 0.254)
		(layer "F.Cu")
		(net "GND")
	)
	(segment
		(start 25.019 -9.561068)
		(end 25.367996 -9.212072)
		(width 0.7112)
		(layer "F.Cu")
		(net "GND")
	)
	(segment
		(start 99.841558 -42.78757)
		(end 100.229162 -42.399966)
		(width 0.254)
		(layer "F.Cu")
		(net "GND")
	)
	(segment
		(start 106.9086 -34.996374)
		(end 106.582972 -35.322002)
		(width 0.254)
		(layer "F.Cu")
		(net "GND")
	)
	(segment
		(start 81.72577 -38.585394)
		(end 81.785968 -38.585394)
		(width 0.254)
		(layer "F.Cu")
		(net "GND")
	)
	(segment
		(start 103.874316 -38.051486)
		(end 104.242108 -37.683694)
		(width 0.3048)
		(layer "F.Cu")
		(net "GND")
	)
	(segment
		(start 82.3468 -40.0812)
		(end 82.3214 -40.0558)
		(width 0.254)
		(layer "F.Cu")
		(net "GND")
	)
	(segment
		(start 86.314788 -38.730174)
		(end 86.314788 -38.729666)
		(width 0.254)
		(layer "F.Cu")
		(net "GND")
	)
	(segment
		(start 89.850468 -41.600374)
		(end 90.648028 -41.600374)
		(width 0.254)
		(layer "F.Cu")
		(net "GND")
	)
	(segment
		(start 106.109262 -33.367472)
		(end 106.109262 -33.355788)
		(width 0.254)
		(layer "F.Cu")
		(net "GND")
	)
	(segment
		(start 103.480108 -41.656254)
		(end 103.318056 -41.494202)
		(width 0.254)
		(layer "F.Cu")
		(net "GND")
	)
	(segment
		(start 140.99794 -24.746204)
		(end 141.397736 -25.146)
		(width 0.3048)
		(layer "F.Cu")
		(net "GND")
	)
	(segment
		(start 91.407488 -48.021494)
		(end 91.39809 -48.012096)
		(width 0.254)
		(layer "F.Cu")
		(net "GND")
	)
	(segment
		(start 46.3042 -21.209)
		(end 45.974 -21.5392)
		(width 0.3048)
		(layer "F.Cu")
		(net "GND")
	)
	(segment
		(start 85.159088 -26.561034)
		(end 85.159088 -27.269694)
		(width 0.254)
		(layer "F.Cu")
		(net "GND")
	)
	(segment
		(start 89.149428 -44.701714)
		(end 89.850468 -44.701714)
		(width 0.254)
		(layer "F.Cu")
		(net "GND")
	)
	(segment
		(start 132.588 -20.1168)
		(end 132.842 -19.8628)
		(width 0.3048)
		(layer "F.Cu")
		(net "GND")
	)
	(segment
		(start 142.1384 -1.69545)
		(end 142.1384 -2.85877)
		(width 0.3048)
		(layer "F.Cu")
		(net "GND")
	)
	(segment
		(start 74.803 -9.6012)
		(end 74.803 -9.6266)
		(width 0.7112)
		(layer "F.Cu")
		(net "GND")
	)
	(segment
		(start 99.451668 -42.400474)
		(end 99.451668 -42.399966)
		(width 0.3048)
		(layer "F.Cu")
		(net "GND")
	)
	(segment
		(start 91.450668 -35.199574)
		(end 91.450668 -35.200336)
		(width 0.254)
		(layer "F.Cu")
		(net "GND")
	)
	(segment
		(start 80.498188 -43.698414)
		(end 79.701136 -43.698414)
		(width 0.254)
		(layer "F.Cu")
		(net "GND")
	)
	(segment
		(start 83.0834 -24.892)
		(end 83.312 -24.6634)
		(width 0.254)
		(layer "F.Cu")
		(net "GND")
	)
	(segment
		(start 61.16701 -40.11549)
		(end 61.7093 -39.5732)
		(width 0.3048)
		(layer "F.Cu")
		(net "GND")
	)
	(segment
		(start 186.5376 -2.534158)
		(end 185.95594 -3.115818)
		(width 0.254)
		(layer "F.Cu")
		(net "GND")
	)
	(segment
		(start 58.928 -39.878)
		(end 59.2328 -39.5732)
		(width 0.3048)
		(layer "F.Cu")
		(net "GND")
	)
	(segment
		(start 142.49781 -45.1612)
		(end 142.49781 -46.068742)
		(width 0.3048)
		(layer "F.Cu")
		(net "GND")
	)
	(segment
		(start 132.1308 -33.29432)
		(end 132.94868 -33.29432)
		(width 0.3048)
		(layer "F.Cu")
		(net "GND")
	)
	(segment
		(start 89.850468 -42.400474)
		(end 90.648028 -42.400474)
		(width 0.3048)
		(layer "F.Cu")
		(net "GND")
	)
	(segment
		(start 131.934204 -3.127502)
		(end 131.934204 -3.128772)
		(width 0.3048)
		(layer "F.Cu")
		(net "GND")
	)
	(segment
		(start 90.361008 -32.283654)
		(end 90.361008 -32.279336)
		(width 0.3048)
		(layer "F.Cu")
		(net "GND")
	)
	(segment
		(start 152.461976 -54.38648)
		(end 151.5999 -54.38648)
		(width 0.3048)
		(layer "F.Cu")
		(net "GND")
	)
	(segment
		(start 92.347288 -33.423606)
		(end 91.976194 -33.052512)
		(width 0.3048)
		(layer "F.Cu")
		(net "GND")
	)
	(segment
		(start 89.3318 -42.4942)
		(end 89.3064 -42.4688)
		(width 0.3048)
		(layer "F.Cu")
		(net "GND")
	)
	(segment
		(start 82.954368 -28.196032)
		(end 82.6262 -28.5242)
		(width 0.254)
		(layer "F.Cu")
		(net "GND")
	)
	(segment
		(start 61.595 -42.047414)
		(end 61.595 -41.424098)
		(width 0.3048)
		(layer "F.Cu")
		(net "GND")
	)
	(segment
		(start 108.42752 -40.65524)
		(end 108.364274 -40.65524)
		(width 0.254)
		(layer "F.Cu")
		(net "GND")
	)
	(segment
		(start 49.7078 -43.4848)
		(end 48.3616 -44.831)
		(width 0.3048)
		(layer "F.Cu")
		(net "GND")
	)
	(segment
		(start 184.749948 -2.623058)
		(end 184.28462 -3.088386)
		(width 0.254)
		(layer "F.Cu")
		(net "GND")
	)
	(segment
		(start 104.480868 -46.952154)
		(end 104.480868 -46.996096)
		(width 0.254)
		(layer "F.Cu")
		(net "GND")
	)
	(segment
		(start 104.415082 -34.4424)
		(end 103.861108 -34.996374)
		(width 0.3048)
		(layer "F.Cu")
		(net "GND")
	)
	(segment
		(start 100.968048 -28.135834)
		(end 100.968048 -28.333954)
		(width 0.254)
		(layer "F.Cu")
		(net "GND")
	)
	(segment
		(start 89.352628 -50.25263)
		(end 89.3064 -50.206402)
		(width 0.254)
		(layer "F.Cu")
		(net "GND")
	)
	(segment
		(start 96.081088 -44.973494)
		(end 96.081088 -44.990512)
		(width 0.3048)
		(layer "F.Cu")
		(net "GND")
	)
	(segment
		(start 130.02895 -41.29405)
		(end 129.159 -42.164)
		(width 0.3048)
		(layer "F.Cu")
		(net "GND")
	)
	(segment
		(start 88.653874 -32.1818)
		(end 88.374728 -31.902654)
		(width 0.3048)
		(layer "F.Cu")
		(net "GND")
	)
	(segment
		(start 146.05 -62.59322)
		(end 146.05 -63.373)
		(width 0.254)
		(layer "F.Cu")
		(net "GND")
	)
	(segment
		(start 110.749588 -37.482526)
		(end 111.082836 -37.149278)
		(width 0.254)
		(layer "F.Cu")
		(net "GND")
	)
	(segment
		(start 153.849578 -8.934958)
		(end 154.316176 -8.46836)
		(width 0.3048)
		(layer "F.Cu")
		(net "GND")
	)
	(segment
		(start 134.649972 -63.343028)
		(end 133.9596 -64.0334)
		(width 0.254)
		(layer "F.Cu")
		(net "GND")
	)
	(segment
		(start 90.731848 -50.264314)
		(end 90.593672 -50.264314)
		(width 0.254)
		(layer "F.Cu")
		(net "GND")
	)
	(segment
		(start 49.744884 -40.196516)
		(end 49.744884 -43.103292)
		(width 0.3048)
		(layer "F.Cu")
		(net "GND")
	)
	(segment
		(start 84.074 -33.15716)
		(end 84.04098 -33.15716)
		(width 0.254)
		(layer "F.Cu")
		(net "GND")
	)
	(segment
		(start 81.343754 -37.720016)
		(end 81.127854 -37.935916)
		(width 0.254)
		(layer "F.Cu")
		(net "GND")
	)
	(segment
		(start 89.352628 -50.404014)
		(end 89.352628 -50.25263)
		(width 0.254)
		(layer "F.Cu")
		(net "GND")
	)
	(segment
		(start 105.4608 -20.701)
		(end 105.4608 -21.5138)
		(width 0.381)
		(layer "F.Cu")
		(net "GND")
	)
	(segment
		(start 74.367898 -6.213602)
		(end 74.367898 -9.166098)
		(width 0.7112)
		(layer "F.Cu")
		(net "GND")
	)
	(segment
		(start 33.36798 -6.213602)
		(end 33.36798 -9.046972)
		(width 0.7112)
		(layer "F.Cu")
		(net "GND")
	)
	(segment
		(start 187.198 -47.879)
		(end 187.198 -47.83201)
		(width 0.3048)
		(layer "F.Cu")
		(net "GND")
	)
	(segment
		(start 166.150036 -70.806564)
		(end 166.150036 -69.616828)
		(width 0.3048)
		(layer "F.Cu")
		(net "GND")
	)
	(segment
		(start 145.450052 -8.958326)
		(end 145.603468 -8.80491)
		(width 0.254)
		(layer "F.Cu")
		(net "GND")
	)
	(segment
		(start 90.648028 -39.200074)
		(end 90.648028 -39.237412)
		(width 0.254)
		(layer "F.Cu")
		(net "GND")
	)
	(segment
		(start 89.529666 -27.996134)
		(end 89.154 -28.3718)
		(width 0.3048)
		(layer "F.Cu")
		(net "GND")
	)
	(segment
		(start 86.947248 -27.176476)
		(end 86.947248 -27.658314)
		(width 0.3048)
		(layer "F.Cu")
		(net "GND")
	)
	(segment
		(start 52.8066 -53.467)
		(end 52.8066 -53.90642)
		(width 0.3048)
		(layer "F.Cu")
		(net "GND")
	)
	(segment
		(start 157.65653 -51.2826)
		(end 156.7688 -52.17033)
		(width 0.254)
		(layer "F.Cu")
		(net "GND")
	)
	(segment
		(start 106.528108 -45.628814)
		(end 106.51236 -45.628814)
		(width 0.254)
		(layer "F.Cu")
		(net "GND")
	)
	(segment
		(start 35.844226 -24.55672)
		(end 35.203384 -24.55672)
		(width 0.2794)
		(layer "F.Cu")
		(net "GND")
	)
	(segment
		(start 33.36798 -9.046972)
		(end 32.851344 -9.563608)
		(width 0.7112)
		(layer "F.Cu")
		(net "GND")
	)
	(segment
		(start 98.067368 -48.402494)
		(end 98.062542 -48.402494)
		(width 0.254)
		(layer "F.Cu")
		(net "GND")
	)
	(segment
		(start 95.618808 -29.616654)
		(end 95.618808 -29.616146)
		(width 0.3048)
		(layer "F.Cu")
		(net "GND")
	)
	(segment
		(start 147.928838 -48.081438)
		(end 147.928838 -49.135538)
		(width 0.3048)
		(layer "F.Cu")
		(net "GND")
	)
	(segment
		(start 129.250186 -62.59322)
		(end 129.250186 -63.806324)
		(width 0.254)
		(layer "F.Cu")
		(net "GND")
	)
	(segment
		(start 57.785 -22.479)
		(end 57.785 -21.47824)
		(width 0.3048)
		(layer "F.Cu")
		(net "GND")
	)
	(segment
		(start 57.785 -21.47824)
		(end 58.175144 -21.088096)
		(width 0.3048)
		(layer "F.Cu")
		(net "GND")
	)
	(segment
		(start 113.040922 -69.632322)
		(end 113.1062 -69.6976)
		(width 0.3048)
		(layer "F.Cu")
		(net "GND")
	)
	(segment
		(start 82.504788 -31.463234)
		(end 82.504788 -31.486094)
		(width 0.254)
		(layer "F.Cu")
		(net "GND")
	)
	(segment
		(start 191.656716 -34.1757)
		(end 192.456308 -34.1757)
		(width 0.2032)
		(layer "F.Cu")
		(net "GND")
	)
	(segment
		(start 91.245944 -34.611056)
		(end 91.059 -34.798)
		(width 0.254)
		(layer "F.Cu")
		(net "GND")
	)
	(segment
		(start 159.3342 -26.5938)
		(end 159.385 -26.6446)
		(width 0.3048)
		(layer "F.Cu")
		(net "GND")
	)
	(segment
		(start 82.885788 -44.689014)
		(end 82.466688 -44.689014)
		(width 0.254)
		(layer "F.Cu")
		(net "GND")
	)
	(segment
		(start 107.349036 -50.404014)
		(end 106.998262 -50.754788)
		(width 0.254)
		(layer "F.Cu")
		(net "GND")
	)
	(segment
		(start 90.2462 -44.3484)
		(end 90.300302 -44.3484)
		(width 0.254)
		(layer "F.Cu")
		(net "GND")
	)
	(segment
		(start 189.850014 -63.662814)
		(end 190.246 -64.0588)
		(width 0.254)
		(layer "F.Cu")
		(net "GND")
	)
	(segment
		(start 81.366868 -38.944296)
		(end 81.72577 -38.585394)
		(width 0.254)
		(layer "F.Cu")
		(net "GND")
	)
	(segment
		(start 153.849832 -9.897364)
		(end 153.849578 -9.89711)
		(width 0.3048)
		(layer "F.Cu")
		(net "GND")
	)
	(segment
		(start 87.22233 -49.545494)
		(end 86.875366 -49.892458)
		(width 0.254)
		(layer "F.Cu")
		(net "GND")
	)
	(segment
		(start 105.766108 -40.955214)
		(end 105.766108 -40.954706)
		(width 0.254)
		(layer "F.Cu")
		(net "GND")
	)
	(segment
		(start 79.2099 -40.317928)
		(end 79.055468 -40.317928)
		(width 0.254)
		(layer "F.Cu")
		(net "GND")
	)
	(segment
		(start 97.165668 -28.186634)
		(end 97.653348 -28.186634)
		(width 0.254)
		(layer "F.Cu")
		(net "GND")
	)
	(segment
		(start 84.402168 -29.552646)
		(end 84.721954 -29.23286)
		(width 0.3048)
		(layer "F.Cu")
		(net "GND")
	)
	(segment
		(start 106.142536 -45.304202)
		(end 105.766108 -44.927774)
		(width 0.3048)
		(layer "F.Cu")
		(net "GND")
	)
	(segment
		(start 106.172508 -28.186634)
		(end 106.172508 -28.414726)
		(width 0.254)
		(layer "F.Cu")
		(net "GND")
	)
	(segment
		(start 178.150012 -69.905626)
		(end 177.8762 -69.631814)
		(width 0.254)
		(layer "F.Cu")
		(net "GND")
	)
	(segment
		(start 96.251268 -40.000174)
		(end 96.251268 -39.99738)
		(width 0.3048)
		(layer "F.Cu")
		(net "GND")
	)
	(segment
		(start 81.097628 -48.780954)
		(end 81.618328 -48.780954)
		(width 0.254)
		(layer "F.Cu")
		(net "GND")
	)
	(segment
		(start 89.3064 -49.279302)
		(end 89.421208 -49.164494)
		(width 0.254)
		(layer "F.Cu")
		(net "GND")
	)
	(segment
		(start 110.240572 -32.736028)
		(end 110.4138 -32.5628)
		(width 0.254)
		(layer "F.Cu")
		(net "GND")
	)
	(segment
		(start 86.17712 -31.732982)
		(end 86.388448 -31.521654)
		(width 0.3048)
		(layer "F.Cu")
		(net "GND")
	)
	(segment
		(start 97.38233 -36.399724)
		(end 97.38233 -36.333176)
		(width 0.3048)
		(layer "F.Cu")
		(net "GND")
	)
	(segment
		(start 181.749954 -70.806564)
		(end 181.749954 -69.64045)
		(width 0.254)
		(layer "F.Cu")
		(net "GND")
	)
	(segment
		(start 142.113 -25.146)
		(end 142.494 -24.765)
		(width 0.3048)
		(layer "F.Cu")
		(net "GND")
	)
	(segment
		(start 78.80096 -60.46724)
		(end 78.867 -60.4012)
		(width 0.3048)
		(layer "F.Cu")
		(net "GND")
	)
	(segment
		(start 88.161368 -28.186634)
		(end 88.161368 -27.913076)
		(width 0.3048)
		(layer "F.Cu")
		(net "GND")
	)
	(segment
		(start 144.99844 -23.9268)
		(end 144.99844 -22.71141)
		(width 0.3048)
		(layer "F.Cu")
		(net "GND")
	)
	(segment
		(start 103.480108 -37.683186)
		(end 103.786178 -37.989256)
		(width 0.3048)
		(layer "F.Cu")
		(net "GND")
	)
	(segment
		(start 79.64678 -40.535606)
		(end 79.60106 -40.535606)
		(width 0.2032)
		(layer "F.Cu")
		(net "GND")
	)
	(segment
		(start 185.76036 -20.95881)
		(end 185.76036 -20.15871)
		(width 0.3048)
		(layer "F.Cu")
		(net "GND")
	)
	(segment
		(start 91.716606 -46.0756)
		(end 91.765882 -46.0756)
		(width 0.254)
		(layer "F.Cu")
		(net "GND")
	)
	(segment
		(start 142.450058 -64.066674)
		(end 142.38097 -64.135762)
		(width 0.254)
		(layer "F.Cu")
		(net "GND")
	)
	(segment
		(start 86.314788 -34.757106)
		(end 86.314788 -34.757614)
		(width 0.254)
		(layer "F.Cu")
		(net "GND")
	)
	(segment
		(start 55.86476 -41.2115)
		(end 55.86476 -40.45712)
		(width 0.3556)
		(layer "F.Cu")
		(net "GND")
	)
	(segment
		(start 38.813994 -20.830794)
		(end 38.03777 -20.05457)
		(width 0.2794)
		(layer "F.Cu")
		(net "GND")
	)
	(segment
		(start 135.94334 -55.960264)
		(end 135.208264 -55.960264)
		(width 0.3048)
		(layer "F.Cu")
		(net "GND")
	)
	(segment
		(start 103.895652 -36.566602)
		(end 103.910384 -36.566602)
		(width 0.3048)
		(layer "F.Cu")
		(net "GND")
	)
	(segment
		(start 91.450668 -42.354246)
		(end 91.450668 -42.400474)
		(width 0.254)
		(layer "F.Cu")
		(net "GND")
	)
	(segment
		(start 92.7735 -52.568602)
		(end 92.7735 -52.9844)
		(width 0.254)
		(layer "F.Cu")
		(net "GND")
	)
	(segment
		(start 88.519 -37.933122)
		(end 88.580722 -37.8714)
		(width 0.254)
		(layer "F.Cu")
		(net "GND")
	)
	(segment
		(start 82.08391 -43.386756)
		(end 82.08391 -43.671998)
		(width 0.254)
		(layer "F.Cu")
		(net "GND")
	)
	(segment
		(start 31.2166 -35.0012)
		(end 30.9118 -35.306)
		(width 0.3048)
		(layer "F.Cu")
		(net "GND")
	)
	(segment
		(start 87.434928 -45.05198)
		(end 87.772748 -45.3898)
		(width 0.254)
		(layer "F.Cu")
		(net "GND")
	)
	(segment
		(start 99.453954 -42.399966)
		(end 99.841558 -42.78757)
		(width 0.3048)
		(layer "F.Cu")
		(net "GND")
	)
	(segment
		(start 177.2666 -46.0756)
		(end 177.292 -46.101)
		(width 0.3048)
		(layer "F.Cu")
		(net "GND")
	)
	(segment
		(start 110.053628 -36.693094)
		(end 110.491016 -36.09594)
		(width 0.254)
		(layer "F.Cu")
		(net "GND")
	)
	(segment
		(start 88.8746 -47.425102)
		(end 88.8746 -47.521368)
		(width 0.254)
		(layer "F.Cu")
		(net "GND")
	)
	(segment
		(start 84.150708 -50.404014)
		(end 83.772248 -50.782474)
		(width 0.254)
		(layer "F.Cu")
		(net "GND")
	)
	(segment
		(start 90.648028 -40.800274)
		(end 90.707718 -40.800274)
		(width 0.254)
		(layer "F.Cu")
		(net "GND")
	)
	(segment
		(start 85.0773 -41.571418)
		(end 85.0773 -41.72712)
		(width 0.254)
		(layer "F.Cu")
		(net "GND")
	)
	(segment
		(start 58.175144 -21.088096)
		(end 58.175144 -21.082)
		(width 0.3048)
		(layer "F.Cu")
		(net "GND")
	)
	(segment
		(start 81.146142 -39.095426)
		(end 80.73771 -38.686994)
		(width 0.254)
		(layer "F.Cu")
		(net "GND")
	)
	(segment
		(start 58.363104 -20.89404)
		(end 58.175144 -21.082)
		(width 0.3048)
		(layer "F.Cu")
		(net "GND")
	)
	(segment
		(start 94.09176 -46.878494)
		(end 93.728286 -47.241968)
		(width 0.254)
		(layer "F.Cu")
		(net "GND")
	)
	(segment
		(start 158.433008 -51.2826)
		(end 157.65653 -51.2826)
		(width 0.254)
		(layer "F.Cu")
		(net "GND")
	)
	(segment
		(start 136.449816 -9.897364)
		(end 136.449816 -8.435594)
		(width 0.3048)
		(layer "F.Cu")
		(net "GND")
	)
	(segment
		(start 97.050606 -42.400474)
		(end 97.421192 -42.77106)
		(width 0.254)
		(layer "F.Cu")
		(net "GND")
	)
	(segment
		(start 72.445626 -32.888174)
		(end 72.43826 -32.89554)
		(width 0.3048)
		(layer "F.Cu")
		(net "GND")
	)
	(segment
		(start 90.830908 -29.235908)
		(end 90.932 -29.337)
		(width 0.3048)
		(layer "F.Cu")
		(net "GND")
	)
	(segment
		(start 57.4294 -22.8346)
		(end 57.785 -22.479)
		(width 0.3048)
		(layer "F.Cu")
		(net "GND")
	)
	(segment
		(start 140.99794 -23.9268)
		(end 140.99794 -24.746204)
		(width 0.3048)
		(layer "F.Cu")
		(net "GND")
	)
	(segment
		(start 83.429348 -50.63871)
		(end 83.573112 -50.782474)
		(width 0.254)
		(layer "F.Cu")
		(net "GND")
	)
	(segment
		(start 186.260486 -16.736314)
		(end 186.260486 -17.23771)
		(width 0.3048)
		(layer "F.Cu")
		(net "GND")
	)
	(segment
		(start 43.6372 -32.1564)
		(end 43.5356 -32.0548)
		(width 0.2794)
		(layer "F.Cu")
		(net "GND")
	)
	(segment
		(start 57.349898 -6.195568)
		(end 57.349898 -9.084818)
		(width 0.7112)
		(layer "F.Cu")
		(net "GND")
	)
	(segment
		(start 108.4326 -40.65016)
		(end 108.42752 -40.65524)
		(width 0.254)
		(layer "F.Cu")
		(net "GND")
	)
	(segment
		(start 90.25128 -39.6367)
		(end 90.274902 -39.6367)
		(width 0.254)
		(layer "F.Cu")
		(net "GND")
	)
	(segment
		(start 79.219806 -43.598846)
		(end 79.601568 -43.598846)
		(width 0.254)
		(layer "F.Cu")
		(net "GND")
	)
	(segment
		(start 108.204 -42.51198)
		(end 108.204 -42.71264)
		(width 0.254)
		(layer "F.Cu")
		(net "GND")
	)
	(segment
		(start 128.949958 -1.68402)
		(end 128.949958 -3.05562)
		(width 0.3048)
		(layer "F.Cu")
		(net "GND")
	)
	(segment
		(start 81.646268 -45.511974)
		(end 81.305146 -45.853096)
		(width 0.254)
		(layer "F.Cu")
		(net "GND")
	)
	(segment
		(start 82.466688 -44.689014)
		(end 82.406744 -44.62907)
		(width 0.254)
		(layer "F.Cu")
		(net "GND")
	)
	(segment
		(start 87.450168 -28.128214)
		(end 87.417148 -28.128214)
		(width 0.3048)
		(layer "F.Cu")
		(net "GND")
	)
	(segment
		(start 100.250498 -39.199566)
		(end 100.621592 -39.57066)
		(width 0.3048)
		(layer "F.Cu")
		(net "GND")
	)
	(segment
		(start 92.108528 -49.911254)
		(end 92.108528 -49.545494)
		(width 0.254)
		(layer "F.Cu")
		(net "GND")
	)
	(segment
		(start 140.58519 -64.01181)
		(end 140.58519 -64.092328)
		(width 0.254)
		(layer "F.Cu")
		(net "GND")
	)
	(segment
		(start 89.850468 -36.799774)
		(end 89.907872 -36.799774)
		(width 0.254)
		(layer "F.Cu")
		(net "GND")
	)
	(segment
		(start 108.204 -42.71264)
		(end 108.433108 -42.941494)
		(width 0.254)
		(layer "F.Cu")
		(net "GND")
	)
	(segment
		(start 103.172768 -28.120594)
		(end 103.048308 -27.996134)
		(width 0.254)
		(layer "F.Cu")
		(net "GND")
	)
	(segment
		(start 95.873824 -39.624)
		(end 95.885 -39.624)
		(width 0.3048)
		(layer "F.Cu")
		(net "GND")
	)
	(segment
		(start 152.349962 -1.68402)
		(end 152.349962 -2.873756)
		(width 0.3048)
		(layer "F.Cu")
		(net "GND")
	)
	(segment
		(start 111.488728 -37.515546)
		(end 111.12246 -37.149278)
		(width 0.254)
		(layer "F.Cu")
		(net "GND")
	)
	(segment
		(start 95.443548 -28.135834)
		(end 95.633032 -28.135834)
		(width 0.3048)
		(layer "F.Cu")
		(net "GND")
	)
	(segment
		(start 188.949838 -1.68402)
		(end 188.949838 -2.807462)
		(width 0.254)
		(layer "F.Cu")
		(net "GND")
	)
	(segment
		(start 82.1817 -36.070032)
		(end 82.215228 -36.036504)
		(width 0.254)
		(layer "F.Cu")
		(net "GND")
	)
	(segment
		(start 51.8668 -23.495)
		(end 51.8668 -24.2062)
		(width 0.3048)
		(layer "F.Cu")
		(net "GND")
	)
	(segment
		(start 89.659968 -31.578296)
		(end 90.000582 -31.91891)
		(width 0.3048)
		(layer "F.Cu")
		(net "GND")
	)
	(segment
		(start 111.961168 -28.526994)
		(end 113.261394 -28.526994)
		(width 0.3048)
		(layer "F.Cu")
		(net "GND")
	)
	(segment
		(start 93.968062 -28.885388)
		(end 93.974412 -28.885388)
		(width 0.3048)
		(layer "F.Cu")
		(net "GND")
	)
	(segment
		(start 154.15006 -2.867152)
		(end 153.891234 -3.125978)
		(width 0.3048)
		(layer "F.Cu")
		(net "GND")
	)
	(segment
		(start 95.9612 -28.496006)
		(end 95.9612 -28.464002)
		(width 0.3048)
		(layer "F.Cu")
		(net "GND")
	)
	(segment
		(start 174.816008 -2.994406)
		(end 174.650908 -3.159506)
		(width 0.254)
		(layer "F.Cu")
		(net "GND")
	)
	(segment
		(start 95.618808 -32.664654)
		(end 95.618808 -31.902654)
		(width 0.3048)
		(layer "F.Cu")
		(net "GND")
	)
	(segment
		(start 79.2226 -47.76978)
		(end 79.26832 -47.76978)
		(width 0.254)
		(layer "F.Cu")
		(net "GND")
	)
	(segment
		(start 79.883 -61.1378)
		(end 79.6544 -60.9092)
		(width 0.3048)
		(layer "F.Cu")
		(net "GND")
	)
	(segment
		(start 103.099108 -42.941494)
		(end 103.172006 -42.941494)
		(width 0.254)
		(layer "F.Cu")
		(net "GND")
	)
	(segment
		(start 88.374728 -31.097728)
		(end 88.374728 -31.140654)
		(width 0.3048)
		(layer "F.Cu")
		(net "GND")
	)
	(segment
		(start 107.696 -66.536824)
		(end 107.696 -66.4972)
		(width 0.3048)
		(layer "F.Cu")
		(net "GND")
	)
	(segment
		(start 52.30368 -54.40934)
		(end 52.30368 -56.2737)
		(width 0.3048)
		(layer "F.Cu")
		(net "GND")
	)
	(segment
		(start 86.695788 -45.390054)
		(end 86.543642 -45.237908)
		(width 0.254)
		(layer "F.Cu")
		(net "GND")
	)
	(segment
		(start 132.249926 -8.790686)
		(end 131.9276 -8.46836)
		(width 0.3048)
		(layer "F.Cu")
		(net "GND")
	)
	(segment
		(start 98.64852 -39.200074)
		(end 98.649028 -39.200074)
		(width 0.3048)
		(layer "F.Cu")
		(net "GND")
	)
	(segment
		(start 59.2328 -39.5732)
		(end 61.7093 -39.5732)
		(width 0.3048)
		(layer "F.Cu")
		(net "GND")
	)
	(segment
		(start 84.126324 -28.57881)
		(end 84.402168 -28.854654)
		(width 0.3048)
		(layer "F.Cu")
		(net "GND")
	)
	(segment
		(start 47.6504 -36.3474)
		(end 47.5488 -36.2458)
		(width 0.508)
		(layer "F.Cu")
		(net "GND")
	)
	(segment
		(start 153.3652 -41.29405)
		(end 150.64105 -41.29405)
		(width 0.3048)
		(layer "F.Cu")
		(net "GND")
	)
	(segment
		(start 85.10651 -40.716454)
		(end 84.770468 -41.052496)
		(width 0.254)
		(layer "F.Cu")
		(net "GND")
	)
	(segment
		(start 68.307712 -29.445712)
		(end 68.307712 -28.60675)
		(width 0.3048)
		(layer "F.Cu")
		(net "GND")
	)
	(segment
		(start 79.738728 -26.042874)
		(end 80.165702 -25.6159)
		(width 0.3048)
		(layer "F.Cu")
		(net "GND")
	)
	(segment
		(start 82.885788 -36.743894)
		(end 82.641694 -36.743894)
		(width 0.254)
		(layer "F.Cu")
		(net "GND")
	)
	(segment
		(start 180.850032 -62.59322)
		(end 180.850032 -64.083692)
		(width 0.254)
		(layer "F.Cu")
		(net "GND")
	)
	(segment
		(start 97.957894 -32.673036)
		(end 97.605088 -33.025842)
		(width 0.254)
		(layer "F.Cu")
		(net "GND")
	)
	(segment
		(start 106.1466 -45.304202)
		(end 106.142536 -45.304202)
		(width 0.3048)
		(layer "F.Cu")
		(net "GND")
	)
	(segment
		(start 93.076268 -42.403268)
		(end 93.472 -42.799)
		(width 0.254)
		(layer "F.Cu")
		(net "GND")
	)
	(segment
		(start 85.171788 -44.688506)
		(end 84.845398 -45.014896)
		(width 0.3048)
		(layer "F.Cu")
		(net "GND")
	)
	(segment
		(start 104.6734 -34.4424)
		(end 104.415082 -34.4424)
		(width 0.3048)
		(layer "F.Cu")
		(net "GND")
	)
	(segment
		(start 143.8402 -63.859156)
		(end 143.8402 -63.999364)
		(width 0.254)
		(layer "F.Cu")
		(net "GND")
	)
	(segment
		(start 107.6706 -64.8208)
		(end 107.6706 -65.405)
		(width 0.3048)
		(layer "F.Cu")
		(net "GND")
	)
	(segment
		(start 73.3679 -6.213602)
		(end 73.3679 -9.1059)
		(width 0.7112)
		(layer "F.Cu")
		(net "GND")
	)
	(segment
		(start 79.6544 -60.9092)
		(end 79.6544 -60.3758)
		(width 0.3048)
		(layer "F.Cu")
		(net "GND")
	)
	(segment
		(start 79.11084 -43.707812)
		(end 79.219806 -43.598846)
		(width 0.254)
		(layer "F.Cu")
		(net "GND")
	)
	(segment
		(start 108.10113 -33.711134)
		(end 108.453428 -33.358836)
		(width 0.3048)
		(layer "F.Cu")
		(net "GND")
	)
	(segment
		(start 49.349914 -9.080754)
		(end 48.8696 -9.561068)
		(width 0.7112)
		(layer "F.Cu")
		(net "GND")
	)
	(segment
		(start 76.53528 -48.52924)
		(end 76.53528 -48.81372)
		(width 0.3048)
		(layer "F.Cu")
		(net "GND")
	)
	(segment
		(start 145.750026 -3.027172)
		(end 145.66138 -3.115818)
		(width 0.3048)
		(layer "F.Cu")
		(net "GND")
	)
	(segment
		(start 81.785968 -30.122114)
		(end 81.79054 -30.117542)
		(width 0.3048)
		(layer "F.Cu")
		(net "GND")
	)
	(segment
		(start 179.95011 -69.902324)
		(end 179.5526 -69.504814)
		(width 0.254)
		(layer "F.Cu")
		(net "GND")
	)
	(segment
		(start 141.986 -46.613572)
		(end 141.96441 -46.635162)
		(width 0.3048)
		(layer "F.Cu")
		(net "GND")
	)
	(segment
		(start 82.6389 -29.083)
		(end 82.6389 -29.252926)
		(width 0.3048)
		(layer "F.Cu")
		(net "GND")
	)
	(segment
		(start 109.711744 -41.786302)
		(end 109.779816 -41.854374)
		(width 0.254)
		(layer "F.Cu")
		(net "GND")
	)
	(segment
		(start 85.349842 -6.195568)
		(end 85.349842 -9.061958)
		(width 0.7112)
		(layer "F.Cu")
		(net "GND")
	)
	(segment
		(start 142.24 -44.04106)
		(end 142.49781 -44.29887)
		(width 0.3048)
		(layer "F.Cu")
		(net "GND")
	)
	(segment
		(start 94.651068 -35.999674)
		(end 94.651068 -36.000944)
		(width 0.3048)
		(layer "F.Cu")
		(net "GND")
	)
	(segment
		(start 104.623616 -38.968934)
		(end 104.9528 -39.298118)
		(width 0.3048)
		(layer "F.Cu")
		(net "GND")
	)
	(segment
		(start 98.298 -28.5242)
		(end 98.712528 -28.938728)
		(width 0.3048)
		(layer "F.Cu")
		(net "GND")
	)
	(segment
		(start 71.681086 -54.41696)
		(end 71.6788 -54.419246)
		(width 0.3048)
		(layer "F.Cu")
		(net "GND")
	)
	(segment
		(start 93.050868 -35.199574)
		(end 92.993972 -35.199574)
		(width 0.3048)
		(layer "F.Cu")
		(net "GND")
	)
	(segment
		(start 179.349908 -3.083306)
		(end 179.41544 -3.148838)
		(width 0.254)
		(layer "F.Cu")
		(net "GND")
	)
	(segment
		(start 127.762 -39.37)
		(end 127.2286 -39.9034)
		(width 0.3048)
		(layer "F.Cu")
		(net "GND")
	)
	(segment
		(start 174.850044 -63.935864)
		(end 174.93488 -64.0207)
		(width 0.254)
		(layer "F.Cu")
		(net "GND")
	)
	(segment
		(start 106.190542 -36.8681)
		(end 105.669842 -36.3474)
		(width 0.254)
		(layer "F.Cu")
		(net "GND")
	)
	(segment
		(start 32.258 -39.1668)
		(end 32.4612 -39.1668)
		(width 0.508)
		(layer "F.Cu")
		(net "GND")
	)
	(segment
		(start 93.848428 -42.400474)
		(end 93.472 -42.776902)
		(width 0.254)
		(layer "F.Cu")
		(net "GND")
	)
	(segment
		(start 140.64996 -63.94704)
		(end 140.58519 -64.01181)
		(width 0.254)
		(layer "F.Cu")
		(net "GND")
	)
	(segment
		(start 106.187748 -45.304202)
		(end 106.1466 -45.304202)
		(width 0.254)
		(layer "F.Cu")
		(net "GND")
	)
	(segment
		(start 134.35076 -16.01724)
		(end 133.7945 -16.01724)
		(width 0.3048)
		(layer "F.Cu")
		(net "GND")
	)
	(segment
		(start 112.207294 -36.3474)
		(end 112.213644 -36.3474)
		(width 0.254)
		(layer "F.Cu")
		(net "GND")
	)
	(segment
		(start 90.31224 -39.674038)
		(end 90.274902 -39.6367)
		(width 0.254)
		(layer "F.Cu")
		(net "GND")
	)
	(segment
		(start 70.29196 -12.827)
		(end 70.013576 -12.827)
		(width 0.3048)
		(layer "F.Cu")
		(net "GND")
	)
	(segment
		(start 171.85005 -8.603488)
		(end 171.69638 -8.449818)
		(width 0.254)
		(layer "F.Cu")
		(net "GND")
	)
	(segment
		(start 185.35015 -70.806564)
		(end 185.35015 -69.902324)
		(width 0.254)
		(layer "F.Cu")
		(net "GND")
	)
	(segment
		(start 112.392968 -31.394146)
		(end 112.392968 -31.442914)
		(width 0.254)
		(layer "F.Cu")
		(net "GND")
	)
	(segment
		(start 103.861108 -43.642534)
		(end 103.861108 -43.642026)
		(width 0.254)
		(layer "F.Cu")
		(net "GND")
	)
	(segment
		(start 86.314788 -43.403774)
		(end 86.364826 -43.403774)
		(width 0.254)
		(layer "F.Cu")
		(net "GND")
	)
	(segment
		(start 81.646268 -46.209966)
		(end 81.289398 -45.853096)
		(width 0.254)
		(layer "F.Cu")
		(net "GND")
	)
	(segment
		(start 153.406856 -53.4416)
		(end 152.461976 -54.38648)
		(width 0.3048)
		(layer "F.Cu")
		(net "GND")
	)
	(segment
		(start 79.60106 -40.535606)
		(end 79.601568 -40.536114)
		(width 0.254)
		(layer "F.Cu")
		(net "GND")
	)
	(segment
		(start 69.469 -57.277)
		(end 69.596 -57.15)
		(width 0.3048)
		(layer "F.Cu")
		(net "GND")
	)
	(segment
		(start 30.349952 -9.05002)
		(end 30.861 -9.561068)
		(width 0.7112)
		(layer "F.Cu")
		(net "GND")
	)
	(segment
		(start 107.671108 -31.750508)
		(end 107.671108 -31.724854)
		(width 0.254)
		(layer "F.Cu")
		(net "GND")
	)
	(segment
		(start 101.849428 -36.799774)
		(end 102.26675 -36.799774)
		(width 0.4064)
		(layer "F.Cu")
		(net "GND")
	)
	(segment
		(start 91.922346 -28.174696)
		(end 91.961208 -28.135834)
		(width 0.3048)
		(layer "F.Cu")
		(net "GND")
	)
	(segment
		(start 50.349912 -6.195568)
		(end 50.349912 -9.03478)
		(width 0.7112)
		(layer "F.Cu")
		(net "GND")
	)
	(segment
		(start 112.098328 -36.238434)
		(end 112.207294 -36.3474)
		(width 0.254)
		(layer "F.Cu")
		(net "GND")
	)
	(segment
		(start 153.3652 -36.79444)
		(end 152.23236 -36.79444)
		(width 0.3048)
		(layer "F.Cu")
		(net "GND")
	)
	(segment
		(start 140.119608 -53.277008)
		(end 140.270992 -53.277008)
		(width 0.3048)
		(layer "F.Cu")
		(net "GND")
	)
	(segment
		(start 176.403 -57.5818)
		(end 176.403 -58.0898)
		(width 0.3048)
		(layer "F.Cu")
		(net "GND")
	)
	(segment
		(start 106.413554 -36.8681)
		(end 106.190542 -36.8681)
		(width 0.254)
		(layer "F.Cu")
		(net "GND")
	)
	(segment
		(start 88.7984 -32.1818)
		(end 88.653874 -32.1818)
		(width 0.3048)
		(layer "F.Cu")
		(net "GND")
	)
	(segment
		(start 84.028788 -43.795188)
		(end 84.028788 -43.403774)
		(width 0.254)
		(layer "F.Cu")
		(net "GND")
	)
	(segment
		(start 106.909108 -43.642534)
		(end 107.111038 -43.844464)
		(width 0.254)
		(layer "F.Cu")
		(net "GND")
	)
	(segment
		(start 107.6706 -65.544954)
		(end 107.3658 -65.849754)
		(width 0.3048)
		(layer "F.Cu")
		(net "GND")
	)
	(segment
		(start 104.243632 -43.259502)
		(end 104.243632 -43.246294)
		(width 0.254)
		(layer "F.Cu")
		(net "GND")
	)
	(via
		(at 96.4438 -54.991)
		(size 0.4318)
		(drill 0.2032)
		(layers "F.Cu" "B.Cu")
		(net "GND")
	)
	(via
		(at 85.344 -55.8165)
		(size 0.4318)
		(drill 0.2032)
		(layers "F.Cu" "B.Cu")
		(net "GND")
	)
	(via
		(at 114.554 -65.382902)
		(size 0.508)
		(drill 0.254)
		(layers "F.Cu" "B.Cu")
		(net "GND")
	)
	(via
		(at 99.233482 -27.442668)
		(size 0.4318)
		(drill 0.2032)
		(layers "F.Cu" "B.Cu")
		(net "GND")
	)
	(via
		(at 106.552746 -35.322256)
		(size 0.4318)
		(drill 0.2032)
		(layers "F.Cu" "B.Cu")
		(net "GND")
	)
	(via
		(at 115.951 -44.4246)
		(size 0.4318)
		(drill 0.2032)
		(layers "F.Cu" "B.Cu")
		(net "GND")
	)
	(via
		(at 21.463 -58.42)
		(size 0.508)
		(drill 0.254)
		(layers "F.Cu" "B.Cu")
		(net "GND")
	)
	(via
		(at 110.491016 -36.09594)
		(size 0.4318)
		(drill 0.2032)
		(layers "F.Cu" "B.Cu")
		(net "GND")
	)
	(via
		(at 98.8568 -57.7596)
		(size 0.4318)
		(drill 0.2032)
		(layers "F.Cu" "B.Cu")
		(net "GND")
	)
	(via
		(at 91.7956 -47.6504)
		(size 0.4318)
		(drill 0.2032)
		(layers "F.Cu" "B.Cu")
		(net "GND")
	)
	(via
		(at 35.687 -46.228)
		(size 0.7112)
		(drill 0.3556)
		(layers "F.Cu" "B.Cu")
		(net "GND")
	)
	(via
		(at 90.932 -29.337)
		(size 0.4318)
		(drill 0.2032)
		(layers "F.Cu" "B.Cu")
		(net "GND")
	)
	(via
		(at 185.674 -22.352)
		(size 0.7112)
		(drill 0.3556)
		(layers "F.Cu" "B.Cu")
		(net "GND")
	)
	(via
		(at 82.2452 -48.8061)
		(size 0.4318)
		(drill 0.2032)
		(layers "F.Cu" "B.Cu")
		(net "GND")
	)
	(via
		(at 171.7548 -46.1264)
		(size 0.508)
		(drill 0.254)
		(layers "F.Cu" "B.Cu")
		(net "GND")
	)
	(via
		(at 93.6244 -23.9014)
		(size 0.4318)
		(drill 0.2032)
		(layers "F.Cu" "B.Cu")
		(net "GND")
	)
	(via
		(at 47.371 -71.374)
		(size 0.7112)
		(drill 0.4064)
		(layers "F.Cu" "B.Cu")
		(net "GND")
	)
	(via
		(at 103.12146 -36.639754)
		(size 0.4318)
		(drill 0.2032)
		(layers "F.Cu" "B.Cu")
		(net "GND")
	)
	(via
		(at 145.603468 -8.245348)
		(size 0.4318)
		(drill 0.2032)
		(layers "F.Cu" "B.Cu")
		(net "GND")
	)
	(via
		(at 188.4934 -7.139178)
		(size 0.4318)
		(drill 0.2032)
		(layers "F.Cu" "B.Cu")
		(net "GND")
	)
	(via
		(at 106.1212 -25.5016)
		(size 0.4318)
		(drill 0.2032)
		(layers "F.Cu" "B.Cu")
		(net "GND")
	)
	(via
		(at 40.868092 -9.576816)
		(size 0.508)
		(drill 0.254)
		(layers "F.Cu" "B.Cu")
		(net "GND")
	)
	(via
		(at 140.1318 -53.2892)
		(size 0.508)
		(drill 0.254)
		(layers "F.Cu" "B.Cu")
		(net "GND")
	)
	(via
		(at 39.27221 -13.843)
		(size 0.508)
		(drill 0.254)
		(layers "F.Cu" "B.Cu")
		(net "GND")
	)
	(via
		(at 162.433 -34.66846)
		(size 0.508)
		(drill 0.254)
		(layers "F.Cu" "B.Cu")
		(net "GND")
	)
	(via
		(at 95.5802 -54.2798)
		(size 0.4318)
		(drill 0.2032)
		(layers "F.Cu" "B.Cu")
		(net "GND")
	)
	(via
		(at 99.695 -62.23)
		(size 0.7112)
		(drill 0.3556)
		(layers "F.Cu" "B.Cu")
		(net "GND")
	)
	(via
		(at 179.70246 -64.08674)
		(size 0.4318)
		(drill 0.2032)
		(layers "F.Cu" "B.Cu")
		(net "GND")
	)
	(via
		(at 151.59863 -22.764496)
		(size 0.508)
		(drill 0.254)
		(layers "F.Cu" "B.Cu")
		(net "GND")
	)
	(via
		(at 205.4098 -59.4614)
		(size 0.7112)
		(drill 0.4064)
		(layers "F.Cu" "B.Cu")
		(net "GND")
	)
	(via
		(at 87.06104 -47.70374)
		(size 0.4318)
		(drill 0.2032)
		(layers "F.Cu" "B.Cu")
		(net "GND")
	)
	(via
		(at 99.568 -55.1688)
		(size 0.4318)
		(drill 0.2032)
		(layers "F.Cu" "B.Cu")
		(net "GND")
	)
	(via
		(at 88.836754 -47.559214)
		(size 0.4318)
		(drill 0.2032)
		(layers "F.Cu" "B.Cu")
		(net "GND")
	)
	(via
		(at 94.4626 -22.606)
		(size 0.4318)
		(drill 0.2032)
		(layers "F.Cu" "B.Cu")
		(net "GND")
	)
	(via
		(at 48.828198 -37.4142)
		(size 0.508)
		(drill 0.254)
		(layers "F.Cu" "B.Cu")
		(net "GND")
	)
	(via
		(at 152.1968 -36.83)
		(size 0.508)
		(drill 0.254)
		(layers "F.Cu" "B.Cu")
		(net "GND")
	)
	(via
		(at 127.508 -22.606)
		(size 0.508)
		(drill 0.254)
		(layers "F.Cu" "B.Cu")
		(net "GND")
	)
	(via
		(at 185.38444 -68.53174)
		(size 0.4318)
		(drill 0.2032)
		(layers "F.Cu" "B.Cu")
		(net "GND")
	)
	(via
		(at 2.54 -58.293)
		(size 0.508)
		(drill 0.254)
		(layers "F.Cu" "B.Cu")
		(net "GND")
	)
	(via
		(at 80.1116 -28.1432)
		(size 0.4318)
		(drill 0.2032)
		(layers "F.Cu" "B.Cu")
		(net "GND")
	)
	(via
		(at 187.579 -22.86)
		(size 0.508)
		(drill 0.254)
		(layers "F.Cu" "B.Cu")
		(net "GND")
	)
	(via
		(at 74.1934 -18.0594)
		(size 0.508)
		(drill 0.254)
		(layers "F.Cu" "B.Cu")
		(net "GND")
	)
	(via
		(at 59.743594 -48.358806)
		(size 0.7112)
		(drill 0.3556)
		(layers "F.Cu" "B.Cu")
		(net "GND")
	)
	(via
		(at 198.882 -31.242)
		(size 0.7112)
		(drill 0.4064)
		(layers "F.Cu" "B.Cu")
		(net "GND")
	)
	(via
		(at 84.795868 -45.014896)
		(size 0.4318)
		(drill 0.2032)
		(layers "F.Cu" "B.Cu")
		(net "GND")
	)
	(via
		(at 143.097504 -65.183258)
		(size 0.4318)
		(drill 0.2032)
		(layers "F.Cu" "B.Cu")
		(net "GND")
	)
	(via
		(at 41.148 -56.261)
		(size 0.508)
		(drill 0.254)
		(layers "F.Cu" "B.Cu")
		(net "GND")
	)
	(via
		(at 10.2108 -62.3062)
		(size 0.508)
		(drill 0.254)
		(layers "F.Cu" "B.Cu")
		(net "GND")
	)
	(via
		(at 195.4276 -64.1858)
		(size 0.7112)
		(drill 0.4064)
		(layers "F.Cu" "B.Cu")
		(net "GND")
	)
	(via
		(at 152.6286 -58.4708)
		(size 0.7112)
		(drill 0.4064)
		(layers "F.Cu" "B.Cu")
		(net "GND")
	)
	(via
		(at 3.302 -34.798)
		(size 0.7112)
		(drill 0.4064)
		(layers "F.Cu" "B.Cu")
		(net "GND")
	)
	(via
		(at 97.709736 -48.7553)
		(size 0.4318)
		(drill 0.2032)
		(layers "F.Cu" "B.Cu")
		(net "GND")
	)
	(via
		(at 1.9304 -68.0974)
		(size 0.508)
		(drill 0.254)
		(layers "F.Cu" "B.Cu")
		(net "GND")
	)
	(via
		(at 107.67314 -44.6278)
		(size 0.4318)
		(drill 0.2032)
		(layers "F.Cu" "B.Cu")
		(net "GND")
	)
	(via
		(at 71.501 -36.0934)
		(size 0.508)
		(drill 0.254)
		(layers "F.Cu" "B.Cu")
		(net "GND")
	)
	(via
		(at 143.77416 -3.128518)
		(size 0.4318)
		(drill 0.2032)
		(layers "F.Cu" "B.Cu")
		(net "GND")
	)
	(via
		(at 189.2554 -3.113024)
		(size 0.4318)
		(drill 0.2032)
		(layers "F.Cu" "B.Cu")
		(net "GND")
	)
	(via
		(at 83.015074 -49.814226)
		(size 0.4318)
		(drill 0.2032)
		(layers "F.Cu" "B.Cu")
		(net "GND")
	)
	(via
		(at 68.834 -9.6012)
		(size 0.508)
		(drill 0.254)
		(layers "F.Cu" "B.Cu")
		(net "GND")
	)
	(via
		(at 26.035 -42.037)
		(size 0.7112)
		(drill 0.3556)
		(layers "F.Cu" "B.Cu")
		(net "GND")
	)
	(via
		(at 98.0186 -56.5404)
		(size 0.4318)
		(drill 0.2032)
		(layers "F.Cu" "B.Cu")
		(net "GND")
	)
	(via
		(at 38.813994 -21.4122)
		(size 0.508)
		(drill 0.254)
		(layers "F.Cu" "B.Cu")
		(net "GND")
	)
	(via
		(at 152.2222 -30.29458)
		(size 0.508)
		(drill 0.254)
		(layers "F.Cu" "B.Cu")
		(net "GND")
	)
	(via
		(at 115.824 -50.9778)
		(size 0.4318)
		(drill 0.2032)
		(layers "F.Cu" "B.Cu")
		(net "GND")
	)
	(via
		(at 105.753662 -52.641246)
		(size 0.4318)
		(drill 0.2032)
		(layers "F.Cu" "B.Cu")
		(net "GND")
	)
	(via
		(at 147.9042 -64.7446)
		(size 0.4318)
		(drill 0.2032)
		(layers "F.Cu" "B.Cu")
		(net "GND")
	)
	(via
		(at 148.2598 -7.164578)
		(size 0.4318)
		(drill 0.2032)
		(layers "F.Cu" "B.Cu")
		(net "GND")
	)
	(via
		(at 83.3882 -14.7828)
		(size 0.508)
		(drill 0.254)
		(layers "F.Cu" "B.Cu")
		(net "GND")
	)
	(via
		(at 147.892516 -46.561502)
		(size 0.508)
		(drill 0.254)
		(layers "F.Cu" "B.Cu")
		(net "GND")
	)
	(via
		(at 82.6389 -29.083)
		(size 0.4318)
		(drill 0.2032)
		(layers "F.Cu" "B.Cu")
		(net "GND")
	)
	(via
		(at 183.23433 -69.3674)
		(size 0.4318)
		(drill 0.2032)
		(layers "F.Cu" "B.Cu")
		(net "GND")
	)
	(via
		(at 184.3913 -64.153542)
		(size 0.4318)
		(drill 0.2032)
		(layers "F.Cu" "B.Cu")
		(net "GND")
	)
	(via
		(at 44.642532 -13.431266)
		(size 0.508)
		(drill 0.254)
		(layers "F.Cu" "B.Cu")
		(net "GND")
	)
	(via
		(at 75.0062 -16.8148)
		(size 0.508)
		(drill 0.254)
		(layers "F.Cu" "B.Cu")
		(net "GND")
	)
	(via
		(at 84.05114 -29.21254)
		(size 0.4318)
		(drill 0.2032)
		(layers "F.Cu" "B.Cu")
		(net "GND")
	)
	(via
		(at 3.8862 -72.5932)
		(size 0.7112)
		(drill 0.4064)
		(layers "F.Cu" "B.Cu")
		(net "GND")
	)
	(via
		(at 104.1654 -40.0558)
		(size 0.4318)
		(drill 0.2032)
		(layers "F.Cu" "B.Cu")
		(net "GND")
	)
	(via
		(at 100.5078 -56.0324)
		(size 0.4318)
		(drill 0.2032)
		(layers "F.Cu" "B.Cu")
		(net "GND")
	)
	(via
		(at 72.8726 -9.6012)
		(size 0.508)
		(drill 0.254)
		(layers "F.Cu" "B.Cu")
		(net "GND")
	)
	(via
		(at 135.265668 -8.459978)
		(size 0.4318)
		(drill 0.2032)
		(layers "F.Cu" "B.Cu")
		(net "GND")
	)
	(via
		(at 166.4462 -25.6286)
		(size 0.7112)
		(drill 0.3556)
		(layers "F.Cu" "B.Cu")
		(net "GND")
	)
	(via
		(at 81.927192 -14.8082)
		(size 0.508)
		(drill 0.254)
		(layers "F.Cu" "B.Cu")
		(net "GND")
	)
	(via
		(at 104.480868 -46.996096)
		(size 0.4318)
		(drill 0.2032)
		(layers "F.Cu" "B.Cu")
		(net "GND")
	)
	(via
		(at 103.6828 -56.8452)
		(size 0.4318)
		(drill 0.2032)
		(layers "F.Cu" "B.Cu")
		(net "GND")
	)
	(via
		(at 3.683 -50.292)
		(size 0.7112)
		(drill 0.4064)
		(layers "F.Cu" "B.Cu")
		(net "GND")
	)
	(via
		(at 90.000582 -31.91891)
		(size 0.4318)
		(drill 0.2032)
		(layers "F.Cu" "B.Cu")
		(net "GND")
	)
	(via
		(at 8.8392 -50.4952)
		(size 0.508)
		(drill 0.254)
		(layers "F.Cu" "B.Cu")
		(net "GND")
	)
	(via
		(at 189.256416 -32.959802)
		(size 0.508)
		(drill 0.254)
		(layers "F.Cu" "B.Cu")
		(net "GND")
	)
	(via
		(at 101.7016 -24.13)
		(size 0.4318)
		(drill 0.2032)
		(layers "F.Cu" "B.Cu")
		(net "GND")
	)
	(via
		(at 112.649 -59.817)
		(size 0.7112)
		(drill 0.3556)
		(layers "F.Cu" "B.Cu")
		(net "GND")
	)
	(via
		(at 2.58826 -65.66154)
		(size 0.508)
		(drill 0.254)
		(layers "F.Cu" "B.Cu")
		(net "GND")
	)
	(via
		(at 136.7536 -53.213)
		(size 0.7112)
		(drill 0.3556)
		(layers "F.Cu" "B.Cu")
		(net "GND")
	)
	(via
		(at 9.779 -37.592)
		(size 0.508)
		(drill 0.254)
		(layers "F.Cu" "B.Cu")
		(net "GND")
	)
	(via
		(at 83.8708 -55.0672)
		(size 0.4318)
		(drill 0.2032)
		(layers "F.Cu" "B.Cu")
		(net "GND")
	)
	(via
		(at 205.5368 -54.2798)
		(size 0.7112)
		(drill 0.4064)
		(layers "F.Cu" "B.Cu")
		(net "GND")
	)
	(via
		(at 185.4962 -65.5066)
		(size 0.4318)
		(drill 0.2032)
		(layers "F.Cu" "B.Cu")
		(net "GND")
	)
	(via
		(at 45.858684 -48.897286)
		(size 0.508)
		(drill 0.254)
		(layers "F.Cu" "B.Cu")
		(net "GND")
	)
	(via
		(at 81.1276 -54.9148)
		(size 0.4318)
		(drill 0.2032)
		(layers "F.Cu" "B.Cu")
		(net "GND")
	)
	(via
		(at 52.832 -70.358)
		(size 0.7112)
		(drill 0.4064)
		(layers "F.Cu" "B.Cu")
		(net "GND")
	)
	(via
		(at 11.049 -35.179)
		(size 0.508)
		(drill 0.254)
		(layers "F.Cu" "B.Cu")
		(net "GND")
	)
	(via
		(at 171.70146 -3.138678)
		(size 0.4318)
		(drill 0.2032)
		(layers "F.Cu" "B.Cu")
		(net "GND")
	)
	(via
		(at 8.763 -54.864)
		(size 0.508)
		(drill 0.254)
		(layers "F.Cu" "B.Cu")
		(net "GND")
	)
	(via
		(at 60.6552 -11.5062)
		(size 0.508)
		(drill 0.254)
		(layers "F.Cu" "B.Cu")
		(net "GND")
	)
	(via
		(at 130.6322 -5.208778)
		(size 0.4318)
		(drill 0.2032)
		(layers "F.Cu" "B.Cu")
		(net "GND")
	)
	(via
		(at 5.5626 -52.1716)
		(size 0.508)
		(drill 0.254)
		(layers "F.Cu" "B.Cu")
		(net "GND")
	)
	(via
		(at 152.49144 -8.454898)
		(size 0.4318)
		(drill 0.2032)
		(layers "F.Cu" "B.Cu")
		(net "GND")
	)
	(via
		(at 107.567984 -36.576)
		(size 0.4318)
		(drill 0.2032)
		(layers "F.Cu" "B.Cu")
		(net "GND")
	)
	(via
		(at 166.1414 -56.3372)
		(size 0.508)
		(drill 0.254)
		(layers "F.Cu" "B.Cu")
		(net "GND")
	)
	(via
		(at 98.3488 -22.0726)
		(size 0.4318)
		(drill 0.2032)
		(layers "F.Cu" "B.Cu")
		(net "GND")
	)
	(via
		(at 183.23433 -64.05245)
		(size 0.4318)
		(drill 0.2032)
		(layers "F.Cu" "B.Cu")
		(net "GND")
	)
	(via
		(at 139.015724 -8.416036)
		(size 0.4318)
		(drill 0.2032)
		(layers "F.Cu" "B.Cu")
		(net "GND")
	)
	(via
		(at 61.722 -54.356)
		(size 0.7112)
		(drill 0.3556)
		(layers "F.Cu" "B.Cu")
		(net "GND")
	)
	(via
		(at 11.557 -29.972)
		(size 0.7112)
		(drill 0.4064)
		(layers "F.Cu" "B.Cu")
		(net "GND")
	)
	(via
		(at 100.7364 -28.565602)
		(size 0.4318)
		(drill 0.2032)
		(layers "F.Cu" "B.Cu")
		(net "GND")
	)
	(via
		(at 53.9496 -71.4248)
		(size 0.7112)
		(drill 0.4064)
		(layers "F.Cu" "B.Cu")
		(net "GND")
	)
	(via
		(at 103.8606 -41.265602)
		(size 0.4318)
		(drill 0.2032)
		(layers "F.Cu" "B.Cu")
		(net "GND")
	)
	(via
		(at 205.4098 -61.6966)
		(size 0.7112)
		(drill 0.4064)
		(layers "F.Cu" "B.Cu")
		(net "GND")
	)
	(via
		(at 116.7638 -33.9344)
		(size 0.4318)
		(drill 0.2032)
		(layers "F.Cu" "B.Cu")
		(net "GND")
	)
	(via
		(at 95.692468 -46.107096)
		(size 0.4318)
		(drill 0.2032)
		(layers "F.Cu" "B.Cu")
		(net "GND")
	)
	(via
		(at 130.30327 -8.232648)
		(size 0.4318)
		(drill 0.2032)
		(layers "F.Cu" "B.Cu")
		(net "GND")
	)
	(via
		(at 28.85567 -9.56691)
		(size 0.508)
		(drill 0.254)
		(layers "F.Cu" "B.Cu")
		(net "GND")
	)
	(via
		(at 10.414 -38.6842)
		(size 0.508)
		(drill 0.254)
		(layers "F.Cu" "B.Cu")
		(net "GND")
	)
	(via
		(at 144.0434 -34.544)
		(size 0.508)
		(drill 0.254)
		(layers "F.Cu" "B.Cu")
		(net "GND")
	)
	(via
		(at 20.193 -58.42)
		(size 0.508)
		(drill 0.254)
		(layers "F.Cu" "B.Cu")
		(net "GND")
	)
	(via
		(at 174.08906 -64.7446)
		(size 0.4318)
		(drill 0.2032)
		(layers "F.Cu" "B.Cu")
		(net "GND")
	)
	(via
		(at 146.6723 -67.2846)
		(size 0.4318)
		(drill 0.2032)
		(layers "F.Cu" "B.Cu")
		(net "GND")
	)
	(via
		(at 19.3548 -47.5488)
		(size 0.7112)
		(drill 0.4064)
		(layers "F.Cu" "B.Cu")
		(net "GND")
	)
	(via
		(at 132.7658 -7.621778)
		(size 0.4318)
		(drill 0.2032)
		(layers "F.Cu" "B.Cu")
		(net "GND")
	)
	(via
		(at 173.5074 -68.072)
		(size 0.4318)
		(drill 0.2032)
		(layers "F.Cu" "B.Cu")
		(net "GND")
	)
	(via
		(at 119.2784 -47.117)
		(size 0.4318)
		(drill 0.2032)
		(layers "F.Cu" "B.Cu")
		(net "GND")
	)
	(via
		(at 95.3516 -9.5758)
		(size 0.508)
		(drill 0.254)
		(layers "F.Cu" "B.Cu")
		(net "GND")
	)
	(via
		(at 23.0378 -44.9707)
		(size 0.7112)
		(drill 0.4064)
		(layers "F.Cu" "B.Cu")
		(net "GND")
	)
	(via
		(at 133.2738 -30.353)
		(size 0.508)
		(drill 0.254)
		(layers "F.Cu" "B.Cu")
		(net "GND")
	)
	(via
		(at 84.5312 -47.6758)
		(size 0.4318)
		(drill 0.2032)
		(layers "F.Cu" "B.Cu")
		(net "GND")
	)
	(via
		(at 51.181 -13.843)
		(size 0.508)
		(drill 0.254)
		(layers "F.Cu" "B.Cu")
		(net "GND")
	)
	(via
		(at 97.7011 -46.52518)
		(size 0.4318)
		(drill 0.2032)
		(layers "F.Cu" "B.Cu")
		(net "GND")
	)
	(via
		(at 141.859 -5.208778)
		(size 0.4318)
		(drill 0.2032)
		(layers "F.Cu" "B.Cu")
		(net "GND")
	)
	(via
		(at 179.5526 -69.342)
		(size 0.4318)
		(drill 0.2032)
		(layers "F.Cu" "B.Cu")
		(net "GND")
	)
	(via
		(at 93.0656 -28.4988)
		(size 0.4318)
		(drill 0.2032)
		(layers "F.Cu" "B.Cu")
		(net "GND")
	)
	(via
		(at 179.223416 -4.305046)
		(size 0.4318)
		(drill 0.2032)
		(layers "F.Cu" "B.Cu")
		(net "GND")
	)
	(via
		(at 134.4422 -68.834)
		(size 0.4318)
		(drill 0.2032)
		(layers "F.Cu" "B.Cu")
		(net "GND")
	)
	(via
		(at 101.7016 -53.1876)
		(size 0.4318)
		(drill 0.2032)
		(layers "F.Cu" "B.Cu")
		(net "GND")
	)
	(via
		(at 89.240868 -28.996132)
		(size 0.4318)
		(drill 0.2032)
		(layers "F.Cu" "B.Cu")
		(net "GND")
	)
	(via
		(at 40.15867 -24.58085)
		(size 0.508)
		(drill 0.254)
		(layers "F.Cu" "B.Cu")
		(net "GND")
	)
	(via
		(at 183.2864 -65.405)
		(size 0.4318)
		(drill 0.2032)
		(layers "F.Cu" "B.Cu")
		(net "GND")
	)
	(via
		(at 165.872414 -69.339206)
		(size 0.4318)
		(drill 0.2032)
		(layers "F.Cu" "B.Cu")
		(net "GND")
	)
	(via
		(at 34.671 -32.0802)
		(size 0.508)
		(drill 0.254)
		(layers "F.Cu" "B.Cu")
		(net "GND")
	)
	(via
		(at 82.406744 -44.62907)
		(size 0.4318)
		(drill 0.2032)
		(layers "F.Cu" "B.Cu")
		(net "GND")
	)
	(via
		(at 4.1402 -59.949842)
		(size 0.508)
		(drill 0.254)
		(layers "F.Cu" "B.Cu")
		(net "GND")
	)
	(via
		(at 92.893134 -29.344112)
		(size 0.4318)
		(drill 0.2032)
		(layers "F.Cu" "B.Cu")
		(net "GND")
	)
	(via
		(at 110.51667 -46.026578)
		(size 0.4318)
		(drill 0.2032)
		(layers "F.Cu" "B.Cu")
		(net "GND")
	)
	(via
		(at 118.7958 -62.357)
		(size 0.508)
		(drill 0.254)
		(layers "F.Cu" "B.Cu")
		(net "GND")
	)
	(via
		(at 137.6553 -8.46836)
		(size 0.4318)
		(drill 0.2032)
		(layers "F.Cu" "B.Cu")
		(net "GND")
	)
	(via
		(at 24.384 -24.892)
		(size 0.7112)
		(drill 0.3556)
		(layers "F.Cu" "B.Cu")
		(net "GND")
	)
	(via
		(at 142.748 -32.4612)
		(size 0.508)
		(drill 0.254)
		(layers "F.Cu" "B.Cu")
		(net "GND")
	)
	(via
		(at 85.217 -23.2664)
		(size 0.4318)
		(drill 0.2032)
		(layers "F.Cu" "B.Cu")
		(net "GND")
	)
	(via
		(at 89.003886 -50.73777)
		(size 0.4318)
		(drill 0.2032)
		(layers "F.Cu" "B.Cu")
		(net "GND")
	)
	(via
		(at 88.580722 -37.8714)
		(size 0.4318)
		(drill 0.2032)
		(layers "F.Cu" "B.Cu")
		(net "GND")
	)
	(via
		(at 80.15859 -52.777898)
		(size 0.4318)
		(drill 0.2032)
		(layers "F.Cu" "B.Cu")
		(net "GND")
	)
	(via
		(at 127.2286 -46.5836)
		(size 0.508)
		(drill 0.254)
		(layers "F.Cu" "B.Cu")
		(net "GND")
	)
	(via
		(at 91.768168 -46.077886)
		(size 0.4318)
		(drill 0.2032)
		(layers "F.Cu" "B.Cu")
		(net "GND")
	)
	(via
		(at 149.987 -7.748778)
		(size 0.4318)
		(drill 0.2032)
		(layers "F.Cu" "B.Cu")
		(net "GND")
	)
	(via
		(at 142.38097 -64.135762)
		(size 0.4318)
		(drill 0.2032)
		(layers "F.Cu" "B.Cu")
		(net "GND")
	)
	(via
		(at 16.8402 -65.8622)
		(size 0.508)
		(drill 0.254)
		(layers "F.Cu" "B.Cu")
		(net "GND")
	)
	(via
		(at 189.256416 -33.975802)
		(size 0.508)
		(drill 0.254)
		(layers "F.Cu" "B.Cu")
		(net "GND")
	)
	(via
		(at 109.602016 -32.019494)
		(size 0.4318)
		(drill 0.2032)
		(layers "F.Cu" "B.Cu")
		(net "GND")
	)
	(via
		(at 169.433494 -44.510706)
		(size 0.7112)
		(drill 0.4064)
		(layers "F.Cu" "B.Cu")
		(net "GND")
	)
	(via
		(at 185.293 -41.2242)
		(size 0.508)
		(drill 0.254)
		(layers "F.Cu" "B.Cu")
		(net "GND")
	)
	(via
		(at 49.784 -47.471838)
		(size 0.508)
		(drill 0.254)
		(layers "F.Cu" "B.Cu")
		(net "GND")
	)
	(via
		(at 108.4326 -40.65016)
		(size 0.4318)
		(drill 0.2032)
		(layers "F.Cu" "B.Cu")
		(net "GND")
	)
	(via
		(at 181.1274 -69.342)
		(size 0.4318)
		(drill 0.2032)
		(layers "F.Cu" "B.Cu")
		(net "GND")
	)
	(via
		(at 131.248658 -69.372988)
		(size 0.4318)
		(drill 0.2032)
		(layers "F.Cu" "B.Cu")
		(net "GND")
	)
	(via
		(at 131.934204 -3.128772)
		(size 0.4318)
		(drill 0.2032)
		(layers "F.Cu" "B.Cu")
		(net "GND")
	)
	(via
		(at 134.366 -7.621778)
		(size 0.4318)
		(drill 0.2032)
		(layers "F.Cu" "B.Cu")
		(net "GND")
	)
	(via
		(at 182.65394 -3.136138)
		(size 0.4318)
		(drill 0.2032)
		(layers "F.Cu" "B.Cu")
		(net "GND")
	)
	(via
		(at 7.4168 -30.5562)
		(size 0.508)
		(drill 0.254)
		(layers "F.Cu" "B.Cu")
		(net "GND")
	)
	(via
		(at 94.278704 -34.77006)
		(size 0.4318)
		(drill 0.2032)
		(layers "F.Cu" "B.Cu")
		(net "GND")
	)
	(via
		(at 52.245006 -28.671266)
		(size 0.508)
		(drill 0.254)
		(layers "F.Cu" "B.Cu")
		(net "GND")
	)
	(via
		(at 205.5368 -55.4736)
		(size 0.7112)
		(drill 0.4064)
		(layers "F.Cu" "B.Cu")
		(net "GND")
	)
	(via
		(at 136.4488 -8.434578)
		(size 0.4318)
		(drill 0.2032)
		(layers "F.Cu" "B.Cu")
		(net "GND")
	)
	(via
		(at 103.134668 -37.34435)
		(size 0.4318)
		(drill 0.2032)
		(layers "F.Cu" "B.Cu")
		(net "GND")
	)
	(via
		(at 77.54366 -47.710344)
		(size 0.4318)
		(drill 0.2032)
		(layers "F.Cu" "B.Cu")
		(net "GND")
	)
	(via
		(at 13.8938 -48.8188)
		(size 0.508)
		(drill 0.254)
		(layers "F.Cu" "B.Cu")
		(net "GND")
	)
	(via
		(at 76.8096 -15.113)
		(size 0.508)
		(drill 0.254)
		(layers "F.Cu" "B.Cu")
		(net "GND")
	)
	(via
		(at 26.20645 -34.0487)
		(size 0.7112)
		(drill 0.4064)
		(layers "F.Cu" "B.Cu")
		(net "GND")
	)
	(via
		(at 91.41714 -54.3814)
		(size 0.4318)
		(drill 0.2032)
		(layers "F.Cu" "B.Cu")
		(net "GND")
	)
	(via
		(at 34.6456 -15.3924)
		(size 0.508)
		(drill 0.254)
		(layers "F.Cu" "B.Cu")
		(net "GND")
	)
	(via
		(at 102.395528 -36.670996)
		(size 0.4318)
		(drill 0.2032)
		(layers "F.Cu" "B.Cu")
		(net "GND")
	)
	(via
		(at 6.35 -19.6342)
		(size 0.7112)
		(drill 0.4064)
		(layers "F.Cu" "B.Cu")
		(net "GND")
	)
	(via
		(at 147.347178 -68.707254)
		(size 0.4318)
		(drill 0.2032)
		(layers "F.Cu" "B.Cu")
		(net "GND")
	)
	(via
		(at 110.987078 -53.306218)
		(size 0.4318)
		(drill 0.2032)
		(layers "F.Cu" "B.Cu")
		(net "GND")
	)
	(via
		(at 8.8392 -51.7398)
		(size 0.508)
		(drill 0.254)
		(layers "F.Cu" "B.Cu")
		(net "GND")
	)
	(via
		(at 96.399604 -27.024584)
		(size 0.4318)
		(drill 0.2032)
		(layers "F.Cu" "B.Cu")
		(net "GND")
	)
	(via
		(at 95.7072 -45.3644)
		(size 0.4318)
		(drill 0.2032)
		(layers "F.Cu" "B.Cu")
		(net "GND")
	)
	(via
		(at 56.515 -57.785)
		(size 0.7112)
		(drill 0.3556)
		(layers "F.Cu" "B.Cu")
		(net "GND")
	)
	(via
		(at 70.8152 -9.5758)
		(size 0.508)
		(drill 0.254)
		(layers "F.Cu" "B.Cu")
		(net "GND")
	)
	(via
		(at 22.824948 -9.613646)
		(size 0.508)
		(drill 0.254)
		(layers "F.Cu" "B.Cu")
		(net "GND")
	)
	(via
		(at 137.442956 -3.125978)
		(size 0.4318)
		(drill 0.2032)
		(layers "F.Cu" "B.Cu")
		(net "GND")
	)
	(via
		(at 62.093602 -33.18637)
		(size 0.508)
		(drill 0.254)
		(layers "F.Cu" "B.Cu")
		(net "GND")
	)
	(via
		(at 141.020546 -17.7038)
		(size 0.508)
		(drill 0.254)
		(layers "F.Cu" "B.Cu")
		(net "GND")
	)
	(via
		(at 4.093972 -58.449972)
		(size 0.508)
		(drill 0.254)
		(layers "F.Cu" "B.Cu")
		(net "GND")
	)
	(via
		(at 137.3886 -64.0842)
		(size 0.4318)
		(drill 0.2032)
		(layers "F.Cu" "B.Cu")
		(net "GND")
	)
	(via
		(at 183.152796 -7.750556)
		(size 0.4318)
		(drill 0.2032)
		(layers "F.Cu" "B.Cu")
		(net "GND")
	)
	(via
		(at 78.994 -35.999674)
		(size 0.4318)
		(drill 0.2032)
		(layers "F.Cu" "B.Cu")
		(net "GND")
	)
	(via
		(at 2.589276 -61.748924)
		(size 0.508)
		(drill 0.254)
		(layers "F.Cu" "B.Cu")
		(net "GND")
	)
	(via
		(at 82.538062 -41.077388)
		(size 0.4318)
		(drill 0.2032)
		(layers "F.Cu" "B.Cu")
		(net "GND")
	)
	(via
		(at 31.0515 -61.341)
		(size 0.7112)
		(drill 0.4064)
		(layers "F.Cu" "B.Cu")
		(net "GND")
	)
	(via
		(at 83.742022 -34.144712)
		(size 0.4318)
		(drill 0.2032)
		(layers "F.Cu" "B.Cu")
		(net "GND")
	)
	(via
		(at 99.874832 -39.57066)
		(size 0.4318)
		(drill 0.2032)
		(layers "F.Cu" "B.Cu")
		(net "GND")
	)
	(via
		(at 174.117 -38.608)
		(size 0.7112)
		(drill 0.3556)
		(layers "F.Cu" "B.Cu")
		(net "GND")
	)
	(via
		(at 200.28281 -36.59124)
		(size 0.508)
		(drill 0.254)
		(layers "F.Cu" "B.Cu")
		(net "GND")
	)
	(via
		(at 88.19642 -25.44826)
		(size 0.4318)
		(drill 0.2032)
		(layers "F.Cu" "B.Cu")
		(net "GND")
	)
	(via
		(at 92.7735 -52.9844)
		(size 0.4318)
		(drill 0.2032)
		(layers "F.Cu" "B.Cu")
		(net "GND")
	)
	(via
		(at 179.41544 -3.148838)
		(size 0.4318)
		(drill 0.2032)
		(layers "F.Cu" "B.Cu")
		(net "GND")
	)
	(via
		(at 174.93488 -64.03086)
		(size 0.4318)
		(drill 0.2032)
		(layers "F.Cu" "B.Cu")
		(net "GND")
	)
	(via
		(at 178.9938 -46.6852)
		(size 0.508)
		(drill 0.254)
		(layers "F.Cu" "B.Cu")
		(net "GND")
	)
	(via
		(at 92.6084 -34.814002)
		(size 0.4318)
		(drill 0.2032)
		(layers "F.Cu" "B.Cu")
		(net "GND")
	)
	(via
		(at 26.871676 -9.573768)
		(size 0.508)
		(drill 0.254)
		(layers "F.Cu" "B.Cu")
		(net "GND")
	)
	(via
		(at 194.056 -47.752)
		(size 0.7112)
		(drill 0.4064)
		(layers "F.Cu" "B.Cu")
		(net "GND")
	)
	(via
		(at 34.671 -69.215)
		(size 0.7112)
		(drill 0.4064)
		(layers "F.Cu" "B.Cu")
		(net "GND")
	)
	(via
		(at 162.687 -13.97)
		(size 0.7112)
		(drill 0.4064)
		(layers "F.Cu" "B.Cu")
		(net "GND")
	)
	(via
		(at 112.364012 -26.974292)
		(size 0.4318)
		(drill 0.2032)
		(layers "F.Cu" "B.Cu")
		(net "GND")
	)
	(via
		(at 23.876 -33.782)
		(size 0.7112)
		(drill 0.4064)
		(layers "F.Cu" "B.Cu")
		(net "GND")
	)
	(via
		(at 77.7494 -23.0124)
		(size 0.508)
		(drill 0.254)
		(layers "F.Cu" "B.Cu")
		(net "GND")
	)
	(via
		(at 34.021014 -53.051202)
		(size 0.7112)
		(drill 0.4064)
		(layers "F.Cu" "B.Cu")
		(net "GND")
	)
	(via
		(at 60.065158 -45.556678)
		(size 0.508)
		(drill 0.254)
		(layers "F.Cu" "B.Cu")
		(net "GND")
	)
	(via
		(at 81.090008 -35.801046)
		(size 0.4318)
		(drill 0.2032)
		(layers "F.Cu" "B.Cu")
		(net "GND")
	)
	(via
		(at 90.38844 -55.03926)
		(size 0.4318)
		(drill 0.2032)
		(layers "F.Cu" "B.Cu")
		(net "GND")
	)
	(via
		(at 93.472 -42.799)
		(size 0.4318)
		(drill 0.2032)
		(layers "F.Cu" "B.Cu")
		(net "GND")
	)
	(via
		(at 91.7702 -46.863)
		(size 0.4318)
		(drill 0.2032)
		(layers "F.Cu" "B.Cu")
		(net "GND")
	)
	(via
		(at 90.274902 -39.6367)
		(size 0.4318)
		(drill 0.2032)
		(layers "F.Cu" "B.Cu")
		(net "GND")
	)
	(via
		(at 113.157 -54.737)
		(size 0.7112)
		(drill 0.3556)
		(layers "F.Cu" "B.Cu")
		(net "GND")
	)
	(via
		(at 57.518808 -37.4142)
		(size 0.508)
		(drill 0.254)
		(layers "F.Cu" "B.Cu")
		(net "GND")
	)
	(via
		(at 50.419 -21.2852)
		(size 0.508)
		(drill 0.254)
		(layers "F.Cu" "B.Cu")
		(net "GND")
	)
	(via
		(at 66.8274 -9.5758)
		(size 0.508)
		(drill 0.254)
		(layers "F.Cu" "B.Cu")
		(net "GND")
	)
	(via
		(at 81.127854 -37.935916)
		(size 0.4318)
		(drill 0.2032)
		(layers "F.Cu" "B.Cu")
		(net "GND")
	)
	(via
		(at 16.764 -28.956)
		(size 0.7112)
		(drill 0.3556)
		(layers "F.Cu" "B.Cu")
		(net "GND")
	)
	(via
		(at 135.255 -3.405378)
		(size 0.4318)
		(drill 0.2032)
		(layers "F.Cu" "B.Cu")
		(net "GND")
	)
	(via
		(at 93.274134 -31.858712)
		(size 0.4318)
		(drill 0.2032)
		(layers "F.Cu" "B.Cu")
		(net "GND")
	)
	(via
		(at 192.024 -26.924)
		(size 0.508)
		(drill 0.254)
		(layers "F.Cu" "B.Cu")
		(net "GND")
	)
	(via
		(at 184.310528 -12.5984)
		(size 0.7112)
		(drill 0.4064)
		(layers "F.Cu" "B.Cu")
		(net "GND")
	)
	(via
		(at 33.274762 -52.264564)
		(size 0.7112)
		(drill 0.4064)
		(layers "F.Cu" "B.Cu")
		(net "GND")
	)
	(via
		(at 137.03427 -67.3354)
		(size 0.4318)
		(drill 0.2032)
		(layers "F.Cu" "B.Cu")
		(net "GND")
	)
	(via
		(at 29.40304 -48.620426)
		(size 0.508)
		(drill 0.254)
		(layers "F.Cu" "B.Cu")
		(net "GND")
	)
	(via
		(at 62.992 -65.786)
		(size 0.7112)
		(drill 0.4064)
		(layers "F.Cu" "B.Cu")
		(net "GND")
	)
	(via
		(at 45.085 -53.213)
		(size 0.508)
		(drill 0.254)
		(layers "F.Cu" "B.Cu")
		(net "GND")
	)
	(via
		(at 89.154 -28.3718)
		(size 0.4318)
		(drill 0.2032)
		(layers "F.Cu" "B.Cu")
		(net "GND")
	)
	(via
		(at 48.8696 -9.561068)
		(size 0.508)
		(drill 0.254)
		(layers "F.Cu" "B.Cu")
		(net "GND")
	)
	(via
		(at 110.358428 -44.963334)
		(size 0.4318)
		(drill 0.2032)
		(layers "F.Cu" "B.Cu")
		(net "GND")
	)
	(via
		(at 157.48 -28.59405)
		(size 0.508)
		(drill 0.254)
		(layers "F.Cu" "B.Cu")
		(net "GND")
	)
	(via
		(at 177.8508 -67.2846)
		(size 0.4318)
		(drill 0.2032)
		(layers "F.Cu" "B.Cu")
		(net "GND")
	)
	(via
		(at 194.056 -50.165)
		(size 0.7112)
		(drill 0.4064)
		(layers "F.Cu" "B.Cu")
		(net "GND")
	)
	(via
		(at 90.21445 -27.485848)
		(size 0.4318)
		(drill 0.2032)
		(layers "F.Cu" "B.Cu")
		(net "GND")
	)
	(via
		(at 146.96948 -3.138678)
		(size 0.4318)
		(drill 0.2032)
		(layers "F.Cu" "B.Cu")
		(net "GND")
	)
	(via
		(at 18.923 -54.229)
		(size 0.7112)
		(drill 0.3556)
		(layers "F.Cu" "B.Cu")
		(net "GND")
	)
	(via
		(at 111.576104 -40.54983)
		(size 0.4318)
		(drill 0.2032)
		(layers "F.Cu" "B.Cu")
		(net "GND")
	)
	(via
		(at 68.1482 -36.034726)
		(size 0.508)
		(drill 0.254)
		(layers "F.Cu" "B.Cu")
		(net "GND")
	)
	(via
		(at 174.7266 -8.465058)
		(size 0.4318)
		(drill 0.2032)
		(layers "F.Cu" "B.Cu")
		(net "GND")
	)
	(via
		(at 110.241334 -25.432512)
		(size 0.4318)
		(drill 0.2032)
		(layers "F.Cu" "B.Cu")
		(net "GND")
	)
	(via
		(at 166.0144 -64.04102)
		(size 0.4318)
		(drill 0.2032)
		(layers "F.Cu" "B.Cu")
		(net "GND")
	)
	(via
		(at 180.9369 -64.17056)
		(size 0.4318)
		(drill 0.2032)
		(layers "F.Cu" "B.Cu")
		(net "GND")
	)
	(via
		(at 29.083 -34.0487)
		(size 0.7112)
		(drill 0.4064)
		(layers "F.Cu" "B.Cu")
		(net "GND")
	)
	(via
		(at 80.784192 -9.5758)
		(size 0.508)
		(drill 0.254)
		(layers "F.Cu" "B.Cu")
		(net "GND")
	)
	(via
		(at 145.4658 -69.3674)
		(size 0.4318)
		(drill 0.2032)
		(layers "F.Cu" "B.Cu")
		(net "GND")
	)
	(via
		(at 85.09 -47.117)
		(size 0.4318)
		(drill 0.2032)
		(layers "F.Cu" "B.Cu")
		(net "GND")
	)
	(via
		(at 110.605062 -47.090838)
		(size 0.4318)
		(drill 0.2032)
		(layers "F.Cu" "B.Cu")
		(net "GND")
	)
	(via
		(at 181.3814 -5.234178)
		(size 0.4318)
		(drill 0.2032)
		(layers "F.Cu" "B.Cu")
		(net "GND")
	)
	(via
		(at 87.122 -31.496)
		(size 0.4318)
		(drill 0.2032)
		(layers "F.Cu" "B.Cu")
		(net "GND")
	)
	(via
		(at 135.247888 -5.21081)
		(size 0.4318)
		(drill 0.2032)
		(layers "F.Cu" "B.Cu")
		(net "GND")
	)
	(via
		(at 163.32708 -64.69634)
		(size 0.4318)
		(drill 0.2032)
		(layers "F.Cu" "B.Cu")
		(net "GND")
	)
	(via
		(at 4.292346 -62.949836)
		(size 0.508)
		(drill 0.254)
		(layers "F.Cu" "B.Cu")
		(net "GND")
	)
	(via
		(at 175.26 -65.2272)
		(size 0.4318)
		(drill 0.2032)
		(layers "F.Cu" "B.Cu")
		(net "GND")
	)
	(via
		(at 44.8056 -44.6278)
		(size 0.508)
		(drill 0.254)
		(layers "F.Cu" "B.Cu")
		(net "GND")
	)
	(via
		(at 27.686 -58.7756)
		(size 0.508)
		(drill 0.254)
		(layers "F.Cu" "B.Cu")
		(net "GND")
	)
	(via
		(at 9.779 -35.179)
		(size 0.508)
		(drill 0.254)
		(layers "F.Cu" "B.Cu")
		(net "GND")
	)
	(via
		(at 107.280202 -39.2938)
		(size 0.4318)
		(drill 0.2032)
		(layers "F.Cu" "B.Cu")
		(net "GND")
	)
	(via
		(at 79.458566 -46.21276)
		(size 0.4318)
		(drill 0.2032)
		(layers "F.Cu" "B.Cu")
		(net "GND")
	)
	(via
		(at 187.575698 -8.405876)
		(size 0.4318)
		(drill 0.2032)
		(layers "F.Cu" "B.Cu")
		(net "GND")
	)
	(via
		(at 85.864192 -49.8475)
		(size 0.4318)
		(drill 0.2032)
		(layers "F.Cu" "B.Cu")
		(net "GND")
	)
	(via
		(at 140.664438 -5.205984)
		(size 0.4318)
		(drill 0.2032)
		(layers "F.Cu" "B.Cu")
		(net "GND")
	)
	(via
		(at 40.3098 -54.3052)
		(size 0.7112)
		(drill 0.4064)
		(layers "F.Cu" "B.Cu")
		(net "GND")
	)
	(via
		(at 187.133992 -5.157978)
		(size 0.4318)
		(drill 0.2032)
		(layers "F.Cu" "B.Cu")
		(net "GND")
	)
	(via
		(at 185.039 -7.088378)
		(size 0.4318)
		(drill 0.2032)
		(layers "F.Cu" "B.Cu")
		(net "GND")
	)
	(via
		(at 104.648 -56.388)
		(size 0.4318)
		(drill 0.2032)
		(layers "F.Cu" "B.Cu")
		(net "GND")
	)
	(via
		(at 91.3765 -52.93106)
		(size 0.4318)
		(drill 0.2032)
		(layers "F.Cu" "B.Cu")
		(net "GND")
	)
	(via
		(at 104.8131 -25.450038)
		(size 0.4318)
		(drill 0.2032)
		(layers "F.Cu" "B.Cu")
		(net "GND")
	)
	(via
		(at 87.7062 -55.0418)
		(size 0.4318)
		(drill 0.2032)
		(layers "F.Cu" "B.Cu")
		(net "GND")
	)
	(via
		(at 172.3136 -29.083)
		(size 0.7112)
		(drill 0.4064)
		(layers "F.Cu" "B.Cu")
		(net "GND")
	)
	(via
		(at 140.1572 -17.6784)
		(size 0.508)
		(drill 0.254)
		(layers "F.Cu" "B.Cu")
		(net "GND")
	)
	(via
		(at 10.795 -40.513)
		(size 0.7112)
		(drill 0.3556)
		(layers "F.Cu" "B.Cu")
		(net "GND")
	)
	(via
		(at 91.976194 -33.052512)
		(size 0.4318)
		(drill 0.2032)
		(layers "F.Cu" "B.Cu")
		(net "GND")
	)
	(via
		(at 62.865 -9.561068)
		(size 0.508)
		(drill 0.254)
		(layers "F.Cu" "B.Cu")
		(net "GND")
	)
	(via
		(at 91.425268 -28.174696)
		(size 0.4318)
		(drill 0.2032)
		(layers "F.Cu" "B.Cu")
		(net "GND")
	)
	(via
		(at 84.4042 -44.1706)
		(size 0.4318)
		(drill 0.2032)
		(layers "F.Cu" "B.Cu")
		(net "GND")
	)
	(via
		(at 13.97 -28.2702)
		(size 0.508)
		(drill 0.254)
		(layers "F.Cu" "B.Cu")
		(net "GND")
	)
	(via
		(at 25.273 -24.384)
		(size 0.7112)
		(drill 0.4064)
		(layers "F.Cu" "B.Cu")
		(net "GND")
	)
	(via
		(at 87.508842 -25.013158)
		(size 0.4318)
		(drill 0.2032)
		(layers "F.Cu" "B.Cu")
		(net "GND")
	)
	(via
		(at 93.655134 -27.566112)
		(size 0.4318)
		(drill 0.2032)
		(layers "F.Cu" "B.Cu")
		(net "GND")
	)
	(via
		(at 187.918852 -69.294502)
		(size 0.4318)
		(drill 0.2032)
		(layers "F.Cu" "B.Cu")
		(net "GND")
	)
	(via
		(at 140.826236 -69.320156)
		(size 0.4318)
		(drill 0.2032)
		(layers "F.Cu" "B.Cu")
		(net "GND")
	)
	(via
		(at 118.6434 -39.1668)
		(size 0.508)
		(drill 0.254)
		(layers "F.Cu" "B.Cu")
		(net "GND")
	)
	(via
		(at 139.573 -7.393178)
		(size 0.4318)
		(drill 0.2032)
		(layers "F.Cu" "B.Cu")
		(net "GND")
	)
	(via
		(at 74.803 -9.6266)
		(size 0.508)
		(drill 0.254)
		(layers "F.Cu" "B.Cu")
		(net "GND")
	)
	(via
		(at 187.452 -16.6878)
		(size 0.508)
		(drill 0.254)
		(layers "F.Cu" "B.Cu")
		(net "GND")
	)
	(via
		(at 35.0774 -52.8574)
		(size 0.7112)
		(drill 0.4064)
		(layers "F.Cu" "B.Cu")
		(net "GND")
	)
	(via
		(at 128.7272 -3.278378)
		(size 0.4318)
		(drill 0.2032)
		(layers "F.Cu" "B.Cu")
		(net "GND")
	)
	(via
		(at 81.6102 -22.4028)
		(size 0.7112)
		(drill 0.4064)
		(layers "F.Cu" "B.Cu")
		(net "GND")
	)
	(via
		(at 30.41904 -48.620426)
		(size 0.508)
		(drill 0.254)
		(layers "F.Cu" "B.Cu")
		(net "GND")
	)
	(via
		(at 59.309 -65.775332)
		(size 0.7112)
		(drill 0.4064)
		(layers "F.Cu" "B.Cu")
		(net "GND")
	)
	(via
		(at 65.0748 -15.0368)
		(size 0.508)
		(drill 0.254)
		(layers "F.Cu" "B.Cu")
		(net "GND")
	)
	(via
		(at 131.9276 -8.46836)
		(size 0.4318)
		(drill 0.2032)
		(layers "F.Cu" "B.Cu")
		(net "GND")
	)
	(via
		(at 92.350082 -9.561068)
		(size 0.508)
		(drill 0.254)
		(layers "F.Cu" "B.Cu")
		(net "GND")
	)
	(via
		(at 59.2709 -45.8978)
		(size 0.508)
		(drill 0.254)
		(layers "F.Cu" "B.Cu")
		(net "GND")
	)
	(via
		(at 16.383 -45.847)
		(size 0.7112)
		(drill 0.3556)
		(layers "F.Cu" "B.Cu")
		(net "GND")
	)
	(via
		(at 78.5114 -52.5272)
		(size 0.4318)
		(drill 0.2032)
		(layers "F.Cu" "B.Cu")
		(net "GND")
	)
	(via
		(at 101.4222 -42.7736)
		(size 0.4318)
		(drill 0.2032)
		(layers "F.Cu" "B.Cu")
		(net "GND")
	)
	(via
		(at 139.2936 -17.7038)
		(size 0.508)
		(drill 0.254)
		(layers "F.Cu" "B.Cu")
		(net "GND")
	)
	(via
		(at 129.8448 -65.7606)
		(size 0.4318)
		(drill 0.2032)
		(layers "F.Cu" "B.Cu")
		(net "GND")
	)
	(via
		(at 100.621592 -39.57066)
		(size 0.4318)
		(drill 0.2032)
		(layers "F.Cu" "B.Cu")
		(net "GND")
	)
	(via
		(at 134.19582 -69.37756)
		(size 0.4318)
		(drill 0.2032)
		(layers "F.Cu" "B.Cu")
		(net "GND")
	)
	(via
		(at 107.6706 -65.405)
		(size 0.508)
		(drill 0.254)
		(layers "F.Cu" "B.Cu")
		(net "GND")
	)
	(via
		(at 134.167626 -3.834384)
		(size 0.4318)
		(drill 0.2032)
		(layers "F.Cu" "B.Cu")
		(net "GND")
	)
	(via
		(at 90.6272 -48.514)
		(size 0.4318)
		(drill 0.2032)
		(layers "F.Cu" "B.Cu")
		(net "GND")
	)
	(via
		(at 41.148 -57.404)
		(size 0.508)
		(drill 0.254)
		(layers "F.Cu" "B.Cu")
		(net "GND")
	)
	(via
		(at 84.770468 -41.052496)
		(size 0.4318)
		(drill 0.2032)
		(layers "F.Cu" "B.Cu")
		(net "GND")
	)
	(via
		(at 64.77 -9.561068)
		(size 0.508)
		(drill 0.254)
		(layers "F.Cu" "B.Cu")
		(net "GND")
	)
	(via
		(at 115.8748 -30.2006)
		(size 0.4318)
		(drill 0.2032)
		(layers "F.Cu" "B.Cu")
		(net "GND")
	)
	(via
		(at 85.39226 -36.06038)
		(size 0.4318)
		(drill 0.2032)
		(layers "F.Cu" "B.Cu")
		(net "GND")
	)
	(via
		(at 79.480918 -33.89376)
		(size 0.4318)
		(drill 0.2032)
		(layers "F.Cu" "B.Cu")
		(net "GND")
	)
	(via
		(at 135.914892 -64.1604)
		(size 0.4318)
		(drill 0.2032)
		(layers "F.Cu" "B.Cu")
		(net "GND")
	)
	(via
		(at 131.3434 -67.3354)
		(size 0.4318)
		(drill 0.2032)
		(layers "F.Cu" "B.Cu")
		(net "GND")
	)
	(via
		(at 114.808 -27.178)
		(size 0.7112)
		(drill 0.3556)
		(layers "F.Cu" "B.Cu")
		(net "GND")
	)
	(via
		(at 89.3953 -54.5592)
		(size 0.4318)
		(drill 0.2032)
		(layers "F.Cu" "B.Cu")
		(net "GND")
	)
	(via
		(at 109.357668 -40.831262)
		(size 0.4318)
		(drill 0.2032)
		(layers "F.Cu" "B.Cu")
		(net "GND")
	)
	(via
		(at 154.316176 -8.46836)
		(size 0.4318)
		(drill 0.2032)
		(layers "F.Cu" "B.Cu")
		(net "GND")
	)
	(via
		(at 183.2356 -67.31)
		(size 0.4318)
		(drill 0.2032)
		(layers "F.Cu" "B.Cu")
		(net "GND")
	)
	(via
		(at 44.86656 -9.575546)
		(size 0.508)
		(drill 0.254)
		(layers "F.Cu" "B.Cu")
		(net "GND")
	)
	(via
		(at 41.3766 -38.6588)
		(size 0.508)
		(drill 0.254)
		(layers "F.Cu" "B.Cu")
		(net "GND")
	)
	(via
		(at 13.335 -24.511)
		(size 0.508)
		(drill 0.254)
		(layers "F.Cu" "B.Cu")
		(net "GND")
	)
	(via
		(at 179.705 -19.812)
		(size 0.7112)
		(drill 0.3556)
		(layers "F.Cu" "B.Cu")
		(net "GND")
	)
	(via
		(at 184.8612 -69.2912)
		(size 0.4318)
		(drill 0.2032)
		(layers "F.Cu" "B.Cu")
		(net "GND")
	)
	(via
		(at 142.1384 -69.3166)
		(size 0.4318)
		(drill 0.2032)
		(layers "F.Cu" "B.Cu")
		(net "GND")
	)
	(via
		(at 81.788 -67.1322)
		(size 0.508)
		(drill 0.254)
		(layers "F.Cu" "B.Cu")
		(net "GND")
	)
	(via
		(at 105.326688 -24.003)
		(size 0.4318)
		(drill 0.2032)
		(layers "F.Cu" "B.Cu")
		(net "GND")
	)
	(via
		(at 186.4868 -67.3354)
		(size 0.4318)
		(drill 0.2032)
		(layers "F.Cu" "B.Cu")
		(net "GND")
	)
	(via
		(at 94.7293 -55.2196)
		(size 0.4318)
		(drill 0.2032)
		(layers "F.Cu" "B.Cu")
		(net "GND")
	)
	(via
		(at 186.673998 -64.2874)
		(size 0.4318)
		(drill 0.2032)
		(layers "F.Cu" "B.Cu")
		(net "GND")
	)
	(via
		(at 106.109262 -33.355788)
		(size 0.4318)
		(drill 0.2032)
		(layers "F.Cu" "B.Cu")
		(net "GND")
	)
	(via
		(at 47.128684 -48.897286)
		(size 0.508)
		(drill 0.254)
		(layers "F.Cu" "B.Cu")
		(net "GND")
	)
	(via
		(at 42.418 -57.404)
		(size 0.508)
		(drill 0.254)
		(layers "F.Cu" "B.Cu")
		(net "GND")
	)
	(via
		(at 147.0914 -8.434578)
		(size 0.4318)
		(drill 0.2032)
		(layers "F.Cu" "B.Cu")
		(net "GND")
	)
	(via
		(at 84.37499 -39.066724)
		(size 0.4318)
		(drill 0.2032)
		(layers "F.Cu" "B.Cu")
		(net "GND")
	)
	(via
		(at 73.3298 -18.0594)
		(size 0.508)
		(drill 0.254)
		(layers "F.Cu" "B.Cu")
		(net "GND")
	)
	(via
		(at 51.0286 -44.958)
		(size 0.508)
		(drill 0.254)
		(layers "F.Cu" "B.Cu")
		(net "GND")
	)
	(via
		(at 90.256868 -36.429696)
		(size 0.4318)
		(drill 0.2032)
		(layers "F.Cu" "B.Cu")
		(net "GND")
	)
	(via
		(at 150.10765 -46.55185)
		(size 0.508)
		(drill 0.254)
		(layers "F.Cu" "B.Cu")
		(net "GND")
	)
	(via
		(at 181.61 -20.3962)
		(size 0.7112)
		(drill 0.4064)
		(layers "F.Cu" "B.Cu")
		(net "GND")
	)
	(via
		(at 44.9072 -61.3664)
		(size 0.508)
		(drill 0.254)
		(layers "F.Cu" "B.Cu")
		(net "GND")
	)
	(via
		(at 2.413 -59.4868)
		(size 0.508)
		(drill 0.254)
		(layers "F.Cu" "B.Cu")
		(net "GND")
	)
	(via
		(at 21.463 -59.69)
		(size 0.508)
		(drill 0.254)
		(layers "F.Cu" "B.Cu")
		(net "GND")
	)
	(via
		(at 97.38233 -36.399724)
		(size 0.4318)
		(drill 0.2032)
		(layers "F.Cu" "B.Cu")
		(net "GND")
	)
	(via
		(at 25.2984 -57.3278)
		(size 0.508)
		(drill 0.254)
		(layers "F.Cu" "B.Cu")
		(net "GND")
	)
	(via
		(at 138.772646 -22.736048)
		(size 0.508)
		(drill 0.254)
		(layers "F.Cu" "B.Cu")
		(net "GND")
	)
	(via
		(at 153.854912 -5.211572)
		(size 0.4318)
		(drill 0.2032)
		(layers "F.Cu" "B.Cu")
		(net "GND")
	)
	(via
		(at 50.8762 -9.561068)
		(size 0.508)
		(drill 0.254)
		(layers "F.Cu" "B.Cu")
		(net "GND")
	)
	(via
		(at 81.963514 -34.549842)
		(size 0.4318)
		(drill 0.2032)
		(layers "F.Cu" "B.Cu")
		(net "GND")
	)
	(via
		(at 93.98 -31.131002)
		(size 0.4318)
		(drill 0.2032)
		(layers "F.Cu" "B.Cu")
		(net "GND")
	)
	(via
		(at 187.198 -47.83201)
		(size 0.508)
		(drill 0.254)
		(layers "F.Cu" "B.Cu")
		(net "GND")
	)
	(via
		(at 79.145892 -14.610588)
		(size 0.508)
		(drill 0.254)
		(layers "F.Cu" "B.Cu")
		(net "GND")
	)
	(via
		(at 4.1656 -56.949848)
		(size 0.508)
		(drill 0.254)
		(layers "F.Cu" "B.Cu")
		(net "GND")
	)
	(via
		(at 79.09814 -29.99994)
		(size 0.4318)
		(drill 0.2032)
		(layers "F.Cu" "B.Cu")
		(net "GND")
	)
	(via
		(at 95.965772 -29.212032)
		(size 0.4318)
		(drill 0.2032)
		(layers "F.Cu" "B.Cu")
		(net "GND")
	)
	(via
		(at 84.022184 -37.140134)
		(size 0.4318)
		(drill 0.2032)
		(layers "F.Cu" "B.Cu")
		(net "GND")
	)
	(via
		(at 79.248 -31.1404)
		(size 0.4318)
		(drill 0.2032)
		(layers "F.Cu" "B.Cu")
		(net "GND")
	)
	(via
		(at 168.9862 -64.6938)
		(size 0.4318)
		(drill 0.2032)
		(layers "F.Cu" "B.Cu")
		(net "GND")
	)
	(via
		(at 185.3438 -37.3126)
		(size 0.7112)
		(drill 0.3556)
		(layers "F.Cu" "B.Cu")
		(net "GND")
	)
	(via
		(at 8.3312 -30.5816)
		(size 0.508)
		(drill 0.254)
		(layers "F.Cu" "B.Cu")
		(net "GND")
	)
	(via
		(at 86.17712 -32.35452)
		(size 0.4318)
		(drill 0.2032)
		(layers "F.Cu" "B.Cu")
		(net "GND")
	)
	(via
		(at 118.8212 -46.1772)
		(size 0.4318)
		(drill 0.2032)
		(layers "F.Cu" "B.Cu")
		(net "GND")
	)
	(via
		(at 130.64744 -3.153918)
		(size 0.4318)
		(drill 0.2032)
		(layers "F.Cu" "B.Cu")
		(net "GND")
	)
	(via
		(at 187.8965 -64.2112)
		(size 0.4318)
		(drill 0.2032)
		(layers "F.Cu" "B.Cu")
		(net "GND")
	)
	(via
		(at 101.460808 -34.026856)
		(size 0.4318)
		(drill 0.2032)
		(layers "F.Cu" "B.Cu")
		(net "GND")
	)
	(via
		(at 168.783 -68.58)
		(size 0.4318)
		(drill 0.2032)
		(layers "F.Cu" "B.Cu")
		(net "GND")
	)
	(via
		(at 201.29881 -37.60724)
		(size 0.508)
		(drill 0.254)
		(layers "F.Cu" "B.Cu")
		(net "GND")
	)
	(via
		(at 152.654 -5.208778)
		(size 0.4318)
		(drill 0.2032)
		(layers "F.Cu" "B.Cu")
		(net "GND")
	)
	(via
		(at 73.0758 -53.8226)
		(size 0.508)
		(drill 0.254)
		(layers "F.Cu" "B.Cu")
		(net "GND")
	)
	(via
		(at 194.056 -48.97374)
		(size 0.7112)
		(drill 0.4064)
		(layers "F.Cu" "B.Cu")
		(net "GND")
	)
	(via
		(at 189.738 -41.148)
		(size 0.508)
		(drill 0.254)
		(layers "F.Cu" "B.Cu")
		(net "GND")
	)
	(via
		(at 43.1292 -46.087792)
		(size 0.508)
		(drill 0.254)
		(layers "F.Cu" "B.Cu")
		(net "GND")
	)
	(via
		(at 52.2859 -30.01645)
		(size 0.508)
		(drill 0.254)
		(layers "F.Cu" "B.Cu")
		(net "GND")
	)
	(via
		(at 49.14519 -21.265896)
		(size 0.508)
		(drill 0.254)
		(layers "F.Cu" "B.Cu")
		(net "GND")
	)
	(via
		(at 13.335 -27.051)
		(size 0.508)
		(drill 0.254)
		(layers "F.Cu" "B.Cu")
		(net "GND")
	)
	(via
		(at 185.76036 -20.95881)
		(size 0.508)
		(drill 0.254)
		(layers "F.Cu" "B.Cu")
		(net "GND")
	)
	(via
		(at 46.863 -9.5758)
		(size 0.508)
		(drill 0.254)
		(layers "F.Cu" "B.Cu")
		(net "GND")
	)
	(via
		(at 112.7252 -62.5094)
		(size 0.7112)
		(drill 0.4064)
		(layers "F.Cu" "B.Cu")
		(net "GND")
	)
	(via
		(at 90.28684 -37.97554)
		(size 0.4318)
		(drill 0.2032)
		(layers "F.Cu" "B.Cu")
		(net "GND")
	)
	(via
		(at 197.358 -23.6474)
		(size 0.7112)
		(drill 0.4064)
		(layers "F.Cu" "B.Cu")
		(net "GND")
	)
	(via
		(at 96.647 -42.799)
		(size 0.4318)
		(drill 0.2032)
		(layers "F.Cu" "B.Cu")
		(net "GND")
	)
	(via
		(at 173.04512 -3.164078)
		(size 0.4318)
		(drill 0.2032)
		(layers "F.Cu" "B.Cu")
		(net "GND")
	)
	(via
		(at 176.657 -67.31)
		(size 0.4318)
		(drill 0.2032)
		(layers "F.Cu" "B.Cu")
		(net "GND")
	)
	(via
		(at 137.541 -59.6646)
		(size 0.508)
		(drill 0.254)
		(layers "F.Cu" "B.Cu")
		(net "GND")
	)
	(via
		(at 186.2836 -41.2242)
		(size 0.508)
		(drill 0.254)
		(layers "F.Cu" "B.Cu")
		(net "GND")
	)
	(via
		(at 133.9596 -64.0334)
		(size 0.4318)
		(drill 0.2032)
		(layers "F.Cu" "B.Cu")
		(net "GND")
	)
	(via
		(at 149.5552 -52.2986)
		(size 0.508)
		(drill 0.254)
		(layers "F.Cu" "B.Cu")
		(net "GND")
	)
	(via
		(at 74.295 -15.367)
		(size 0.508)
		(drill 0.254)
		(layers "F.Cu" "B.Cu")
		(net "GND")
	)
	(via
		(at 85.0519 -24.6126)
		(size 0.4318)
		(drill 0.2032)
		(layers "F.Cu" "B.Cu")
		(net "GND")
	)
	(via
		(at 81.287366 -46.8122)
		(size 0.4318)
		(drill 0.2032)
		(layers "F.Cu" "B.Cu")
		(net "GND")
	)
	(via
		(at 104.6734 -34.4424)
		(size 0.4318)
		(drill 0.2032)
		(layers "F.Cu" "B.Cu")
		(net "GND")
	)
	(via
		(at 103.479346 -36.210494)
		(size 0.4318)
		(drill 0.2032)
		(layers "F.Cu" "B.Cu")
		(net "GND")
	)
	(via
		(at 143.802354 -64.03721)
		(size 0.4318)
		(drill 0.2032)
		(layers "F.Cu" "B.Cu")
		(net "GND")
	)
	(via
		(at 145.66138 -3.136138)
		(size 0.4318)
		(drill 0.2032)
		(layers "F.Cu" "B.Cu")
		(net "GND")
	)
	(via
		(at 84.591144 -58.90514)
		(size 0.4318)
		(drill 0.2032)
		(layers "F.Cu" "B.Cu")
		(net "GND")
	)
	(via
		(at 95.885 -39.624)
		(size 0.4318)
		(drill 0.2032)
		(layers "F.Cu" "B.Cu")
		(net "GND")
	)
	(via
		(at 112.922812 -26.975054)
		(size 0.4318)
		(drill 0.2032)
		(layers "F.Cu" "B.Cu")
		(net "GND")
	)
	(via
		(at 39.92245 -29.327348)
		(size 0.508)
		(drill 0.254)
		(layers "F.Cu" "B.Cu")
		(net "GND")
	)
	(via
		(at 183.388 -18.923)
		(size 0.7112)
		(drill 0.4064)
		(layers "F.Cu" "B.Cu")
		(net "GND")
	)
	(via
		(at 94.309946 -49.786032)
		(size 0.4318)
		(drill 0.2032)
		(layers "F.Cu" "B.Cu")
		(net "GND")
	)
	(via
		(at 177.8762 -69.3674)
		(size 0.4318)
		(drill 0.2032)
		(layers "F.Cu" "B.Cu")
		(net "GND")
	)
	(via
		(at 43.0784 -13.462)
		(size 0.508)
		(drill 0.254)
		(layers "F.Cu" "B.Cu")
		(net "GND")
	)
	(via
		(at 133.7818 -8.434578)
		(size 0.4318)
		(drill 0.2032)
		(layers "F.Cu" "B.Cu")
		(net "GND")
	)
	(via
		(at 128.3208 -54.61)
		(size 0.7112)
		(drill 0.4064)
		(layers "F.Cu" "B.Cu")
		(net "GND")
	)
	(via
		(at 91.018868 -41.992296)
		(size 0.4318)
		(drill 0.2032)
		(layers "F.Cu" "B.Cu")
		(net "GND")
	)
	(via
		(at 4.292346 -61.449966)
		(size 0.508)
		(drill 0.254)
		(layers "F.Cu" "B.Cu")
		(net "GND")
	)
	(via
		(at 15.24 -25.781)
		(size 0.508)
		(drill 0.254)
		(layers "F.Cu" "B.Cu")
		(net "GND")
	)
	(via
		(at 177.292 -46.101)
		(size 0.508)
		(drill 0.254)
		(layers "F.Cu" "B.Cu")
		(net "GND")
	)
	(via
		(at 5.9436 -20.7137)
		(size 0.7112)
		(drill 0.4064)
		(layers "F.Cu" "B.Cu")
		(net "GND")
	)
	(via
		(at 139.065 -3.176778)
		(size 0.4318)
		(drill 0.2032)
		(layers "F.Cu" "B.Cu")
		(net "GND")
	)
	(via
		(at 170.6626 -7.799578)
		(size 0.4318)
		(drill 0.2032)
		(layers "F.Cu" "B.Cu")
		(net "GND")
	)
	(via
		(at 131.2164 -64.0588)
		(size 0.4318)
		(drill 0.2032)
		(layers "F.Cu" "B.Cu")
		(net "GND")
	)
	(via
		(at 80.9498 -52.7812)
		(size 0.4318)
		(drill 0.2032)
		(layers "F.Cu" "B.Cu")
		(net "GND")
	)
	(via
		(at 93.979238 -28.881324)
		(size 0.4318)
		(drill 0.2032)
		(layers "F.Cu" "B.Cu")
		(net "GND")
	)
	(via
		(at 91.242388 -50.2158)
		(size 0.4318)
		(drill 0.2032)
		(layers "F.Cu" "B.Cu")
		(net "GND")
	)
	(via
		(at 17.1704 -64.9732)
		(size 0.508)
		(drill 0.254)
		(layers "F.Cu" "B.Cu")
		(net "GND")
	)
	(via
		(at 84.3534 -47.1424)
		(size 0.4318)
		(drill 0.2032)
		(layers "F.Cu" "B.Cu")
		(net "GND")
	)
	(via
		(at 103.518208 -43.287696)
		(size 0.4318)
		(drill 0.2032)
		(layers "F.Cu" "B.Cu")
		(net "GND")
	)
	(via
		(at 42.545 -17.272)
		(size 0.508)
		(drill 0.254)
		(layers "F.Cu" "B.Cu")
		(net "GND")
	)
	(via
		(at 50.0126 -17.4498)
		(size 0.508)
		(drill 0.254)
		(layers "F.Cu" "B.Cu")
		(net "GND")
	)
	(via
		(at 99.841558 -42.78757)
		(size 0.4318)
		(drill 0.2032)
		(layers "F.Cu" "B.Cu")
		(net "GND")
	)
	(via
		(at 10.414 -36.3982)
		(size 0.508)
		(drill 0.254)
		(layers "F.Cu" "B.Cu")
		(net "GND")
	)
	(via
		(at 186.182 -54.61)
		(size 0.7112)
		(drill 0.3556)
		(layers "F.Cu" "B.Cu")
		(net "GND")
	)
	(via
		(at 81.361534 -33.154112)
		(size 0.4318)
		(drill 0.2032)
		(layers "F.Cu" "B.Cu")
		(net "GND")
	)
	(via
		(at 155.1432 -3.760978)
		(size 0.4318)
		(drill 0.2032)
		(layers "F.Cu" "B.Cu")
		(net "GND")
	)
	(via
		(at 116.7892 -32.0548)
		(size 0.4318)
		(drill 0.2032)
		(layers "F.Cu" "B.Cu")
		(net "GND")
	)
	(via
		(at 111.805212 -26.9748)
		(size 0.4318)
		(drill 0.2032)
		(layers "F.Cu" "B.Cu")
		(net "GND")
	)
	(via
		(at 115.8748 -32.9184)
		(size 0.4318)
		(drill 0.2032)
		(layers "F.Cu" "B.Cu")
		(net "GND")
	)
	(via
		(at 205.4098 -60.5282)
		(size 0.7112)
		(drill 0.4064)
		(layers "F.Cu" "B.Cu")
		(net "GND")
	)
	(via
		(at 141.884146 -17.7038)
		(size 0.508)
		(drill 0.254)
		(layers "F.Cu" "B.Cu")
		(net "GND")
	)
	(via
		(at 121.158 -39.1287)
		(size 0.508)
		(drill 0.254)
		(layers "F.Cu" "B.Cu")
		(net "GND")
	)
	(via
		(at 4.3942 -55.449978)
		(size 0.508)
		(drill 0.254)
		(layers "F.Cu" "B.Cu")
		(net "GND")
	)
	(via
		(at 12.319 -37.592)
		(size 0.508)
		(drill 0.254)
		(layers "F.Cu" "B.Cu")
		(net "GND")
	)
	(via
		(at 182.051198 -64.056006)
		(size 0.4318)
		(drill 0.2032)
		(layers "F.Cu" "B.Cu")
		(net "GND")
	)
	(via
		(at 173.863 -3.938778)
		(size 0.4318)
		(drill 0.2032)
		(layers "F.Cu" "B.Cu")
		(net "GND")
	)
	(via
		(at 145.3134 -34.544)
		(size 0.508)
		(drill 0.254)
		(layers "F.Cu" "B.Cu")
		(net "GND")
	)
	(via
		(at 68.29933 -27.2669)
		(size 0.508)
		(drill 0.254)
		(layers "F.Cu" "B.Cu")
		(net "GND")
	)
	(via
		(at 179.324 -68.707)
		(size 0.4318)
		(drill 0.2032)
		(layers "F.Cu" "B.Cu")
		(net "GND")
	)
	(via
		(at 145.3388 -7.291578)
		(size 0.4318)
		(drill 0.2032)
		(layers "F.Cu" "B.Cu")
		(net "GND")
	)
	(via
		(at 112.974882 -7.226554)
		(size 0.508)
		(drill 0.254)
		(layers "F.Cu" "B.Cu")
		(net "GND")
	)
	(via
		(at 177.673762 -3.170428)
		(size 0.4318)
		(drill 0.2032)
		(layers "F.Cu" "B.Cu")
		(net "GND")
	)
	(via
		(at 83.536028 -18.197322)
		(size 0.508)
		(drill 0.254)
		(layers "F.Cu" "B.Cu")
		(net "GND")
	)
	(via
		(at 85.76818 -54.23408)
		(size 0.4318)
		(drill 0.2032)
		(layers "F.Cu" "B.Cu")
		(net "GND")
	)
	(via
		(at 137.143998 -69.339206)
		(size 0.4318)
		(drill 0.2032)
		(layers "F.Cu" "B.Cu")
		(net "GND")
	)
	(via
		(at 69.7738 -56.4134)
		(size 0.508)
		(drill 0.254)
		(layers "F.Cu" "B.Cu")
		(net "GND")
	)
	(via
		(at 51.5874 -64.2366)
		(size 0.7112)
		(drill 0.4064)
		(layers "F.Cu" "B.Cu")
		(net "GND")
	)
	(via
		(at 204.216 -21.971)
		(size 0.7112)
		(drill 0.3556)
		(layers "F.Cu" "B.Cu")
		(net "GND")
	)
	(via
		(at 180.546502 -7.314184)
		(size 0.4318)
		(drill 0.2032)
		(layers "F.Cu" "B.Cu")
		(net "GND")
	)
	(via
		(at 205.5368 -53.213)
		(size 0.7112)
		(drill 0.4064)
		(layers "F.Cu" "B.Cu")
		(net "GND")
	)
	(via
		(at 193.9544 -42.672)
		(size 0.7112)
		(drill 0.4064)
		(layers "F.Cu" "B.Cu")
		(net "GND")
	)
	(via
		(at 80.695292 -38.686994)
		(size 0.4318)
		(drill 0.2032)
		(layers "F.Cu" "B.Cu")
		(net "GND")
	)
	(via
		(at 105.5878 -55.6768)
		(size 0.4318)
		(drill 0.2032)
		(layers "F.Cu" "B.Cu")
		(net "GND")
	)
	(via
		(at 86.3092 -52.6796)
		(size 0.4318)
		(drill 0.2032)
		(layers "F.Cu" "B.Cu")
		(net "GND")
	)
	(via
		(at 68.522088 -47.821596)
		(size 0.508)
		(drill 0.254)
		(layers "F.Cu" "B.Cu")
		(net "GND")
	)
	(via
		(at 21.971 -45.085)
		(size 0.7112)
		(drill 0.4064)
		(layers "F.Cu" "B.Cu")
		(net "GND")
	)
	(via
		(at 132.584698 -67.3354)
		(size 0.4318)
		(drill 0.2032)
		(layers "F.Cu" "B.Cu")
		(net "GND")
	)
	(via
		(at 31.0515 -58.1025)
		(size 0.7112)
		(drill 0.4064)
		(layers "F.Cu" "B.Cu")
		(net "GND")
	)
	(via
		(at 3.302 -35.941)
		(size 0.7112)
		(drill 0.4064)
		(layers "F.Cu" "B.Cu")
		(net "GND")
	)
	(via
		(at 3.6576 -24.892)
		(size 0.7112)
		(drill 0.4064)
		(layers "F.Cu" "B.Cu")
		(net "GND")
	)
	(via
		(at 193.3702 -24.3078)
		(size 0.7112)
		(drill 0.4064)
		(layers "F.Cu" "B.Cu")
		(net "GND")
	)
	(via
		(at 205.867 -48.8442)
		(size 0.7112)
		(drill 0.4064)
		(layers "F.Cu" "B.Cu")
		(net "GND")
	)
	(via
		(at 100.475542 -44.5516)
		(size 0.4318)
		(drill 0.2032)
		(layers "F.Cu" "B.Cu")
		(net "GND")
	)
	(via
		(at 172.8724 -67.31)
		(size 0.4318)
		(drill 0.2032)
		(layers "F.Cu" "B.Cu")
		(net "GND")
	)
	(via
		(at 58.98515 -49.09185)
		(size 0.508)
		(drill 0.254)
		(layers "F.Cu" "B.Cu")
		(net "GND")
	)
	(via
		(at 14.6304 -54.4068)
		(size 0.508)
		(drill 0.254)
		(layers "F.Cu" "B.Cu")
		(net "GND")
	)
	(via
		(at 82.242406 -47.781718)
		(size 0.4318)
		(drill 0.2032)
		(layers "F.Cu" "B.Cu")
		(net "GND")
	)
	(via
		(at 38.27018 -28.4734)
		(size 0.508)
		(drill 0.254)
		(layers "F.Cu" "B.Cu")
		(net "GND")
	)
	(via
		(at 131.984242 -5.196078)
		(size 0.4318)
		(drill 0.2032)
		(layers "F.Cu" "B.Cu")
		(net "GND")
	)
	(via
		(at 82.931 -47.7266)
		(size 0.4318)
		(drill 0.2032)
		(layers "F.Cu" "B.Cu")
		(net "GND")
	)
	(via
		(at 80.107536 -42.350182)
		(size 0.4318)
		(drill 0.2032)
		(layers "F.Cu" "B.Cu")
		(net "GND")
	)
	(via
		(at 164.719 -41.3004)
		(size 0.508)
		(drill 0.254)
		(layers "F.Cu" "B.Cu")
		(net "GND")
	)
	(via
		(at 118.6688 -1.1176)
		(size 0.7112)
		(drill 0.4064)
		(layers "F.Cu" "B.Cu")
		(net "GND")
	)
	(via
		(at 21.717 -19.05)
		(size 0.7112)
		(drill 0.3556)
		(layers "F.Cu" "B.Cu")
		(net "GND")
	)
	(via
		(at 10.2616 -55.1434)
		(size 0.508)
		(drill 0.254)
		(layers "F.Cu" "B.Cu")
		(net "GND")
	)
	(via
		(at 82.1817 -36.094416)
		(size 0.4318)
		(drill 0.2032)
		(layers "F.Cu" "B.Cu")
		(net "GND")
	)
	(via
		(at 174.0916 -7.189978)
		(size 0.4318)
		(drill 0.2032)
		(layers "F.Cu" "B.Cu")
		(net "GND")
	)
	(via
		(at 197.739 -27.178)
		(size 0.7112)
		(drill 0.4064)
		(layers "F.Cu" "B.Cu")
		(net "GND")
	)
	(via
		(at 67.104006 -24.956008)
		(size 0.508)
		(drill 0.254)
		(layers "F.Cu" "B.Cu")
		(net "GND")
	)
	(via
		(at 79.2226 -47.76978)
		(size 0.4318)
		(drill 0.2032)
		(layers "F.Cu" "B.Cu")
		(net "GND")
	)
	(via
		(at 166.403782 -14.181582)
		(size 0.7112)
		(drill 0.4064)
		(layers "F.Cu" "B.Cu")
		(net "GND")
	)
	(via
		(at 58.816748 -36.532058)
		(size 0.508)
		(drill 0.254)
		(layers "F.Cu" "B.Cu")
		(net "GND")
	)
	(via
		(at 101.219 -52.832)
		(size 0.4318)
		(drill 0.2032)
		(layers "F.Cu" "B.Cu")
		(net "GND")
	)
	(via
		(at 12.7 -25.781)
		(size 0.508)
		(drill 0.254)
		(layers "F.Cu" "B.Cu")
		(net "GND")
	)
	(via
		(at 10.3378 -56.896)
		(size 0.508)
		(drill 0.254)
		(layers "F.Cu" "B.Cu")
		(net "GND")
	)
	(via
		(at 128.651 -8.332978)
		(size 0.4318)
		(drill 0.2032)
		(layers "F.Cu" "B.Cu")
		(net "GND")
	)
	(via
		(at 36.4998 -13.843762)
		(size 0.508)
		(drill 0.254)
		(layers "F.Cu" "B.Cu")
		(net "GND")
	)
	(via
		(at 88.9 -45.1358)
		(size 0.4318)
		(drill 0.2032)
		(layers "F.Cu" "B.Cu")
		(net "GND")
	)
	(via
		(at 103.672132 -45.381164)
		(size 0.4318)
		(drill 0.2032)
		(layers "F.Cu" "B.Cu")
		(net "GND")
	)
	(via
		(at 30.607 -35.306)
		(size 0.508)
		(drill 0.254)
		(layers "F.Cu" "B.Cu")
		(net "GND")
	)
	(via
		(at 90.861134 -24.1554)
		(size 0.4318)
		(drill 0.2032)
		(layers "F.Cu" "B.Cu")
		(net "GND")
	)
	(via
		(at 142.40129 -8.449056)
		(size 0.4318)
		(drill 0.2032)
		(layers "F.Cu" "B.Cu")
		(net "GND")
	)
	(via
		(at 87.757 -54.102)
		(size 0.4318)
		(drill 0.2032)
		(layers "F.Cu" "B.Cu")
		(net "GND")
	)
	(via
		(at 93.248734 -32.671512)
		(size 0.4318)
		(drill 0.2032)
		(layers "F.Cu" "B.Cu")
		(net "GND")
	)
	(via
		(at 84.4804 -25.7556)
		(size 0.4318)
		(drill 0.2032)
		(layers "F.Cu" "B.Cu")
		(net "GND")
	)
	(via
		(at 92.0496 -67.2846)
		(size 0.508)
		(drill 0.254)
		(layers "F.Cu" "B.Cu")
		(net "GND")
	)
	(via
		(at 4.292346 -64.44996)
		(size 0.508)
		(drill 0.254)
		(layers "F.Cu" "B.Cu")
		(net "GND")
	)
	(via
		(at 109.202982 -50.109882)
		(size 0.4318)
		(drill 0.2032)
		(layers "F.Cu" "B.Cu")
		(net "GND")
	)
	(via
		(at 13.97 -25.781)
		(size 0.508)
		(drill 0.254)
		(layers "F.Cu" "B.Cu")
		(net "GND")
	)
	(via
		(at 82.043778 -32.428688)
		(size 0.4318)
		(drill 0.2032)
		(layers "F.Cu" "B.Cu")
		(net "GND")
	)
	(via
		(at 4.394454 -53.949854)
		(size 0.508)
		(drill 0.254)
		(layers "F.Cu" "B.Cu")
		(net "GND")
	)
	(via
		(at 140.64488 -3.123438)
		(size 0.4318)
		(drill 0.2032)
		(layers "F.Cu" "B.Cu")
		(net "GND")
	)
	(via
		(at 38.227 -46.482)
		(size 0.508)
		(drill 0.254)
		(layers "F.Cu" "B.Cu")
		(net "GND")
	)
	(via
		(at 107.945428 -32.131)
		(size 0.4318)
		(drill 0.2032)
		(layers "F.Cu" "B.Cu")
		(net "GND")
	)
	(via
		(at 69.596 -14.1732)
		(size 0.508)
		(drill 0.254)
		(layers "F.Cu" "B.Cu")
		(net "GND")
	)
	(via
		(at 56.862472 -9.572244)
		(size 0.508)
		(drill 0.254)
		(layers "F.Cu" "B.Cu")
		(net "GND")
	)
	(via
		(at 173.9138 -45.6692)
		(size 0.508)
		(drill 0.254)
		(layers "F.Cu" "B.Cu")
		(net "GND")
	)
	(via
		(at 105.5878 -36.3474)
		(size 0.4318)
		(drill 0.2032)
		(layers "F.Cu" "B.Cu")
		(net "GND")
	)
	(via
		(at 100.9396 -60.8838)
		(size 0.508)
		(drill 0.254)
		(layers "F.Cu" "B.Cu")
		(net "GND")
	)
	(via
		(at 15.24 -28.2702)
		(size 0.508)
		(drill 0.254)
		(layers "F.Cu" "B.Cu")
		(net "GND")
	)
	(via
		(at 109.3724 -41.786302)
		(size 0.4318)
		(drill 0.2032)
		(layers "F.Cu" "B.Cu")
		(net "GND")
	)
	(via
		(at 10.287 -32.4358)
		(size 0.508)
		(drill 0.254)
		(layers "F.Cu" "B.Cu")
		(net "GND")
	)
	(via
		(at 31.75 -45.212)
		(size 0.508)
		(drill 0.254)
		(layers "F.Cu" "B.Cu")
		(net "GND")
	)
	(via
		(at 87.503 -23.876)
		(size 0.4318)
		(drill 0.2032)
		(layers "F.Cu" "B.Cu")
		(net "GND")
	)
	(via
		(at 93.4974 -41.1988)
		(size 0.4318)
		(drill 0.2032)
		(layers "F.Cu" "B.Cu")
		(net "GND")
	)
	(via
		(at 205.5114 -58.0644)
		(size 0.7112)
		(drill 0.4064)
		(layers "F.Cu" "B.Cu")
		(net "GND")
	)
	(via
		(at 42.872914 -9.573006)
		(size 0.508)
		(drill 0.254)
		(layers "F.Cu" "B.Cu")
		(net "GND")
	)
	(via
		(at 25.273 -23.241)
		(size 0.7112)
		(drill 0.4064)
		(layers "F.Cu" "B.Cu")
		(net "GND")
	)
	(via
		(at 38.884352 -9.563862)
		(size 0.508)
		(drill 0.254)
		(layers "F.Cu" "B.Cu")
		(net "GND")
	)
	(via
		(at 89.6874 -14.262354)
		(size 0.7112)
		(drill 0.4064)
		(layers "F.Cu" "B.Cu")
		(net "GND")
	)
	(via
		(at 97.147634 -50.760122)
		(size 0.4318)
		(drill 0.2032)
		(layers "F.Cu" "B.Cu")
		(net "GND")
	)
	(via
		(at 1.27 -69.85)
		(size 0.7112)
		(drill 0.4064)
		(layers "F.Cu" "B.Cu")
		(net "GND")
	)
	(via
		(at 3.556 -26.543)
		(size 0.7112)
		(drill 0.4064)
		(layers "F.Cu" "B.Cu")
		(net "GND")
	)
	(via
		(at 205.6638 -72.6186)
		(size 0.7112)
		(drill 0.4064)
		(layers "F.Cu" "B.Cu")
		(net "GND")
	)
	(via
		(at 97.3963 -22.0726)
		(size 0.4318)
		(drill 0.2032)
		(layers "F.Cu" "B.Cu")
		(net "GND")
	)
	(via
		(at 107.2007 -24.0792)
		(size 0.4318)
		(drill 0.2032)
		(layers "F.Cu" "B.Cu")
		(net "GND")
	)
	(via
		(at 163.576 -19.558)
		(size 0.7112)
		(drill 0.3556)
		(layers "F.Cu" "B.Cu")
		(net "GND")
	)
	(via
		(at 205.5114 -56.9976)
		(size 0.7112)
		(drill 0.4064)
		(layers "F.Cu" "B.Cu")
		(net "GND")
	)
	(via
		(at 142.1638 -67.2846)
		(size 0.4318)
		(drill 0.2032)
		(layers "F.Cu" "B.Cu")
		(net "GND")
	)
	(via
		(at 179.617878 -8.466582)
		(size 0.4318)
		(drill 0.2032)
		(layers "F.Cu" "B.Cu")
		(net "GND")
	)
	(via
		(at 79.1464 -28.1432)
		(size 0.4318)
		(drill 0.2032)
		(layers "F.Cu" "B.Cu")
		(net "GND")
	)
	(via
		(at 47.371 -70.231)
		(size 0.7112)
		(drill 0.4064)
		(layers "F.Cu" "B.Cu")
		(net "GND")
	)
	(via
		(at 143.764 -4.192778)
		(size 0.4318)
		(drill 0.2032)
		(layers "F.Cu" "B.Cu")
		(net "GND")
	)
	(via
		(at 104.243632 -43.246294)
		(size 0.4318)
		(drill 0.2032)
		(layers "F.Cu" "B.Cu")
		(net "GND")
	)
	(via
		(at 84.04098 -33.15716)
		(size 0.4318)
		(drill 0.2032)
		(layers "F.Cu" "B.Cu")
		(net "GND")
	)
	(via
		(at 165.284404 -31.933896)
		(size 0.7112)
		(drill 0.4064)
		(layers "F.Cu" "B.Cu")
		(net "GND")
	)
	(via
		(at 22.7076 -14.7828)
		(size 0.508)
		(drill 0.254)
		(layers "F.Cu" "B.Cu")
		(net "GND")
	)
	(via
		(at 57.912 -65.786)
		(size 0.7112)
		(drill 0.4064)
		(layers "F.Cu" "B.Cu")
		(net "GND")
	)
	(via
		(at 182.68188 -5.220462)
		(size 0.4318)
		(drill 0.2032)
		(layers "F.Cu" "B.Cu")
		(net "GND")
	)
	(via
		(at 84.95538 -41.84904)
		(size 0.4318)
		(drill 0.2032)
		(layers "F.Cu" "B.Cu")
		(net "GND")
	)
	(via
		(at 86.487 -24.257)
		(size 0.7112)
		(drill 0.3556)
		(layers "F.Cu" "B.Cu")
		(net "GND")
	)
	(via
		(at 110.4138 -33.4772)
		(size 0.4318)
		(drill 0.2032)
		(layers "F.Cu" "B.Cu")
		(net "GND")
	)
	(via
		(at 149.5552 -36.83)
		(size 0.508)
		(drill 0.254)
		(layers "F.Cu" "B.Cu")
		(net "GND")
	)
	(via
		(at 147.0152 -64.0588)
		(size 0.4318)
		(drill 0.2032)
		(layers "F.Cu" "B.Cu")
		(net "GND")
	)
	(via
		(at 42.418 -56.261)
		(size 0.508)
		(drill 0.254)
		(layers "F.Cu" "B.Cu")
		(net "GND")
	)
	(via
		(at 78.867 -49.6824)
		(size 0.4318)
		(drill 0.2032)
		(layers "F.Cu" "B.Cu")
		(net "GND")
	)
	(via
		(at 205.4098 -62.7634)
		(size 0.7112)
		(drill 0.4064)
		(layers "F.Cu" "B.Cu")
		(net "GND")
	)
	(via
		(at 92.9132 -67.2846)
		(size 0.508)
		(drill 0.254)
		(layers "F.Cu" "B.Cu")
		(net "GND")
	)
	(via
		(at 148.7297 -8.46836)
		(size 0.4318)
		(drill 0.2032)
		(layers "F.Cu" "B.Cu")
		(net "GND")
	)
	(via
		(at 62.865 -15.24)
		(size 0.508)
		(drill 0.254)
		(layers "F.Cu" "B.Cu")
		(net "GND")
	)
	(via
		(at 187.2742 -3.125978)
		(size 0.4318)
		(drill 0.2032)
		(layers "F.Cu" "B.Cu")
		(net "GND")
	)
	(via
		(at 76.53528 -48.52924)
		(size 0.4318)
		(drill 0.2032)
		(layers "F.Cu" "B.Cu")
		(net "GND")
	)
	(via
		(at 97.9805 -32.643318)
		(size 0.4318)
		(drill 0.2032)
		(layers "F.Cu" "B.Cu")
		(net "GND")
	)
	(via
		(at 54.243732 -25.019)
		(size 0.508)
		(drill 0.254)
		(layers "F.Cu" "B.Cu")
		(net "GND")
	)
	(via
		(at 88.0364 -30.7594)
		(size 0.4318)
		(drill 0.2032)
		(layers "F.Cu" "B.Cu")
		(net "GND")
	)
	(via
		(at 176.3268 -3.430778)
		(size 0.4318)
		(drill 0.2032)
		(layers "F.Cu" "B.Cu")
		(net "GND")
	)
	(via
		(at 188.240416 -33.975802)
		(size 0.508)
		(drill 0.254)
		(layers "F.Cu" "B.Cu")
		(net "GND")
	)
	(via
		(at 106.11739 -41.305988)
		(size 0.4318)
		(drill 0.2032)
		(layers "F.Cu" "B.Cu")
		(net "GND")
	)
	(via
		(at 145.3261 -64.0588)
		(size 0.4318)
		(drill 0.2032)
		(layers "F.Cu" "B.Cu")
		(net "GND")
	)
	(via
		(at 89.743534 -45.752512)
		(size 0.4318)
		(drill 0.2032)
		(layers "F.Cu" "B.Cu")
		(net "GND")
	)
	(via
		(at 193.1416 -22.5298)
		(size 0.7112)
		(drill 0.4064)
		(layers "F.Cu" "B.Cu")
		(net "GND")
	)
	(via
		(at 86.32825 -45.034962)
		(size 0.4318)
		(drill 0.2032)
		(layers "F.Cu" "B.Cu")
		(net "GND")
	)
	(via
		(at 81.6356 -60.3758)
		(size 0.4318)
		(drill 0.2032)
		(layers "F.Cu" "B.Cu")
		(net "GND")
	)
	(via
		(at 122.8852 -39.1287)
		(size 0.508)
		(drill 0.254)
		(layers "F.Cu" "B.Cu")
		(net "GND")
	)
	(via
		(at 84.7598 -9.652)
		(size 0.508)
		(drill 0.254)
		(layers "F.Cu" "B.Cu")
		(net "GND")
	)
	(via
		(at 22.733 -58.42)
		(size 0.508)
		(drill 0.254)
		(layers "F.Cu" "B.Cu")
		(net "GND")
	)
	(via
		(at 177.7492 -64.06642)
		(size 0.4318)
		(drill 0.2032)
		(layers "F.Cu" "B.Cu")
		(net "GND")
	)
	(via
		(at 138.557 -64.1604)
		(size 0.4318)
		(drill 0.2032)
		(layers "F.Cu" "B.Cu")
		(net "GND")
	)
	(via
		(at 141.845792 -3.151378)
		(size 0.4318)
		(drill 0.2032)
		(layers "F.Cu" "B.Cu")
		(net "GND")
	)
	(via
		(at 18.322798 -53.400198)
		(size 0.508)
		(drill 0.254)
		(layers "F.Cu" "B.Cu")
		(net "GND")
	)
	(via
		(at 76.8604 -9.6012)
		(size 0.508)
		(drill 0.254)
		(layers "F.Cu" "B.Cu")
		(net "GND")
	)
	(via
		(at 12.319 -35.179)
		(size 0.508)
		(drill 0.254)
		(layers "F.Cu" "B.Cu")
		(net "GND")
	)
	(via
		(at 98.90252 -33.0454)
		(size 0.4318)
		(drill 0.2032)
		(layers "F.Cu" "B.Cu")
		(net "GND")
	)
	(via
		(at 39.878 -42.975276)
		(size 0.508)
		(drill 0.254)
		(layers "F.Cu" "B.Cu")
		(net "GND")
	)
	(via
		(at 135.8138 -67.3354)
		(size 0.4318)
		(drill 0.2032)
		(layers "F.Cu" "B.Cu")
		(net "GND")
	)
	(via
		(at 11.684 -38.6842)
		(size 0.508)
		(drill 0.254)
		(layers "F.Cu" "B.Cu")
		(net "GND")
	)
	(via
		(at 9.5504 -54.0258)
		(size 0.508)
		(drill 0.254)
		(layers "F.Cu" "B.Cu")
		(net "GND")
	)
	(via
		(at 91.059 -34.798)
		(size 0.4318)
		(drill 0.2032)
		(layers "F.Cu" "B.Cu")
		(net "GND")
	)
	(via
		(at 10.922 -55.88)
		(size 0.7112)
		(drill 0.3556)
		(layers "F.Cu" "B.Cu")
		(net "GND")
	)
	(via
		(at 113.1062 -69.6976)
		(size 0.508)
		(drill 0.254)
		(layers "F.Cu" "B.Cu")
		(net "GND")
	)
	(via
		(at 96.393 -22.0726)
		(size 0.4318)
		(drill 0.2032)
		(layers "F.Cu" "B.Cu")
		(net "GND")
	)
	(via
		(at 82.3214 -52.832)
		(size 0.4318)
		(drill 0.2032)
		(layers "F.Cu" "B.Cu")
		(net "GND")
	)
	(via
		(at 142.7734 -34.544)
		(size 0.508)
		(drill 0.254)
		(layers "F.Cu" "B.Cu")
		(net "GND")
	)
	(via
		(at 81.265268 -45.853096)
		(size 0.4318)
		(drill 0.2032)
		(layers "F.Cu" "B.Cu")
		(net "GND")
	)
	(via
		(at 95.7326 -49.9364)
		(size 0.4318)
		(drill 0.2032)
		(layers "F.Cu" "B.Cu")
		(net "GND")
	)
	(via
		(at 138.9126 -69.3674)
		(size 0.4318)
		(drill 0.2032)
		(layers "F.Cu" "B.Cu")
		(net "GND")
	)
	(via
		(at 89.1032 -35.1282)
		(size 0.4318)
		(drill 0.2032)
		(layers "F.Cu" "B.Cu")
		(net "GND")
	)
	(via
		(at 119.4054 -39.1668)
		(size 0.508)
		(drill 0.254)
		(layers "F.Cu" "B.Cu")
		(net "GND")
	)
	(via
		(at 63.0682 -54.229)
		(size 0.7112)
		(drill 0.4064)
		(layers "F.Cu" "B.Cu")
		(net "GND")
	)
	(via
		(at 95.7072 -49.149)
		(size 0.4318)
		(drill 0.2032)
		(layers "F.Cu" "B.Cu")
		(net "GND")
	)
	(via
		(at 97.0153 -25.6413)
		(size 0.4318)
		(drill 0.2032)
		(layers "F.Cu" "B.Cu")
		(net "GND")
	)
	(via
		(at 108.804202 -36.006024)
		(size 0.4318)
		(drill 0.2032)
		(layers "F.Cu" "B.Cu")
		(net "GND")
	)
	(via
		(at 195.199 -28.956)
		(size 0.508)
		(drill 0.254)
		(layers "F.Cu" "B.Cu")
		(net "GND")
	)
	(via
		(at 132.666994 -4.24688)
		(size 0.4318)
		(drill 0.2032)
		(layers "F.Cu" "B.Cu")
		(net "GND")
	)
	(via
		(at 182.118 -47.625)
		(size 0.508)
		(drill 0.254)
		(layers "F.Cu" "B.Cu")
		(net "GND")
	)
	(via
		(at 75.5015 -41.5798)
		(size 0.508)
		(drill 0.254)
		(layers "F.Cu" "B.Cu")
		(net "GND")
	)
	(via
		(at 149.86 -3.557778)
		(size 0.4318)
		(drill 0.2032)
		(layers "F.Cu" "B.Cu")
		(net "GND")
	)
	(via
		(at 42.0878 -51.6636)
		(size 0.508)
		(drill 0.254)
		(layers "F.Cu" "B.Cu")
		(net "GND")
	)
	(via
		(at 34.671 -25.786842)
		(size 0.508)
		(drill 0.254)
		(layers "F.Cu" "B.Cu")
		(net "GND")
	)
	(via
		(at 100.584 -45.466)
		(size 0.4318)
		(drill 0.2032)
		(layers "F.Cu" "B.Cu")
		(net "GND")
	)
	(via
		(at 26.416 -23.368)
		(size 0.7112)
		(drill 0.4064)
		(layers "F.Cu" "B.Cu")
		(net "GND")
	)
	(via
		(at 168.148 -56.515)
		(size 0.7112)
		(drill 0.3556)
		(layers "F.Cu" "B.Cu")
		(net "GND")
	)
	(via
		(at 20.881594 -9.587738)
		(size 0.508)
		(drill 0.254)
		(layers "F.Cu" "B.Cu")
		(net "GND")
	)
	(via
		(at 196.6722 -26.035)
		(size 0.7112)
		(drill 0.4064)
		(layers "F.Cu" "B.Cu")
		(net "GND")
	)
	(via
		(at 110.605062 -42.56024)
		(size 0.4318)
		(drill 0.2032)
		(layers "F.Cu" "B.Cu")
		(net "GND")
	)
	(via
		(at 171.5516 -67.31)
		(size 0.4318)
		(drill 0.2032)
		(layers "F.Cu" "B.Cu")
		(net "GND")
	)
	(via
		(at 167.9448 -63.119)
		(size 0.4318)
		(drill 0.2032)
		(layers "F.Cu" "B.Cu")
		(net "GND")
	)
	(via
		(at 156.8958 -31.877)
		(size 0.508)
		(drill 0.254)
		(layers "F.Cu" "B.Cu")
		(net "GND")
	)
	(via
		(at 153.8478 -3.151378)
		(size 0.4318)
		(drill 0.2032)
		(layers "F.Cu" "B.Cu")
		(net "GND")
	)
	(via
		(at 3.3274 -38.2524)
		(size 0.7112)
		(drill 0.4064)
		(layers "F.Cu" "B.Cu")
		(net "GND")
	)
	(via
		(at 68.307712 -28.60675)
		(size 0.508)
		(drill 0.254)
		(layers "F.Cu" "B.Cu")
		(net "GND")
	)
	(via
		(at 64.1858 -54.229)
		(size 0.7112)
		(drill 0.4064)
		(layers "F.Cu" "B.Cu")
		(net "GND")
	)
	(via
		(at 172.8216 -69.3674)
		(size 0.4318)
		(drill 0.2032)
		(layers "F.Cu" "B.Cu")
		(net "GND")
	)
	(via
		(at 126.2634 -2.2352)
		(size 0.7112)
		(drill 0.4064)
		(layers "F.Cu" "B.Cu")
		(net "GND")
	)
	(via
		(at 105.2322 -21.7424)
		(size 0.4318)
		(drill 0.2032)
		(layers "F.Cu" "B.Cu")
		(net "GND")
	)
	(via
		(at 30.861 -9.561068)
		(size 0.508)
		(drill 0.254)
		(layers "F.Cu" "B.Cu")
		(net "GND")
	)
	(via
		(at 17.018 -66.8528)
		(size 0.508)
		(drill 0.254)
		(layers "F.Cu" "B.Cu")
		(net "GND")
	)
	(via
		(at 205.613 -65.278)
		(size 0.7112)
		(drill 0.4064)
		(layers "F.Cu" "B.Cu")
		(net "GND")
	)
	(via
		(at 94.2594 -50.673)
		(size 0.4318)
		(drill 0.2032)
		(layers "F.Cu" "B.Cu")
		(net "GND")
	)
	(via
		(at 11.684 -36.3982)
		(size 0.508)
		(drill 0.254)
		(layers "F.Cu" "B.Cu")
		(net "GND")
	)
	(via
		(at 25.019 -34.925)
		(size 0.7112)
		(drill 0.4064)
		(layers "F.Cu" "B.Cu")
		(net "GND")
	)
	(via
		(at 11.049 -37.592)
		(size 0.508)
		(drill 0.254)
		(layers "F.Cu" "B.Cu")
		(net "GND")
	)
	(via
		(at 202.31481 -37.60724)
		(size 0.508)
		(drill 0.254)
		(layers "F.Cu" "B.Cu")
		(net "GND")
	)
	(via
		(at 83.0834 -60.2234)
		(size 0.4318)
		(drill 0.2032)
		(layers "F.Cu" "B.Cu")
		(net "GND")
	)
	(via
		(at 91.078304 -41.17086)
		(size 0.4318)
		(drill 0.2032)
		(layers "F.Cu" "B.Cu")
		(net "GND")
	)
	(via
		(at 48.5394 -70.2564)
		(size 0.7112)
		(drill 0.4064)
		(layers "F.Cu" "B.Cu")
		(net "GND")
	)
	(via
		(at 82.883502 -31.08452)
		(size 0.4318)
		(drill 0.2032)
		(layers "F.Cu" "B.Cu")
		(net "GND")
	)
	(via
		(at 42.418 -58.547)
		(size 0.508)
		(drill 0.254)
		(layers "F.Cu" "B.Cu")
		(net "GND")
	)
	(via
		(at 48.6918 -13.2334)
		(size 0.508)
		(drill 0.254)
		(layers "F.Cu" "B.Cu")
		(net "GND")
	)
	(via
		(at 99.2251 -23.622)
		(size 0.4318)
		(drill 0.2032)
		(layers "F.Cu" "B.Cu")
		(net "GND")
	)
	(via
		(at 34.8742 -9.561068)
		(size 0.508)
		(drill 0.254)
		(layers "F.Cu" "B.Cu")
		(net "GND")
	)
	(via
		(at 103.5177 -25.449784)
		(size 0.4318)
		(drill 0.2032)
		(layers "F.Cu" "B.Cu")
		(net "GND")
	)
	(via
		(at 4.292346 -67.449954)
		(size 0.508)
		(drill 0.254)
		(layers "F.Cu" "B.Cu")
		(net "GND")
	)
	(via
		(at 41.148 -59.69)
		(size 0.508)
		(drill 0.254)
		(layers "F.Cu" "B.Cu")
		(net "GND")
	)
	(via
		(at 189.256416 -34.991802)
		(size 0.508)
		(drill 0.254)
		(layers "F.Cu" "B.Cu")
		(net "GND")
	)
	(via
		(at 122.301 -2.2606)
		(size 0.7112)
		(drill 0.4064)
		(layers "F.Cu" "B.Cu")
		(net "GND")
	)
	(via
		(at 171.8564 -5.157978)
		(size 0.4318)
		(drill 0.2032)
		(layers "F.Cu" "B.Cu")
		(net "GND")
	)
	(via
		(at 93.8022 -67.2846)
		(size 0.508)
		(drill 0.254)
		(layers "F.Cu" "B.Cu")
		(net "GND")
	)
	(via
		(at 26.416 -24.511)
		(size 0.7112)
		(drill 0.4064)
		(layers "F.Cu" "B.Cu")
		(net "GND")
	)
	(via
		(at 102.7176 -57.2262)
		(size 0.4318)
		(drill 0.2032)
		(layers "F.Cu" "B.Cu")
		(net "GND")
	)
	(via
		(at 103.910384 -36.566602)
		(size 0.4318)
		(drill 0.2032)
		(layers "F.Cu" "B.Cu")
		(net "GND")
	)
	(via
		(at 133.53796 -22.59584)
		(size 0.508)
		(drill 0.254)
		(layers "F.Cu" "B.Cu")
		(net "GND")
	)
	(via
		(at 105.4354 -38.0492)
		(size 0.4318)
		(drill 0.2032)
		(layers "F.Cu" "B.Cu")
		(net "GND")
	)
	(via
		(at 49.657 -12.573)
		(size 0.7112)
		(drill 0.3556)
		(layers "F.Cu" "B.Cu")
		(net "GND")
	)
	(via
		(at 80.165702 -25.6159)
		(size 0.4318)
		(drill 0.2032)
		(layers "F.Cu" "B.Cu")
		(net "GND")
	)
	(via
		(at 81.153 -53.8734)
		(size 0.4318)
		(drill 0.2032)
		(layers "F.Cu" "B.Cu")
		(net "GND")
	)
	(via
		(at 6.5532 -30.5562)
		(size 0.508)
		(drill 0.254)
		(layers "F.Cu" "B.Cu")
		(net "GND")
	)
	(via
		(at 23.2156 -68.6562)
		(size 0.508)
		(drill 0.254)
		(layers "F.Cu" "B.Cu")
		(net "GND")
	)
	(via
		(at 189.671198 -69.313806)
		(size 0.4318)
		(drill 0.2032)
		(layers "F.Cu" "B.Cu")
		(net "GND")
	)
	(via
		(at 112.522 -48.9458)
		(size 0.4318)
		(drill 0.2032)
		(layers "F.Cu" "B.Cu")
		(net "GND")
	)
	(via
		(at 171.357544 -64.111124)
		(size 0.4318)
		(drill 0.2032)
		(layers "F.Cu" "B.Cu")
		(net "GND")
	)
	(via
		(at 115.951 -31.242)
		(size 0.4318)
		(drill 0.2032)
		(layers "F.Cu" "B.Cu")
		(net "GND")
	)
	(via
		(at 102.87 -48.4378)
		(size 0.4318)
		(drill 0.2032)
		(layers "F.Cu" "B.Cu")
		(net "GND")
	)
	(via
		(at 158.3436 -58.4454)
		(size 0.7112)
		(drill 0.4064)
		(layers "F.Cu" "B.Cu")
		(net "GND")
	)
	(via
		(at 178.03876 -8.46836)
		(size 0.4318)
		(drill 0.2032)
		(layers "F.Cu" "B.Cu")
		(net "GND")
	)
	(via
		(at 95.0468 -36.396676)
		(size 0.4318)
		(drill 0.2032)
		(layers "F.Cu" "B.Cu")
		(net "GND")
	)
	(via
		(at 61.722 -65.786)
		(size 0.7112)
		(drill 0.4064)
		(layers "F.Cu" "B.Cu")
		(net "GND")
	)
	(via
		(at 133.604 -3.176778)
		(size 0.4318)
		(drill 0.2032)
		(layers "F.Cu" "B.Cu")
		(net "GND")
	)
	(via
		(at 25.019 -9.561068)
		(size 0.508)
		(drill 0.254)
		(layers "F.Cu" "B.Cu")
		(net "GND")
	)
	(via
		(at 111.099092 -37.149278)
		(size 0.4318)
		(drill 0.2032)
		(layers "F.Cu" "B.Cu")
		(net "GND")
	)
	(via
		(at 60.7822 -49.9872)
		(size 0.5588)
		(drill 0.3048)
		(layers "F.Cu" "B.Cu")
		(net "GND")
	)
	(via
		(at 85.01761 -45.9486)
		(size 0.4318)
		(drill 0.2032)
		(layers "F.Cu" "B.Cu")
		(net "GND")
	)
	(via
		(at 143.6878 -69.3547)
		(size 0.4318)
		(drill 0.2032)
		(layers "F.Cu" "B.Cu")
		(net "GND")
	)
	(via
		(at 182.118 -18.923)
		(size 0.7112)
		(drill 0.4064)
		(layers "F.Cu" "B.Cu")
		(net "GND")
	)
	(via
		(at 174.650908 -3.159506)
		(size 0.4318)
		(drill 0.2032)
		(layers "F.Cu" "B.Cu")
		(net "GND")
	)
	(via
		(at 186.436 -52.07)
		(size 0.508)
		(drill 0.254)
		(layers "F.Cu" "B.Cu")
		(net "GND")
	)
	(via
		(at 160.02 -14.0462)
		(size 0.7112)
		(drill 0.4064)
		(layers "F.Cu" "B.Cu")
		(net "GND")
	)
	(via
		(at 181.737 -52.282598)
		(size 0.508)
		(drill 0.254)
		(layers "F.Cu" "B.Cu")
		(net "GND")
	)
	(via
		(at 115.443 -43.4594)
		(size 0.4318)
		(drill 0.2032)
		(layers "F.Cu" "B.Cu")
		(net "GND")
	)
	(via
		(at 178.2064 -26.6446)
		(size 0.7112)
		(drill 0.4064)
		(layers "F.Cu" "B.Cu")
		(net "GND")
	)
	(via
		(at 184.705498 -35.56)
		(size 0.508)
		(drill 0.254)
		(layers "F.Cu" "B.Cu")
		(net "GND")
	)
	(via
		(at 129.8448 -46.5836)
		(size 0.508)
		(drill 0.254)
		(layers "F.Cu" "B.Cu")
		(net "GND")
	)
	(via
		(at 156.3878 -58.4708)
		(size 0.7112)
		(drill 0.4064)
		(layers "F.Cu" "B.Cu")
		(net "GND")
	)
	(via
		(at 52.705 -64.262)
		(size 0.7112)
		(drill 0.4064)
		(layers "F.Cu" "B.Cu")
		(net "GND")
	)
	(via
		(at 60.579 -65.786)
		(size 0.7112)
		(drill 0.4064)
		(layers "F.Cu" "B.Cu")
		(net "GND")
	)
	(via
		(at 190.272416 -33.975802)
		(size 0.508)
		(drill 0.254)
		(layers "F.Cu" "B.Cu")
		(net "GND")
	)
	(via
		(at 197.866 -36.068)
		(size 0.508)
		(drill 0.254)
		(layers "F.Cu" "B.Cu")
		(net "GND")
	)
	(via
		(at 169.672 -69.31406)
		(size 0.4318)
		(drill 0.2032)
		(layers "F.Cu" "B.Cu")
		(net "GND")
	)
	(via
		(at 31.115 -56.896)
		(size 0.7112)
		(drill 0.3556)
		(layers "F.Cu" "B.Cu")
		(net "GND")
	)
	(via
		(at 51.5112 -48.6156)
		(size 0.508)
		(drill 0.254)
		(layers "F.Cu" "B.Cu")
		(net "GND")
	)
	(via
		(at 93.58757 -49.89957)
		(size 0.4318)
		(drill 0.2032)
		(layers "F.Cu" "B.Cu")
		(net "GND")
	)
	(via
		(at 104.394 -22.5806)
		(size 0.4318)
		(drill 0.2032)
		(layers "F.Cu" "B.Cu")
		(net "GND")
	)
	(via
		(at 91.878404 -35.628072)
		(size 0.4318)
		(drill 0.2032)
		(layers "F.Cu" "B.Cu")
		(net "GND")
	)
	(via
		(at 26.86685 -34.886646)
		(size 0.7112)
		(drill 0.4064)
		(layers "F.Cu" "B.Cu")
		(net "GND")
	)
	(via
		(at 195.453 -59.563)
		(size 0.7112)
		(drill 0.4064)
		(layers "F.Cu" "B.Cu")
		(net "GND")
	)
	(via
		(at 132.5372 -64.23025)
		(size 0.4318)
		(drill 0.2032)
		(layers "F.Cu" "B.Cu")
		(net "GND")
	)
	(via
		(at 164.5412 -64.0842)
		(size 0.4318)
		(drill 0.2032)
		(layers "F.Cu" "B.Cu")
		(net "GND")
	)
	(via
		(at 136.50214 -5.228336)
		(size 0.4318)
		(drill 0.2032)
		(layers "F.Cu" "B.Cu")
		(net "GND")
	)
	(via
		(at 19.9898 -65.9892)
		(size 0.508)
		(drill 0.254)
		(layers "F.Cu" "B.Cu")
		(net "GND")
	)
	(via
		(at 82.905346 -43.027854)
		(size 0.4318)
		(drill 0.2032)
		(layers "F.Cu" "B.Cu")
		(net "GND")
	)
	(via
		(at 141.96441 -46.635162)
		(size 0.508)
		(drill 0.254)
		(layers "F.Cu" "B.Cu")
		(net "GND")
	)
	(via
		(at 187.833 -19.177)
		(size 0.7112)
		(drill 0.4064)
		(layers "F.Cu" "B.Cu")
		(net "GND")
	)
	(via
		(at 91.6686 -23.9268)
		(size 0.4318)
		(drill 0.2032)
		(layers "F.Cu" "B.Cu")
		(net "GND")
	)
	(via
		(at 3.302 -37.084)
		(size 0.7112)
		(drill 0.4064)
		(layers "F.Cu" "B.Cu")
		(net "GND")
	)
	(via
		(at 97.421192 -42.77106)
		(size 0.4318)
		(drill 0.2032)
		(layers "F.Cu" "B.Cu")
		(net "GND")
	)
	(via
		(at 72.4154 -32.89554)
		(size 0.508)
		(drill 0.254)
		(layers "F.Cu" "B.Cu")
		(net "GND")
	)
	(via
		(at 165.862 -23.622)
		(size 0.7112)
		(drill 0.4064)
		(layers "F.Cu" "B.Cu")
		(net "GND")
	)
	(via
		(at 53.3654 -34.4932)
		(size 0.508)
		(drill 0.254)
		(layers "F.Cu" "B.Cu")
		(net "GND")
	)
	(via
		(at 177.822606 -23.218394)
		(size 0.7112)
		(drill 0.4064)
		(layers "F.Cu" "B.Cu")
		(net "GND")
	)
	(via
		(at 190.246 -64.0588)
		(size 0.4318)
		(drill 0.2032)
		(layers "F.Cu" "B.Cu")
		(net "GND")
	)
	(via
		(at 102.5652 -22.098)
		(size 0.4318)
		(drill 0.2032)
		(layers "F.Cu" "B.Cu")
		(net "GND")
	)
	(via
		(at 106.1466 -45.304202)
		(size 0.4318)
		(drill 0.2032)
		(layers "F.Cu" "B.Cu")
		(net "GND")
	)
	(via
		(at 97.699576 -52.322476)
		(size 0.4318)
		(drill 0.2032)
		(layers "F.Cu" "B.Cu")
		(net "GND")
	)
	(via
		(at 2.58826 -62.661546)
		(size 0.508)
		(drill 0.254)
		(layers "F.Cu" "B.Cu")
		(net "GND")
	)
	(via
		(at 83.93938 -28.57881)
		(size 0.4318)
		(drill 0.2032)
		(layers "F.Cu" "B.Cu")
		(net "GND")
	)
	(via
		(at 96.64954 -47.117)
		(size 0.4318)
		(drill 0.2032)
		(layers "F.Cu" "B.Cu")
		(net "GND")
	)
	(via
		(at 34.73958 -28.702)
		(size 0.508)
		(drill 0.254)
		(layers "F.Cu" "B.Cu")
		(net "GND")
	)
	(via
		(at 146.719544 -69.328538)
		(size 0.4318)
		(drill 0.2032)
		(layers "F.Cu" "B.Cu")
		(net "GND")
	)
	(via
		(at 108.204 -42.51198)
		(size 0.4318)
		(drill 0.2032)
		(layers "F.Cu" "B.Cu")
		(net "GND")
	)
	(via
		(at 86.6902 -43.0784)
		(size 0.4318)
		(drill 0.2032)
		(layers "F.Cu" "B.Cu")
		(net "GND")
	)
	(via
		(at 75.1586 -39.1668)
		(size 0.508)
		(drill 0.254)
		(layers "F.Cu" "B.Cu")
		(net "GND")
	)
	(via
		(at 98.933 -69.9262)
		(size 0.508)
		(drill 0.254)
		(layers "F.Cu" "B.Cu")
		(net "GND")
	)
	(via
		(at 50.7746 -39.1668)
		(size 0.508)
		(drill 0.254)
		(layers "F.Cu" "B.Cu")
		(net "GND")
	)
	(via
		(at 198.882 -30.099)
		(size 0.7112)
		(drill 0.4064)
		(layers "F.Cu" "B.Cu")
		(net "GND")
	)
	(via
		(at 112.634522 -36.768278)
		(size 0.4318)
		(drill 0.2032)
		(layers "F.Cu" "B.Cu")
		(net "GND")
	)
	(via
		(at 136.642856 -3.128518)
		(size 0.4318)
		(drill 0.2032)
		(layers "F.Cu" "B.Cu")
		(net "GND")
	)
	(via
		(at 83.573112 -50.782474)
		(size 0.4318)
		(drill 0.2032)
		(layers "F.Cu" "B.Cu")
		(net "GND")
	)
	(via
		(at 155.067 -7.748778)
		(size 0.4318)
		(drill 0.2032)
		(layers "F.Cu" "B.Cu")
		(net "GND")
	)
	(via
		(at 58.87212 -9.573514)
		(size 0.508)
		(drill 0.254)
		(layers "F.Cu" "B.Cu")
		(net "GND")
	)
	(via
		(at 83.312 -24.6634)
		(size 0.4318)
		(drill 0.2032)
		(layers "F.Cu" "B.Cu")
		(net "GND")
	)
	(via
		(at 122.0216 -39.1287)
		(size 0.508)
		(drill 0.254)
		(layers "F.Cu" "B.Cu")
		(net "GND")
	)
	(via
		(at 148.66112 -3.115818)
		(size 0.4318)
		(drill 0.2032)
		(layers "F.Cu" "B.Cu")
		(net "GND")
	)
	(via
		(at 89.3318 -42.4942)
		(size 0.4318)
		(drill 0.2032)
		(layers "F.Cu" "B.Cu")
		(net "GND")
	)
	(via
		(at 183.3753 -13.1953)
		(size 0.7112)
		(drill 0.4064)
		(layers "F.Cu" "B.Cu")
		(net "GND")
	)
	(via
		(at 176.149 -37.592)
		(size 0.7112)
		(drill 0.4064)
		(layers "F.Cu" "B.Cu")
		(net "GND")
	)
	(via
		(at 63.881 -64.389)
		(size 0.7112)
		(drill 0.3556)
		(layers "F.Cu" "B.Cu")
		(net "GND")
	)
	(via
		(at 1.1176 -65.2018)
		(size 0.7112)
		(drill 0.4064)
		(layers "F.Cu" "B.Cu")
		(net "GND")
	)
	(via
		(at 208.7626 -69.3674)
		(size 0.7112)
		(drill 0.4064)
		(layers "F.Cu" "B.Cu")
		(net "GND")
	)
	(via
		(at 98.241358 -41.18737)
		(size 0.4318)
		(drill 0.2032)
		(layers "F.Cu" "B.Cu")
		(net "GND")
	)
	(via
		(at 145.32737 -67.2846)
		(size 0.4318)
		(drill 0.2032)
		(layers "F.Cu" "B.Cu")
		(net "GND")
	)
	(via
		(at 90.2462 -44.3484)
		(size 0.4318)
		(drill 0.2032)
		(layers "F.Cu" "B.Cu")
		(net "GND")
	)
	(via
		(at 189.484 -46.3042)
		(size 0.508)
		(drill 0.254)
		(layers "F.Cu" "B.Cu")
		(net "GND")
	)
	(via
		(at 168.0464 -39.8018)
		(size 0.508)
		(drill 0.254)
		(layers "F.Cu" "B.Cu")
		(net "GND")
	)
	(via
		(at 4.292346 -65.94983)
		(size 0.508)
		(drill 0.254)
		(layers "F.Cu" "B.Cu")
		(net "GND")
	)
	(via
		(at 119.4816 -45.2628)
		(size 0.4318)
		(drill 0.2032)
		(layers "F.Cu" "B.Cu")
		(net "GND")
	)
	(via
		(at 98.186494 -27.638248)
		(size 0.4318)
		(drill 0.2032)
		(layers "F.Cu" "B.Cu")
		(net "GND")
	)
	(via
		(at 151.003 -1.017778)
		(size 0.4318)
		(drill 0.2032)
		(layers "F.Cu" "B.Cu")
		(net "GND")
	)
	(via
		(at 175.15713 -7.082282)
		(size 0.4318)
		(drill 0.2032)
		(layers "F.Cu" "B.Cu")
		(net "GND")
	)
	(via
		(at 25.229312 -59.78398)
		(size 0.508)
		(drill 0.254)
		(layers "F.Cu" "B.Cu")
		(net "GND")
	)
	(via
		(at 75.0062 -60.4774)
		(size 0.508)
		(drill 0.254)
		(layers "F.Cu" "B.Cu")
		(net "GND")
	)
	(via
		(at 168.0464 -69.1642)
		(size 0.4318)
		(drill 0.2032)
		(layers "F.Cu" "B.Cu")
		(net "GND")
	)
	(via
		(at 85.852 -47.1678)
		(size 0.4318)
		(drill 0.2032)
		(layers "F.Cu" "B.Cu")
		(net "GND")
	)
	(via
		(at 184.315862 -8.294116)
		(size 0.4318)
		(drill 0.2032)
		(layers "F.Cu" "B.Cu")
		(net "GND")
	)
	(via
		(at 88.411304 -27.66314)
		(size 0.4318)
		(drill 0.2032)
		(layers "F.Cu" "B.Cu")
		(net "GND")
	)
	(via
		(at 93.87332 -54.7116)
		(size 0.4318)
		(drill 0.2032)
		(layers "F.Cu" "B.Cu")
		(net "GND")
	)
	(via
		(at 53.8226 -64.262)
		(size 0.7112)
		(drill 0.4064)
		(layers "F.Cu" "B.Cu")
		(net "GND")
	)
	(via
		(at 88.7984 -32.1818)
		(size 0.4318)
		(drill 0.2032)
		(layers "F.Cu" "B.Cu")
		(net "GND")
	)
	(via
		(at 61.0108 -15.05585)
		(size 0.508)
		(drill 0.254)
		(layers "F.Cu" "B.Cu")
		(net "GND")
	)
	(via
		(at 130.499104 -65.675002)
		(size 0.4318)
		(drill 0.2032)
		(layers "F.Cu" "B.Cu")
		(net "GND")
	)
	(via
		(at 5.08 -22.987)
		(size 0.7112)
		(drill 0.3556)
		(layers "F.Cu" "B.Cu")
		(net "GND")
	)
	(via
		(at 109.296708 -28.472892)
		(size 0.4318)
		(drill 0.2032)
		(layers "F.Cu" "B.Cu")
		(net "GND")
	)
	(via
		(at 191.135 -12.447778)
		(size 0.508)
		(drill 0.254)
		(layers "F.Cu" "B.Cu")
		(net "GND")
	)
	(via
		(at 87.772748 -45.3898)
		(size 0.4318)
		(drill 0.2032)
		(layers "F.Cu" "B.Cu")
		(net "GND")
	)
	(via
		(at 79.0448 -29.1592)
		(size 0.4318)
		(drill 0.2032)
		(layers "F.Cu" "B.Cu")
		(net "GND")
	)
	(via
		(at 133.2738 -36.840414)
		(size 0.508)
		(drill 0.254)
		(layers "F.Cu" "B.Cu")
		(net "GND")
	)
	(via
		(at 10.2108 -58.7502)
		(size 0.508)
		(drill 0.254)
		(layers "F.Cu" "B.Cu")
		(net "GND")
	)
	(via
		(at 103.124 -41.316402)
		(size 0.4318)
		(drill 0.2032)
		(layers "F.Cu" "B.Cu")
		(net "GND")
	)
	(via
		(at 178.850798 -64.718184)
		(size 0.4318)
		(drill 0.2032)
		(layers "F.Cu" "B.Cu")
		(net "GND")
	)
	(via
		(at 82.6008 -56.3118)
		(size 0.4318)
		(drill 0.2032)
		(layers "F.Cu" "B.Cu")
		(net "GND")
	)
	(via
		(at 123.7488 -39.1414)
		(size 0.508)
		(drill 0.254)
		(layers "F.Cu" "B.Cu")
		(net "GND")
	)
	(via
		(at 53.975 -70.358)
		(size 0.7112)
		(drill 0.4064)
		(layers "F.Cu" "B.Cu")
		(net "GND")
	)
	(via
		(at 87.09152 -37.12972)
		(size 0.4318)
		(drill 0.2032)
		(layers "F.Cu" "B.Cu")
		(net "GND")
	)
	(via
		(at 21.2344 -14.6304)
		(size 0.508)
		(drill 0.254)
		(layers "F.Cu" "B.Cu")
		(net "GND")
	)
	(via
		(at 101.421692 -41.97096)
		(size 0.4318)
		(drill 0.2032)
		(layers "F.Cu" "B.Cu")
		(net "GND")
	)
	(via
		(at 138.7348 -68.834)
		(size 0.4318)
		(drill 0.2032)
		(layers "F.Cu" "B.Cu")
		(net "GND")
	)
	(via
		(at 40.629078 -13.190728)
		(size 0.508)
		(drill 0.254)
		(layers "F.Cu" "B.Cu")
		(net "GND")
	)
	(via
		(at 10.287 -66.04)
		(size 0.508)
		(drill 0.254)
		(layers "F.Cu" "B.Cu")
		(net "GND")
	)
	(via
		(at 144.8308 -68.5038)
		(size 0.4318)
		(drill 0.2032)
		(layers "F.Cu" "B.Cu")
		(net "GND")
	)
	(via
		(at 47.844202 -29.498798)
		(size 0.508)
		(drill 0.254)
		(layers "F.Cu" "B.Cu")
		(net "GND")
	)
	(via
		(at 124.3584 -2.2352)
		(size 0.7112)
		(drill 0.4064)
		(layers "F.Cu" "B.Cu")
		(net "GND")
	)
	(via
		(at 168.709848 -37.590222)
		(size 0.7112)
		(drill 0.4064)
		(layers "F.Cu" "B.Cu")
		(net "GND")
	)
	(via
		(at 170.561 -3.811778)
		(size 0.4318)
		(drill 0.2032)
		(layers "F.Cu" "B.Cu")
		(net "GND")
	)
	(via
		(at 119.126 -33.782)
		(size 0.7112)
		(drill 0.3556)
		(layers "F.Cu" "B.Cu")
		(net "GND")
	)
	(via
		(at 47.0408 -40.4114)
		(size 0.7112)
		(drill 0.3556)
		(layers "F.Cu" "B.Cu")
		(net "GND")
	)
	(via
		(at 45.0088 -33.16605)
		(size 0.508)
		(drill 0.254)
		(layers "F.Cu" "B.Cu")
		(net "GND")
	)
	(via
		(at 171.5516 -69.3674)
		(size 0.4318)
		(drill 0.2032)
		(layers "F.Cu" "B.Cu")
		(net "GND")
	)
	(via
		(at 90.17 -66.0908)
		(size 0.7112)
		(drill 0.3556)
		(layers "F.Cu" "B.Cu")
		(net "GND")
	)
	(via
		(at 82.266028 -18.197322)
		(size 0.508)
		(drill 0.254)
		(layers "F.Cu" "B.Cu")
		(net "GND")
	)
	(via
		(at 175.7426 -68.4022)
		(size 0.4318)
		(drill 0.2032)
		(layers "F.Cu" "B.Cu")
		(net "GND")
	)
	(via
		(at 163.59886 -68.68668)
		(size 0.4318)
		(drill 0.2032)
		(layers "F.Cu" "B.Cu")
		(net "GND")
	)
	(via
		(at 73.406 -16.764)
		(size 0.7112)
		(drill 0.3556)
		(layers "F.Cu" "B.Cu")
		(net "GND")
	)
	(via
		(at 106.5784 -55.6768)
		(size 0.4318)
		(drill 0.2032)
		(layers "F.Cu" "B.Cu")
		(net "GND")
	)
	(via
		(at 54.3179 -45.6819)
		(size 0.508)
		(drill 0.254)
		(layers "F.Cu" "B.Cu")
		(net "GND")
	)
	(via
		(at 199.517 -2.032)
		(size 0.7112)
		(drill 0.4064)
		(layers "F.Cu" "B.Cu")
		(net "GND")
	)
	(via
		(at 85.1916 -43.0784)
		(size 0.4318)
		(drill 0.2032)
		(layers "F.Cu" "B.Cu")
		(net "GND")
	)
	(via
		(at 103.0732 -49.9618)
		(size 0.4318)
		(drill 0.2032)
		(layers "F.Cu" "B.Cu")
		(net "GND")
	)
	(via
		(at 14.605 -27.051)
		(size 0.508)
		(drill 0.254)
		(layers "F.Cu" "B.Cu")
		(net "GND")
	)
	(via
		(at 177.572416 -5.20573)
		(size 0.4318)
		(drill 0.2032)
		(layers "F.Cu" "B.Cu")
		(net "GND")
	)
	(via
		(at 115.9002 -69.9262)
		(size 0.508)
		(drill 0.254)
		(layers "F.Cu" "B.Cu")
		(net "GND")
	)
	(via
		(at 182.051198 -69.339206)
		(size 0.4318)
		(drill 0.2032)
		(layers "F.Cu" "B.Cu")
		(net "GND")
	)
	(via
		(at 54.88559 -9.562846)
		(size 0.508)
		(drill 0.254)
		(layers "F.Cu" "B.Cu")
		(net "GND")
	)
	(via
		(at 25.019 -33.782)
		(size 0.7112)
		(drill 0.4064)
		(layers "F.Cu" "B.Cu")
		(net "GND")
	)
	(via
		(at 31.0515 -59.182)
		(size 0.7112)
		(drill 0.4064)
		(layers "F.Cu" "B.Cu")
		(net "GND")
	)
	(via
		(at 175.26 -40.386)
		(size 0.7112)
		(drill 0.4064)
		(layers "F.Cu" "B.Cu")
		(net "GND")
	)
	(via
		(at 72.136 -14.1732)
		(size 0.508)
		(drill 0.254)
		(layers "F.Cu" "B.Cu")
		(net "GND")
	)
	(via
		(at 96.621092 -36.428172)
		(size 0.4318)
		(drill 0.2032)
		(layers "F.Cu" "B.Cu")
		(net "GND")
	)
	(via
		(at 60.162694 -46.981618)
		(size 0.508)
		(drill 0.254)
		(layers "F.Cu" "B.Cu")
		(net "GND")
	)
	(via
		(at 12.7 -28.2702)
		(size 0.508)
		(drill 0.254)
		(layers "F.Cu" "B.Cu")
		(net "GND")
	)
	(via
		(at 61.7093 -39.5732)
		(size 0.508)
		(drill 0.254)
		(layers "F.Cu" "B.Cu")
		(net "GND")
	)
	(via
		(at 176.32807 -5.156708)
		(size 0.4318)
		(drill 0.2032)
		(layers "F.Cu" "B.Cu")
		(net "GND")
	)
	(via
		(at 42.570908 -40.813736)
		(size 0.508)
		(drill 0.254)
		(layers "F.Cu" "B.Cu")
		(net "GND")
	)
	(via
		(at 115.2906 -50.038)
		(size 0.4318)
		(drill 0.2032)
		(layers "F.Cu" "B.Cu")
		(net "GND")
	)
	(via
		(at 185.95594 -3.115818)
		(size 0.4318)
		(drill 0.2032)
		(layers "F.Cu" "B.Cu")
		(net "GND")
	)
	(via
		(at 104.775 -50.1142)
		(size 0.4318)
		(drill 0.2032)
		(layers "F.Cu" "B.Cu")
		(net "GND")
	)
	(via
		(at 104.216708 -36.033456)
		(size 0.4318)
		(drill 0.2032)
		(layers "F.Cu" "B.Cu")
		(net "GND")
	)
	(via
		(at 96.6216 -34.017712)
		(size 0.4318)
		(drill 0.2032)
		(layers "F.Cu" "B.Cu")
		(net "GND")
	)
	(via
		(at 100.1014 -24.1046)
		(size 0.4318)
		(drill 0.2032)
		(layers "F.Cu" "B.Cu")
		(net "GND")
	)
	(via
		(at 208.407 -1.651)
		(size 0.7112)
		(drill 0.4064)
		(layers "F.Cu" "B.Cu")
		(net "GND")
	)
	(via
		(at 64.135 -65.786)
		(size 0.7112)
		(drill 0.4064)
		(layers "F.Cu" "B.Cu")
		(net "GND")
	)
	(via
		(at 95.939102 -30.749494)
		(size 0.4318)
		(drill 0.2032)
		(layers "F.Cu" "B.Cu")
		(net "GND")
	)
	(via
		(at 189.0014 -64.7192)
		(size 0.4318)
		(drill 0.2032)
		(layers "F.Cu" "B.Cu")
		(net "GND")
	)
	(via
		(at 97.663 -15.748)
		(size 0.7112)
		(drill 0.3556)
		(layers "F.Cu" "B.Cu")
		(net "GND")
	)
	(via
		(at 38.27018 -31.0642)
		(size 0.508)
		(drill 0.254)
		(layers "F.Cu" "B.Cu")
		(net "GND")
	)
	(via
		(at 139.8016 -56.46039)
		(size 0.508)
		(drill 0.254)
		(layers "F.Cu" "B.Cu")
		(net "GND")
	)
	(via
		(at 82.828384 -9.6266)
		(size 0.508)
		(drill 0.254)
		(layers "F.Cu" "B.Cu")
		(net "GND")
	)
	(via
		(at 130.3274 -59.563)
		(size 0.508)
		(drill 0.254)
		(layers "F.Cu" "B.Cu")
		(net "GND")
	)
	(via
		(at 108.113068 -53.219096)
		(size 0.4318)
		(drill 0.2032)
		(layers "F.Cu" "B.Cu")
		(net "GND")
	)
	(via
		(at 6.4008 -72.644)
		(size 0.7112)
		(drill 0.4064)
		(layers "F.Cu" "B.Cu")
		(net "GND")
	)
	(via
		(at 87.049864 -41.044622)
		(size 0.4318)
		(drill 0.2032)
		(layers "F.Cu" "B.Cu")
		(net "GND")
	)
	(via
		(at 150.622 -18.669)
		(size 0.7112)
		(drill 0.3556)
		(layers "F.Cu" "B.Cu")
		(net "GND")
	)
	(via
		(at 140.58519 -64.092328)
		(size 0.4318)
		(drill 0.2032)
		(layers "F.Cu" "B.Cu")
		(net "GND")
	)
	(via
		(at 180.34 -53.34)
		(size 0.7112)
		(drill 0.3556)
		(layers "F.Cu" "B.Cu")
		(net "GND")
	)
	(via
		(at 203.33081 -36.59124)
		(size 0.508)
		(drill 0.254)
		(layers "F.Cu" "B.Cu")
		(net "GND")
	)
	(via
		(at 33.7058 -40.2844)
		(size 0.508)
		(drill 0.254)
		(layers "F.Cu" "B.Cu")
		(net "GND")
	)
	(via
		(at 95.631 -66.919094)
		(size 0.508)
		(drill 0.254)
		(layers "F.Cu" "B.Cu")
		(net "GND")
	)
	(via
		(at 153.406856 -53.4416)
		(size 0.508)
		(drill 0.254)
		(layers "F.Cu" "B.Cu")
		(net "GND")
	)
	(via
		(at 46.8122 -19.939)
		(size 0.508)
		(drill 0.254)
		(layers "F.Cu" "B.Cu")
		(net "GND")
	)
	(via
		(at 26.5176 -14.6558)
		(size 0.508)
		(drill 0.254)
		(layers "F.Cu" "B.Cu")
		(net "GND")
	)
	(via
		(at 1.1176 -62.2554)
		(size 0.7112)
		(drill 0.4064)
		(layers "F.Cu" "B.Cu")
		(net "GND")
	)
	(via
		(at 173.1518 -5.208778)
		(size 0.4318)
		(drill 0.2032)
		(layers "F.Cu" "B.Cu")
		(net "GND")
	)
	(via
		(at 128.985518 -64.070992)
		(size 0.4318)
		(drill 0.2032)
		(layers "F.Cu" "B.Cu")
		(net "GND")
	)
	(via
		(at 197.739 -26.035)
		(size 0.7112)
		(drill 0.4064)
		(layers "F.Cu" "B.Cu")
		(net "GND")
	)
	(via
		(at 176.1998 -8.409178)
		(size 0.4318)
		(drill 0.2032)
		(layers "F.Cu" "B.Cu")
		(net "GND")
	)
	(via
		(at 86.692486 -34.455354)
		(size 0.4318)
		(drill 0.2032)
		(layers "F.Cu" "B.Cu")
		(net "GND")
	)
	(via
		(at 182.06593 -67.31)
		(size 0.4318)
		(drill 0.2032)
		(layers "F.Cu" "B.Cu")
		(net "GND")
	)
	(via
		(at 53.5686 -14.6304)
		(size 0.508)
		(drill 0.254)
		(layers "F.Cu" "B.Cu")
		(net "GND")
	)
	(via
		(at 99.822 -59.9948)
		(size 0.508)
		(drill 0.254)
		(layers "F.Cu" "B.Cu")
		(net "GND")
	)
	(via
		(at 85.958934 -39.065708)
		(size 0.4318)
		(drill 0.2032)
		(layers "F.Cu" "B.Cu")
		(net "GND")
	)
	(via
		(at 143.62938 -8.454898)
		(size 0.4318)
		(drill 0.2032)
		(layers "F.Cu" "B.Cu")
		(net "GND")
	)
	(via
		(at 145.5928 -5.056378)
		(size 0.4318)
		(drill 0.2032)
		(layers "F.Cu" "B.Cu")
		(net "GND")
	)
	(via
		(at 186.302396 -8.46836)
		(size 0.4318)
		(drill 0.2032)
		(layers "F.Cu" "B.Cu")
		(net "GND")
	)
	(via
		(at 116.2558 -42.5196)
		(size 0.4318)
		(drill 0.2032)
		(layers "F.Cu" "B.Cu")
		(net "GND")
	)
	(via
		(at 164.6428 -67.3862)
		(size 0.4318)
		(drill 0.2032)
		(layers "F.Cu" "B.Cu")
		(net "GND")
	)
	(via
		(at 140.5255 -8.434578)
		(size 0.4318)
		(drill 0.2032)
		(layers "F.Cu" "B.Cu")
		(net "GND")
	)
	(via
		(at 103.0478 -62.611)
		(size 0.508)
		(drill 0.254)
		(layers "F.Cu" "B.Cu")
		(net "GND")
	)
	(via
		(at 171.69638 -8.449818)
		(size 0.4318)
		(drill 0.2032)
		(layers "F.Cu" "B.Cu")
		(net "GND")
	)
	(via
		(at 109.865668 -34.772092)
		(size 0.4318)
		(drill 0.2032)
		(layers "F.Cu" "B.Cu")
		(net "GND")
	)
	(via
		(at 99.665028 -25.945846)
		(size 0.4318)
		(drill 0.2032)
		(layers "F.Cu" "B.Cu")
		(net "GND")
	)
	(via
		(at 84.721954 -29.23286)
		(size 0.4318)
		(drill 0.2032)
		(layers "F.Cu" "B.Cu")
		(net "GND")
	)
	(via
		(at 82.6262 -28.5242)
		(size 0.4318)
		(drill 0.2032)
		(layers "F.Cu" "B.Cu")
		(net "GND")
	)
	(via
		(at 46.99 -13.1064)
		(size 0.508)
		(drill 0.254)
		(layers "F.Cu" "B.Cu")
		(net "GND")
	)
	(via
		(at 10.3124 -64.135)
		(size 0.508)
		(drill 0.254)
		(layers "F.Cu" "B.Cu")
		(net "GND")
	)
	(via
		(at 1.143 -58.1406)
		(size 0.7112)
		(drill 0.4064)
		(layers "F.Cu" "B.Cu")
		(net "GND")
	)
	(via
		(at 86.233 -25.908)
		(size 0.4318)
		(drill 0.2032)
		(layers "F.Cu" "B.Cu")
		(net "GND")
	)
	(via
		(at 107.111038 -44.208446)
		(size 0.4318)
		(drill 0.2032)
		(layers "F.Cu" "B.Cu")
		(net "GND")
	)
	(via
		(at 135.86587 -69.366638)
		(size 0.4318)
		(drill 0.2032)
		(layers "F.Cu" "B.Cu")
		(net "GND")
	)
	(via
		(at 10.2108 -60.5282)
		(size 0.508)
		(drill 0.254)
		(layers "F.Cu" "B.Cu")
		(net "GND")
	)
	(via
		(at 176.657 -69.3674)
		(size 0.4318)
		(drill 0.2032)
		(layers "F.Cu" "B.Cu")
		(net "GND")
	)
	(via
		(at 106.51236 -43.307)
		(size 0.4318)
		(drill 0.2032)
		(layers "F.Cu" "B.Cu")
		(net "GND")
	)
	(via
		(at 191.056514 -37.239702)
		(size 0.508)
		(drill 0.254)
		(layers "F.Cu" "B.Cu")
		(net "GND")
	)
	(via
		(at 2.589276 -64.748918)
		(size 0.508)
		(drill 0.254)
		(layers "F.Cu" "B.Cu")
		(net "GND")
	)
	(via
		(at 81.79054 -30.117542)
		(size 0.4318)
		(drill 0.2032)
		(layers "F.Cu" "B.Cu")
		(net "GND")
	)
	(via
		(at 41.148 -58.547)
		(size 0.508)
		(drill 0.254)
		(layers "F.Cu" "B.Cu")
		(net "GND")
	)
	(via
		(at 87.842598 -50.771298)
		(size 0.4318)
		(drill 0.2032)
		(layers "F.Cu" "B.Cu")
		(net "GND")
	)
	(via
		(at 175.895 -26.924)
		(size 0.7112)
		(drill 0.3556)
		(layers "F.Cu" "B.Cu")
		(net "GND")
	)
	(via
		(at 173.2026 -64.135)
		(size 0.4318)
		(drill 0.2032)
		(layers "F.Cu" "B.Cu")
		(net "GND")
	)
	(via
		(at 106.2482 -24.0792)
		(size 0.4318)
		(drill 0.2032)
		(layers "F.Cu" "B.Cu")
		(net "GND")
	)
	(via
		(at 95.9612 -28.464002)
		(size 0.4318)
		(drill 0.2032)
		(layers "F.Cu" "B.Cu")
		(net "GND")
	)
	(via
		(at 146.9644 -5.157978)
		(size 0.4318)
		(drill 0.2032)
		(layers "F.Cu" "B.Cu")
		(net "GND")
	)
	(via
		(at 11.6332 -40.1574)
		(size 0.508)
		(drill 0.254)
		(layers "F.Cu" "B.Cu")
		(net "GND")
	)
	(via
		(at 174.671228 -69.313806)
		(size 0.4318)
		(drill 0.2032)
		(layers "F.Cu" "B.Cu")
		(net "GND")
	)
	(via
		(at 101.5492 -56.0324)
		(size 0.4318)
		(drill 0.2032)
		(layers "F.Cu" "B.Cu")
		(net "GND")
	)
	(via
		(at 98.298 -36.39312)
		(size 0.4318)
		(drill 0.2032)
		(layers "F.Cu" "B.Cu")
		(net "GND")
	)
	(via
		(at 84.575396 -53.561996)
		(size 0.4318)
		(drill 0.2032)
		(layers "F.Cu" "B.Cu")
		(net "GND")
	)
	(via
		(at 142.748 -36.8046)
		(size 0.508)
		(drill 0.254)
		(layers "F.Cu" "B.Cu")
		(net "GND")
	)
	(via
		(at 24.5872 -13.5382)
		(size 0.508)
		(drill 0.254)
		(layers "F.Cu" "B.Cu")
		(net "GND")
	)
	(via
		(at 52.30368 -56.2737)
		(size 0.508)
		(drill 0.254)
		(layers "F.Cu" "B.Cu")
		(net "GND")
	)
	(via
		(at 9.5504 -52.7812)
		(size 0.508)
		(drill 0.254)
		(layers "F.Cu" "B.Cu")
		(net "GND")
	)
	(via
		(at 98.298 -39.5859)
		(size 0.4318)
		(drill 0.2032)
		(layers "F.Cu" "B.Cu")
		(net "GND")
	)
	(via
		(at 16.891 -9.561068)
		(size 0.508)
		(drill 0.254)
		(layers "F.Cu" "B.Cu")
		(net "GND")
	)
	(via
		(at 99.822 -35.628072)
		(size 0.4318)
		(drill 0.2032)
		(layers "F.Cu" "B.Cu")
		(net "GND")
	)
	(via
		(at 194.056 -51.38674)
		(size 0.7112)
		(drill 0.4064)
		(layers "F.Cu" "B.Cu")
		(net "GND")
	)
	(via
		(at 150.9268 -8.536178)
		(size 0.4318)
		(drill 0.2032)
		(layers "F.Cu" "B.Cu")
		(net "GND")
	)
	(via
		(at 12.827 -40.64)
		(size 0.7112)
		(drill 0.4064)
		(layers "F.Cu" "B.Cu")
		(net "GND")
	)
	(via
		(at 173.04512 -8.46836)
		(size 0.4318)
		(drill 0.2032)
		(layers "F.Cu" "B.Cu")
		(net "GND")
	)
	(via
		(at 169.776394 -37.614606)
		(size 0.7112)
		(drill 0.4064)
		(layers "F.Cu" "B.Cu")
		(net "GND")
	)
	(via
		(at 14.605 -24.511)
		(size 0.508)
		(drill 0.254)
		(layers "F.Cu" "B.Cu")
		(net "GND")
	)
	(via
		(at 18.796 -9.561068)
		(size 0.508)
		(drill 0.254)
		(layers "F.Cu" "B.Cu")
		(net "GND")
	)
	(via
		(at 103.844598 -38.051486)
		(size 0.4318)
		(drill 0.2032)
		(layers "F.Cu" "B.Cu")
		(net "GND")
	)
	(via
		(at 199.136 -7.874)
		(size 0.5588)
		(drill 0.3048)
		(layers "F.Cu" "B.Cu")
		(net "GND")
	)
	(via
		(at 78.2828 -49.6824)
		(size 0.4318)
		(drill 0.2032)
		(layers "F.Cu" "B.Cu")
		(net "GND")
	)
	(via
		(at 176.24044 -64.06134)
		(size 0.4318)
		(drill 0.2032)
		(layers "F.Cu" "B.Cu")
		(net "GND")
	)
	(via
		(at 189.1792 -8.383778)
		(size 0.4318)
		(drill 0.2032)
		(layers "F.Cu" "B.Cu")
		(net "GND")
	)
	(via
		(at 195.0974 -22.606)
		(size 0.7112)
		(drill 0.4064)
		(layers "F.Cu" "B.Cu")
		(net "GND")
	)
	(via
		(at 113.03 -49.403)
		(size 0.4318)
		(drill 0.2032)
		(layers "F.Cu" "B.Cu")
		(net "GND")
	)
	(via
		(at 133.7564 -46.609)
		(size 0.508)
		(drill 0.254)
		(layers "F.Cu" "B.Cu")
		(net "GND")
	)
	(via
		(at 97.2058 -57.404)
		(size 0.4318)
		(drill 0.2032)
		(layers "F.Cu" "B.Cu")
		(net "GND")
	)
	(via
		(at 187.833 -29.1846)
		(size 0.508)
		(drill 0.254)
		(layers "F.Cu" "B.Cu")
		(net "GND")
	)
	(via
		(at 180.3908 -51.2318)
		(size 0.7112)
		(drill 0.4064)
		(layers "F.Cu" "B.Cu")
		(net "GND")
	)
	(via
		(at 142.747746 -17.7038)
		(size 0.508)
		(drill 0.254)
		(layers "F.Cu" "B.Cu")
		(net "GND")
	)
	(via
		(at 84.14766 -31.95574)
		(size 0.4318)
		(drill 0.2032)
		(layers "F.Cu" "B.Cu")
		(net "GND")
	)
	(via
		(at 32.385 -50.038)
		(size 0.7112)
		(drill 0.3556)
		(layers "F.Cu" "B.Cu")
		(net "GND")
	)
	(via
		(at 91.729814 -26.441146)
		(size 0.4318)
		(drill 0.2032)
		(layers "F.Cu" "B.Cu")
		(net "GND")
	)
	(via
		(at 190.627 -41.148)
		(size 0.508)
		(drill 0.254)
		(layers "F.Cu" "B.Cu")
		(net "GND")
	)
	(via
		(at 86.875366 -49.892458)
		(size 0.4318)
		(drill 0.2032)
		(layers "F.Cu" "B.Cu")
		(net "GND")
	)
	(via
		(at 116.0526 -49.0982)
		(size 0.4318)
		(drill 0.2032)
		(layers "F.Cu" "B.Cu")
		(net "GND")
	)
	(via
		(at 101.7778 -27.6352)
		(size 0.4318)
		(drill 0.2032)
		(layers "F.Cu" "B.Cu")
		(net "GND")
	)
	(via
		(at 3.556 -27.813)
		(size 0.7112)
		(drill 0.4064)
		(layers "F.Cu" "B.Cu")
		(net "GND")
	)
	(via
		(at 52.7304 -9.561068)
		(size 0.508)
		(drill 0.254)
		(layers "F.Cu" "B.Cu")
		(net "GND")
	)
	(via
		(at 135.001 -55.753)
		(size 0.508)
		(drill 0.254)
		(layers "F.Cu" "B.Cu")
		(net "GND")
	)
	(via
		(at 36.84778 -9.561068)
		(size 0.508)
		(drill 0.254)
		(layers "F.Cu" "B.Cu")
		(net "GND")
	)
	(via
		(at 91.8718 -37.223446)
		(size 0.4318)
		(drill 0.2032)
		(layers "F.Cu" "B.Cu")
		(net "GND")
	)
	(via
		(at 8.001 -52.705)
		(size 0.508)
		(drill 0.254)
		(layers "F.Cu" "B.Cu")
		(net "GND")
	)
	(via
		(at 31.0515 -60.2742)
		(size 0.7112)
		(drill 0.4064)
		(layers "F.Cu" "B.Cu")
		(net "GND")
	)
	(via
		(at 97.74174 -52.96662)
		(size 0.4318)
		(drill 0.2032)
		(layers "F.Cu" "B.Cu")
		(net "GND")
	)
	(via
		(at 33.1216 -15.3924)
		(size 0.508)
		(drill 0.254)
		(layers "F.Cu" "B.Cu")
		(net "GND")
	)
	(via
		(at 100.9142 -23.6474)
		(size 0.4318)
		(drill 0.2032)
		(layers "F.Cu" "B.Cu")
		(net "GND")
	)
	(via
		(at 144.96161 -22.6314)
		(size 0.508)
		(drill 0.254)
		(layers "F.Cu" "B.Cu")
		(net "GND")
	)
	(via
		(at 141.5034 -34.544)
		(size 0.508)
		(drill 0.254)
		(layers "F.Cu" "B.Cu")
		(net "GND")
	)
	(via
		(at 93.728286 -47.292514)
		(size 0.4318)
		(drill 0.2032)
		(layers "F.Cu" "B.Cu")
		(net "GND")
	)
	(via
		(at 103.4796 -22.1996)
		(size 0.4318)
		(drill 0.2032)
		(layers "F.Cu" "B.Cu")
		(net "GND")
	)
	(via
		(at 4.953 -35.306)
		(size 0.7112)
		(drill 0.3556)
		(layers "F.Cu" "B.Cu")
		(net "GND")
	)
	(via
		(at 172.339 -35.941)
		(size 0.7112)
		(drill 0.4064)
		(layers "F.Cu" "B.Cu")
		(net "GND")
	)
	(via
		(at 66.5226 -11.4046)
		(size 0.508)
		(drill 0.254)
		(layers "F.Cu" "B.Cu")
		(net "GND")
	)
	(via
		(at 187.734194 -67.300348)
		(size 0.4318)
		(drill 0.2032)
		(layers "F.Cu" "B.Cu")
		(net "GND")
	)
	(via
		(at 82.08391 -43.671998)
		(size 0.4318)
		(drill 0.2032)
		(layers "F.Cu" "B.Cu")
		(net "GND")
	)
	(via
		(at 96.52 -66.919094)
		(size 0.508)
		(drill 0.254)
		(layers "F.Cu" "B.Cu")
		(net "GND")
	)
	(via
		(at 29.1592 -15.4178)
		(size 0.508)
		(drill 0.254)
		(layers "F.Cu" "B.Cu")
		(net "GND")
	)
	(via
		(at 80.996028 -18.197322)
		(size 0.508)
		(drill 0.254)
		(layers "F.Cu" "B.Cu")
		(net "GND")
	)
	(via
		(at 196.6722 -27.178)
		(size 0.7112)
		(drill 0.4064)
		(layers "F.Cu" "B.Cu")
		(net "GND")
	)
	(via
		(at 48.6156 -52.3494)
		(size 0.508)
		(drill 0.254)
		(layers "F.Cu" "B.Cu")
		(net "GND")
	)
	(via
		(at 48.4886 -71.3232)
		(size 0.7112)
		(drill 0.4064)
		(layers "F.Cu" "B.Cu")
		(net "GND")
	)
	(via
		(at 13.3858 -46.9392)
		(size 0.508)
		(drill 0.254)
		(layers "F.Cu" "B.Cu")
		(net "GND")
	)
	(via
		(at 178.1556 -24.9936)
		(size 0.7112)
		(drill 0.4064)
		(layers "F.Cu" "B.Cu")
		(net "GND")
	)
	(via
		(at 24.3078 -50.0888)
		(size 0.508)
		(drill 0.254)
		(layers "F.Cu" "B.Cu")
		(net "GND")
	)
	(via
		(at 30.8356 -15.2654)
		(size 0.508)
		(drill 0.254)
		(layers "F.Cu" "B.Cu")
		(net "GND")
	)
	(via
		(at 182.4609 -8.409178)
		(size 0.4318)
		(drill 0.2032)
		(layers "F.Cu" "B.Cu")
		(net "GND")
	)
	(via
		(at 109.63148 -39.27348)
		(size 0.4318)
		(drill 0.2032)
		(layers "F.Cu" "B.Cu")
		(net "GND")
	)
	(via
		(at 97.409 -66.919094)
		(size 0.508)
		(drill 0.254)
		(layers "F.Cu" "B.Cu")
		(net "GND")
	)
	(via
		(at 58.829194 -35.137344)
		(size 0.508)
		(drill 0.254)
		(layers "F.Cu" "B.Cu")
		(net "GND")
	)
	(via
		(at 24.257 -23.749)
		(size 0.7112)
		(drill 0.4064)
		(layers "F.Cu" "B.Cu")
		(net "GND")
	)
	(via
		(at 132.53466 -69.37756)
		(size 0.4318)
		(drill 0.2032)
		(layers "F.Cu" "B.Cu")
		(net "GND")
	)
	(via
		(at 159.385 -26.6446)
		(size 0.508)
		(drill 0.254)
		(layers "F.Cu" "B.Cu")
		(net "GND")
	)
	(via
		(at 85.598 -18.847308)
		(size 0.508)
		(drill 0.254)
		(layers "F.Cu" "B.Cu")
		(net "GND")
	)
	(via
		(at 90.0938 -50.7746)
		(size 0.4318)
		(drill 0.2032)
		(layers "F.Cu" "B.Cu")
		(net "GND")
	)
	(via
		(at 164.665914 -69.37756)
		(size 0.4318)
		(drill 0.2032)
		(layers "F.Cu" "B.Cu")
		(net "GND")
	)
	(via
		(at 118.364 -48.006)
		(size 0.4318)
		(drill 0.2032)
		(layers "F.Cu" "B.Cu")
		(net "GND")
	)
	(via
		(at 23.876 -34.925)
		(size 0.7112)
		(drill 0.4064)
		(layers "F.Cu" "B.Cu")
		(net "GND")
	)
	(via
		(at 19.8882 -16.3322)
		(size 0.508)
		(drill 0.254)
		(layers "F.Cu" "B.Cu")
		(net "GND")
	)
	(via
		(at 1.143 -59.6392)
		(size 0.7112)
		(drill 0.4064)
		(layers "F.Cu" "B.Cu")
		(net "GND")
	)
	(via
		(at 140.2334 -34.544)
		(size 0.508)
		(drill 0.254)
		(layers "F.Cu" "B.Cu")
		(net "GND")
	)
	(via
		(at 106.998262 -50.754788)
		(size 0.4318)
		(drill 0.2032)
		(layers "F.Cu" "B.Cu")
		(net "GND")
	)
	(via
		(at 108.453428 -33.358836)
		(size 0.4318)
		(drill 0.2032)
		(layers "F.Cu" "B.Cu")
		(net "GND")
	)
	(via
		(at 198.501 -12.954)
		(size 0.7112)
		(drill 0.4064)
		(layers "F.Cu" "B.Cu")
		(net "GND")
	)
	(via
		(at 152.627584 -3.151378)
		(size 0.4318)
		(drill 0.2032)
		(layers "F.Cu" "B.Cu")
		(net "GND")
	)
	(via
		(at 44.588684 -48.897286)
		(size 0.508)
		(drill 0.254)
		(layers "F.Cu" "B.Cu")
		(net "GND")
	)
	(via
		(at 92.6338 -38.789102)
		(size 0.4318)
		(drill 0.2032)
		(layers "F.Cu" "B.Cu")
		(net "GND")
	)
	(via
		(at 102.997 -33.290002)
		(size 0.4318)
		(drill 0.2032)
		(layers "F.Cu" "B.Cu")
		(net "GND")
	)
	(via
		(at 15.9512 -46.8122)
		(size 0.508)
		(drill 0.254)
		(layers "F.Cu" "B.Cu")
		(net "GND")
	)
	(via
		(at 181.356 -3.151378)
		(size 0.4318)
		(drill 0.2032)
		(layers "F.Cu" "B.Cu")
		(net "GND")
	)
	(via
		(at 140.4112 -64.8462)
		(size 0.4318)
		(drill 0.2032)
		(layers "F.Cu" "B.Cu")
		(net "GND")
	)
	(via
		(at 7.62 -49.8348)
		(size 0.508)
		(drill 0.254)
		(layers "F.Cu" "B.Cu")
		(net "GND")
	)
	(via
		(at 170.16222 -64.0461)
		(size 0.4318)
		(drill 0.2032)
		(layers "F.Cu" "B.Cu")
		(net "GND")
	)
	(via
		(at 96.9137 -29.8196)
		(size 0.4318)
		(drill 0.2032)
		(layers "F.Cu" "B.Cu")
		(net "GND")
	)
	(via
		(at 205.613 -63.881)
		(size 0.7112)
		(drill 0.4064)
		(layers "F.Cu" "B.Cu")
		(net "GND")
	)
	(via
		(at 129.2098 -4.370578)
		(size 0.4318)
		(drill 0.2032)
		(layers "F.Cu" "B.Cu")
		(net "GND")
	)
	(via
		(at 186.56554 -69.36994)
		(size 0.4318)
		(drill 0.2032)
		(layers "F.Cu" "B.Cu")
		(net "GND")
	)
	(via
		(at 1.1684 -56.6674)
		(size 0.7112)
		(drill 0.4064)
		(layers "F.Cu" "B.Cu")
		(net "GND")
	)
	(via
		(at 3.2004 -67.7926)
		(size 0.7112)
		(drill 0.4064)
		(layers "F.Cu" "B.Cu")
		(net "GND")
	)
	(via
		(at 144.5768 -56.7944)
		(size 0.508)
		(drill 0.254)
		(layers "F.Cu" "B.Cu")
		(net "GND")
	)
	(via
		(at 95.9612 -31.537402)
		(size 0.4318)
		(drill 0.2032)
		(layers "F.Cu" "B.Cu")
		(net "GND")
	)
	(via
		(at 72.39 -66.4718)
		(size 0.508)
		(drill 0.254)
		(layers "F.Cu" "B.Cu")
		(net "GND")
	)
	(via
		(at 67.2338 -15.0876)
		(size 0.508)
		(drill 0.254)
		(layers "F.Cu" "B.Cu")
		(net "GND")
	)
	(via
		(at 141.351 -22.606)
		(size 0.508)
		(drill 0.254)
		(layers "F.Cu" "B.Cu")
		(net "GND")
	)
	(via
		(at 201.29881 -36.59124)
		(size 0.508)
		(drill 0.254)
		(layers "F.Cu" "B.Cu")
		(net "GND")
	)
	(via
		(at 43.6372 -32.1564)
		(size 0.508)
		(drill 0.254)
		(layers "F.Cu" "B.Cu")
		(net "GND")
	)
	(via
		(at 47.649638 -33.959038)
		(size 0.508)
		(drill 0.254)
		(layers "F.Cu" "B.Cu")
		(net "GND")
	)
	(via
		(at 95.4532 -22.098)
		(size 0.4318)
		(drill 0.2032)
		(layers "F.Cu" "B.Cu")
		(net "GND")
	)
	(via
		(at 21.463 -57.15)
		(size 0.508)
		(drill 0.254)
		(layers "F.Cu" "B.Cu")
		(net "GND")
	)
	(via
		(at 199.26681 -36.59124)
		(size 0.508)
		(drill 0.254)
		(layers "F.Cu" "B.Cu")
		(net "GND")
	)
	(via
		(at 110.4138 -32.5628)
		(size 0.4318)
		(drill 0.2032)
		(layers "F.Cu" "B.Cu")
		(net "GND")
	)
	(via
		(at 79.6544 -60.3758)
		(size 0.4318)
		(drill 0.2032)
		(layers "F.Cu" "B.Cu")
		(net "GND")
	)
	(via
		(at 77.6986 -30.772354)
		(size 0.4318)
		(drill 0.2032)
		(layers "F.Cu" "B.Cu")
		(net "GND")
	)
	(via
		(at 32.851344 -9.563608)
		(size 0.508)
		(drill 0.254)
		(layers "F.Cu" "B.Cu")
		(net "GND")
	)
	(via
		(at 192.576704 -34.296096)
		(size 0.508)
		(drill 0.254)
		(layers "F.Cu" "B.Cu")
		(net "GND")
	)
	(via
		(at 106.577384 -28.819602)
		(size 0.4318)
		(drill 0.2032)
		(layers "F.Cu" "B.Cu")
		(net "GND")
	)
	(via
		(at 185.039 -3.938778)
		(size 0.4318)
		(drill 0.2032)
		(layers "F.Cu" "B.Cu")
		(net "GND")
	)
	(via
		(at 180.9623 -8.46836)
		(size 0.4318)
		(drill 0.2032)
		(layers "F.Cu" "B.Cu")
		(net "GND")
	)
	(via
		(at 185.928 -5.157978)
		(size 0.4318)
		(drill 0.2032)
		(layers "F.Cu" "B.Cu")
		(net "GND")
	)
	(via
		(at 109.908848 -43.807126)
		(size 0.4318)
		(drill 0.2032)
		(layers "F.Cu" "B.Cu")
		(net "GND")
	)
	(via
		(at 205.867 -49.911)
		(size 0.7112)
		(drill 0.4064)
		(layers "F.Cu" "B.Cu")
		(net "GND")
	)
	(via
		(at 79.11084 -43.707812)
		(size 0.4318)
		(drill 0.2032)
		(layers "F.Cu" "B.Cu")
		(net "GND")
	)
	(via
		(at 202.31481 -36.59124)
		(size 0.508)
		(drill 0.254)
		(layers "F.Cu" "B.Cu")
		(net "GND")
	)
	(via
		(at 84.687664 -27.660346)
		(size 0.4318)
		(drill 0.2032)
		(layers "F.Cu" "B.Cu")
		(net "GND")
	)
	(via
		(at 176.403 -40.386)
		(size 0.7112)
		(drill 0.4064)
		(layers "F.Cu" "B.Cu")
		(net "GND")
	)
	(via
		(at 98.989134 -36.40328)
		(size 0.4318)
		(drill 0.2032)
		(layers "F.Cu" "B.Cu")
		(net "GND")
	)
	(via
		(at 60.858146 -9.568942)
		(size 0.508)
		(drill 0.254)
		(layers "F.Cu" "B.Cu")
		(net "GND")
	)
	(via
		(at 131.191 -59.563)
		(size 0.508)
		(drill 0.254)
		(layers "F.Cu" "B.Cu")
		(net "GND")
	)
	(via
		(at 165.862 -67.2846)
		(size 0.4318)
		(drill 0.2032)
		(layers "F.Cu" "B.Cu")
		(net "GND")
	)
	(via
		(at 178.232816 -65.417446)
		(size 0.4318)
		(drill 0.2032)
		(layers "F.Cu" "B.Cu")
		(net "GND")
	)
	(via
		(at 109.347 -4.318)
		(size 0.508)
		(drill 0.254)
		(layers "F.Cu" "B.Cu")
		(net "GND")
	)
	(via
		(at 129.347976 -69.290184)
		(size 0.4318)
		(drill 0.2032)
		(layers "F.Cu" "B.Cu")
		(net "GND")
	)
	(via
		(at 198.882 -28.702)
		(size 0.7112)
		(drill 0.4064)
		(layers "F.Cu" "B.Cu")
		(net "GND")
	)
	(via
		(at 89.863168 -52.950364)
		(size 0.4318)
		(drill 0.2032)
		(layers "F.Cu" "B.Cu")
		(net "GND")
	)
	(via
		(at 203.33081 -37.60724)
		(size 0.508)
		(drill 0.254)
		(layers "F.Cu" "B.Cu")
		(net "GND")
	)
	(via
		(at 139.759436 -3.809238)
		(size 0.4318)
		(drill 0.2032)
		(layers "F.Cu" "B.Cu")
		(net "GND")
	)
	(via
		(at 104.981756 -39.346632)
		(size 0.4318)
		(drill 0.2032)
		(layers "F.Cu" "B.Cu")
		(net "GND")
	)
	(via
		(at 79.099918 -39.070534)
		(size 0.4318)
		(drill 0.2032)
		(layers "F.Cu" "B.Cu")
		(net "GND")
	)
	(via
		(at 112.903 -18.161)
		(size 0.7112)
		(drill 0.3556)
		(layers "F.Cu" "B.Cu")
		(net "GND")
	)
	(via
		(at 79.1464 -52.7304)
		(size 0.4318)
		(drill 0.2032)
		(layers "F.Cu" "B.Cu")
		(net "GND")
	)
	(via
		(at 55.118 -71.374)
		(size 0.7112)
		(drill 0.4064)
		(layers "F.Cu" "B.Cu")
		(net "GND")
	)
	(via
		(at 181.7878 -31.5468)
		(size 0.508)
		(drill 0.254)
		(layers "F.Cu" "B.Cu")
		(net "GND")
	)
	(via
		(at 194.183 -21.5392)
		(size 0.7112)
		(drill 0.4064)
		(layers "F.Cu" "B.Cu")
		(net "GND")
	)
	(via
		(at 120.396 -2.286)
		(size 0.7112)
		(drill 0.4064)
		(layers "F.Cu" "B.Cu")
		(net "GND")
	)
	(via
		(at 176.4284 -58.3692)
		(size 0.508)
		(drill 0.254)
		(layers "F.Cu" "B.Cu")
		(net "GND")
	)
	(via
		(at 82.3468 -40.0812)
		(size 0.4318)
		(drill 0.2032)
		(layers "F.Cu" "B.Cu")
		(net "GND")
	)
	(via
		(at 65.278 -54.229)
		(size 0.7112)
		(drill 0.4064)
		(layers "F.Cu" "B.Cu")
		(net "GND")
	)
	(via
		(at 1.2446 -72.5678)
		(size 0.7112)
		(drill 0.4064)
		(layers "F.Cu" "B.Cu")
		(net "GND")
	)
	(via
		(at 130.81 -30.29458)
		(size 0.508)
		(drill 0.254)
		(layers "F.Cu" "B.Cu")
		(net "GND")
	)
	(via
		(at 92.71 -24.0538)
		(size 0.4318)
		(drill 0.2032)
		(layers "F.Cu" "B.Cu")
		(net "GND")
	)
	(via
		(at 140.843 -67.2846)
		(size 0.4318)
		(drill 0.2032)
		(layers "F.Cu" "B.Cu")
		(net "GND")
	)
	(via
		(at 184.28462 -3.176778)
		(size 0.4318)
		(drill 0.2032)
		(layers "F.Cu" "B.Cu")
		(net "GND")
	)
	(via
		(at 51.435 -24.638)
		(size 0.508)
		(drill 0.254)
		(layers "F.Cu" "B.Cu")
		(net "GND")
	)
	(via
		(at 176.1744 -55.7022)
		(size 0.7112)
		(drill 0.3556)
		(layers "F.Cu" "B.Cu")
		(net "GND")
	)
	(via
		(at 187.1726 -41.2242)
		(size 0.508)
		(drill 0.254)
		(layers "F.Cu" "B.Cu")
		(net "GND")
	)
	(via
		(at 181.483 -21.717)
		(size 0.7112)
		(drill 0.4064)
		(layers "F.Cu" "B.Cu")
		(net "GND")
	)
	(via
		(at 58.175144 -21.082)
		(size 0.508)
		(drill 0.254)
		(layers "F.Cu" "B.Cu")
		(net "GND")
	)
	(via
		(at 112.5474 -49.7586)
		(size 0.4318)
		(drill 0.2032)
		(layers "F.Cu" "B.Cu")
		(net "GND")
	)
	(via
		(at 79.055468 -40.317928)
		(size 0.4318)
		(drill 0.2032)
		(layers "F.Cu" "B.Cu")
		(net "GND")
	)
	(via
		(at 135.3566 -64.8462)
		(size 0.4318)
		(drill 0.2032)
		(layers "F.Cu" "B.Cu")
		(net "GND")
	)
	(via
		(at 88.011 -52.9209)
		(size 0.4318)
		(drill 0.2032)
		(layers "F.Cu" "B.Cu")
		(net "GND")
	)
	(via
		(at 208.6864 -72.517)
		(size 0.7112)
		(drill 0.4064)
		(layers "F.Cu" "B.Cu")
		(net "GND")
	)
	(via
		(at 51.118008 -34.992564)
		(size 0.508)
		(drill 0.254)
		(layers "F.Cu" "B.Cu")
		(net "GND")
	)
	(via
		(at 120.269 -39.1287)
		(size 0.508)
		(drill 0.254)
		(layers "F.Cu" "B.Cu")
		(net "GND")
	)
	(via
		(at 31.43504 -48.620426)
		(size 0.508)
		(drill 0.254)
		(layers "F.Cu" "B.Cu")
		(net "GND")
	)
	(via
		(at 27.686 -34.0487)
		(size 0.7112)
		(drill 0.4064)
		(layers "F.Cu" "B.Cu")
		(net "GND")
	)
	(via
		(at 45.847 -56.769)
		(size 0.7112)
		(drill 0.3556)
		(layers "F.Cu" "B.Cu")
		(net "GND")
	)
	(via
		(at 138.418316 -46.6344)
		(size 0.508)
		(drill 0.254)
		(layers "F.Cu" "B.Cu")
		(net "GND")
	)
	(via
		(at 78.828392 -9.6266)
		(size 0.508)
		(drill 0.254)
		(layers "F.Cu" "B.Cu")
		(net "GND")
	)
	(via
		(at 80.01 -16.891)
		(size 0.7112)
		(drill 0.3556)
		(layers "F.Cu" "B.Cu")
		(net "GND")
	)
	(segment
		(start 142.2908 -45.0596)
		(end 142.2908 -45.466)
		(width 0.3048)
		(layer "B.Cu")
		(net "GND")
	)
	(segment
		(start 72.517 -35.7378)
		(end 71.9582 -35.179)
		(width 0.3048)
		(layer "B.Cu")
		(net "GND")
	)
	(segment
		(start 62.865 -16.564864)
		(end 63.35014 -17.050004)
		(width 0.508)
		(layer "B.Cu")
		(net "GND")
	)
	(segment
		(start 42.33037 -22.40915)
		(end 40.15867 -24.58085)
		(width 0.3048)
		(layer "B.Cu")
		(net "GND")
	)
	(segment
		(start 39.574724 -42.672)
		(end 39.878 -42.975276)
		(width 0.3048)
		(layer "B.Cu")
		(net "GND")
	)
	(segment
		(start 171.423076 -64.080644)
		(end 171.388024 -64.080644)
		(width 0.254)
		(layer "B.Cu")
		(net "GND")
	)
	(segment
		(start 72.009 -63.9064)
		(end 72.48525 -63.43015)
		(width 0.3048)
		(layer "B.Cu")
		(net "GND")
	)
	(segment
		(start 143.9672 -44.704)
		(end 142.6464 -44.704)
		(width 0.3048)
		(layer "B.Cu")
		(net "GND")
	)
	(segment
		(start 164.5412 -63.843662)
		(end 164.5412 -64.0842)
		(width 0.3048)
		(layer "B.Cu")
		(net "GND")
	)
	(segment
		(start 143.649954 -1.690624)
		(end 143.649954 -2.997962)
		(width 0.254)
		(layer "B.Cu")
		(net "GND")
	)
	(segment
		(start 43.5356 -28.7528)
		(end 43.5356 -32.0548)
		(width 0.508)
		(layer "B.Cu")
		(net "GND")
	)
	(segment
		(start 45.2882 -53.4162)
		(end 45.2882 -54.102)
		(width 0.3048)
		(layer "B.Cu")
		(net "GND")
	)
	(segment
		(start 138.549888 -9.89076)
		(end 138.549888 -9.026398)
		(width 0.254)
		(layer "B.Cu")
		(net "GND")
	)
	(segment
		(start 89.662 -38.0492)
		(end 89.73566 -37.97554)
		(width 0.3048)
		(layer "B.Cu")
		(net "GND")
	)
	(segment
		(start 28.349956 -9.061196)
		(end 28.85567 -9.56691)
		(width 0.7112)
		(layer "B.Cu")
		(net "GND")
	)
	(segment
		(start 128.649984 -3.201162)
		(end 128.7272 -3.278378)
		(width 0.254)
		(layer "B.Cu")
		(net "GND")
	)
	(segment
		(start 62.18174 -45.18152)
		(end 62.18174 -43.78452)
		(width 0.508)
		(layer "B.Cu")
		(net "GND")
	)
	(segment
		(start 176.650142 -70.79996)
		(end 176.650142 -69.374258)
		(width 0.3048)
		(layer "B.Cu")
		(net "GND")
	)
	(segment
		(start 177.54981 -9.89076)
		(end 177.54981 -8.94715)
		(width 0.254)
		(layer "B.Cu")
		(net "GND")
	)
	(segment
		(start 82.828384 -9.619488)
		(end 82.828384 -9.6266)
		(width 0.7112)
		(layer "B.Cu")
		(net "GND")
	)
	(segment
		(start 67.104006 -24.956008)
		(end 67.104006 -24.959056)
		(width 0.3048)
		(layer "B.Cu")
		(net "GND")
	)
	(segment
		(start 73.6092 -35.941)
		(end 73.406 -35.7378)
		(width 0.3048)
		(layer "B.Cu")
		(net "GND")
	)
	(segment
		(start 112.79124 -7.410196)
		(end 112.974882 -7.226554)
		(width 0.3048)
		(layer "B.Cu")
		(net "GND")
	)
	(segment
		(start 52.349908 -5.814568)
		(end 52.349908 -9.180576)
		(width 0.7112)
		(layer "B.Cu")
		(net "GND")
	)
	(segment
		(start 36.34994 -9.063228)
		(end 36.84778 -9.561068)
		(width 0.7112)
		(layer "B.Cu")
		(net "GND")
	)
	(segment
		(start 129.55016 -63.50635)
		(end 128.985518 -64.070992)
		(width 0.254)
		(layer "B.Cu")
		(net "GND")
	)
	(segment
		(start 31.3182 -45.212)
		(end 31.75 -45.212)
		(width 0.3556)
		(layer "B.Cu")
		(net "GND")
	)
	(segment
		(start 148.149818 -9.07796)
		(end 148.7297 -8.498078)
		(width 0.254)
		(layer "B.Cu")
		(net "GND")
	)
	(segment
		(start 36.449 -21.7932)
		(end 38.432994 -21.7932)
		(width 0.508)
		(layer "B.Cu")
		(net "GND")
	)
	(segment
		(start 51.34991 -9.087358)
		(end 50.8762 -9.561068)
		(width 0.7112)
		(layer "B.Cu")
		(net "GND")
	)
	(segment
		(start 36.5252 -27.686)
		(end 36.5252 -26.9494)
		(width 0.508)
		(layer "B.Cu")
		(net "GND")
	)
	(segment
		(start 145.449798 -1.690878)
		(end 145.449798 -2.924556)
		(width 0.254)
		(layer "B.Cu")
		(net "GND")
	)
	(segment
		(start 73.7362 -39.243)
		(end 73.7362 -40.005)
		(width 0.3048)
		(layer "B.Cu")
		(net "GND")
	)
	(segment
		(start 72.349868 -9.078468)
		(end 72.8726 -9.6012)
		(width 0.7112)
		(layer "B.Cu")
		(net "GND")
	)
	(segment
		(start 40.51681 -24.93899)
		(end 40.15867 -24.58085)
		(width 0.3048)
		(layer "B.Cu")
		(net "GND")
	)
	(segment
		(start 43.349926 -9.098026)
		(end 42.874946 -9.573006)
		(width 0.7112)
		(layer "B.Cu")
		(net "GND")
	)
	(segment
		(start 139.015724 -8.560562)
		(end 139.015724 -8.416036)
		(width 0.254)
		(layer "B.Cu")
		(net "GND")
	)
	(segment
		(start 205.6257 -72.6567)
		(end 197.637654 -72.6567)
		(width 0.3048)
		(layer "B.Cu")
		(net "GND")
	)
	(segment
		(start 23.349966 -5.814568)
		(end 23.349966 -9.088628)
		(width 0.7112)
		(layer "B.Cu")
		(net "GND")
	)
	(segment
		(start 45.258736 -45.309536)
		(end 45.258736 -46.087792)
		(width 0.2032)
		(layer "B.Cu")
		(net "GND")
	)
	(segment
		(start 136.750044 -9.89076)
		(end 136.750044 -8.735822)
		(width 0.3048)
		(layer "B.Cu")
		(net "GND")
	)
	(segment
		(start 178.150266 -62.600078)
		(end 178.150266 -63.464186)
		(width 0.254)
		(layer "B.Cu")
		(net "GND")
	)
	(segment
		(start 47.02175 -18.6563)
		(end 47.02175 -19.72945)
		(width 0.3048)
		(layer "B.Cu")
		(net "GND")
	)
	(segment
		(start 137.442956 -2.799842)
		(end 137.442956 -3.125978)
		(width 0.254)
		(layer "B.Cu")
		(net "GND")
	)
	(segment
		(start 48.349916 -9.041384)
		(end 48.8696 -9.561068)
		(width 0.7112)
		(layer "B.Cu")
		(net "GND")
	)
	(segment
		(start 180.850032 -70.79996)
		(end 180.850032 -69.922898)
		(width 0.3048)
		(layer "B.Cu")
		(net "GND")
	)
	(segment
		(start 142.450058 -69.913246)
		(end 142.1384 -69.601588)
		(width 0.3048)
		(layer "B.Cu")
		(net "GND")
	)
	(segment
		(start 133.75005 -62.599824)
		(end 133.75005 -63.82385)
		(width 0.254)
		(layer "B.Cu")
		(net "GND")
	)
	(segment
		(start 130.449828 -2.956306)
		(end 130.64744 -3.153918)
		(width 0.254)
		(layer "B.Cu")
		(net "GND")
	)
	(segment
		(start 99.832668 -35.63874)
		(end 99.822 -35.628072)
		(width 0.3048)
		(layer "B.Cu")
		(net "GND")
	)
	(segment
		(start 42.0878 -51.6636)
		(end 41.3512 -52.4002)
		(width 0.3048)
		(layer "B.Cu")
		(net "GND")
	)
	(segment
		(start 46.8884 -28.7528)
		(end 46.8884 -28.8036)
		(width 0.3048)
		(layer "B.Cu")
		(net "GND")
	)
	(segment
		(start 148.7297 -8.498078)
		(end 148.7297 -8.46836)
		(width 0.254)
		(layer "B.Cu")
		(net "GND")
	)
	(segment
		(start 141.849856 -3.147314)
		(end 141.845792 -3.151378)
		(width 0.254)
		(layer "B.Cu")
		(net "GND")
	)
	(segment
		(start 5.575046 -59.949842)
		(end 4.1402 -59.949842)
		(width 0.3048)
		(layer "B.Cu")
		(net "GND")
	)
	(segment
		(start 60.349892 -5.814568)
		(end 60.349892 -9.060688)
		(width 0.7112)
		(layer "B.Cu")
		(net "GND")
	)
	(segment
		(start 91.960446 -37.1348)
		(end 91.8718 -37.223446)
		(width 0.3048)
		(layer "B.Cu")
		(net "GND")
	)
	(segment
		(start 141.245844 -1.694688)
		(end 141.245844 -2.522474)
		(width 0.254)
		(layer "B.Cu")
		(net "GND")
	)
	(segment
		(start 164.650166 -69.466714)
		(end 164.650166 -70.79996)
		(width 0.3048)
		(layer "B.Cu")
		(net "GND")
	)
	(segment
		(start 187.449968 -2.95021)
		(end 187.2742 -3.125978)
		(width 0.254)
		(layer "B.Cu")
		(net "GND")
	)
	(segment
		(start 132.249926 -2.797302)
		(end 132.12064 -2.926588)
		(width 0.254)
		(layer "B.Cu")
		(net "GND")
	)
	(segment
		(start 39.6494 -46.2026)
		(end 40.1066 -46.6598)
		(width 0.3048)
		(layer "B.Cu")
		(net "GND")
	)
	(segment
		(start 143.77416 -3.122168)
		(end 143.77416 -3.128518)
		(width 0.254)
		(layer "B.Cu")
		(net "GND")
	)
	(segment
		(start 16.2052 -56.4388)
		(end 16.2052 -60.8838)
		(width 0.3048)
		(layer "B.Cu")
		(net "GND")
	)
	(segment
		(start 95.3516 -9.4488)
		(end 95.3516 -9.5758)
		(width 0.7112)
		(layer "B.Cu")
		(net "GND")
	)
	(segment
		(start 187.749942 -64.064642)
		(end 187.8965 -64.2112)
		(width 0.3048)
		(layer "B.Cu")
		(net "GND")
	)
	(segment
		(start 36.5252 -26.9494)
		(end 36.4998 -26.924)
		(width 0.508)
		(layer "B.Cu")
		(net "GND")
	)
	(segment
		(start 35.337242 -9.098026)
		(end 34.8742 -9.561068)
		(width 0.7112)
		(layer "B.Cu")
		(net "GND")
	)
	(segment
		(start 99.949 -21.4884)
		(end 98.933 -21.4884)
		(width 0.381)
		(layer "B.Cu")
		(net "GND")
	)
	(segment
		(start 55.349902 -9.098534)
		(end 54.88559 -9.562846)
		(width 0.7112)
		(layer "B.Cu")
		(net "GND")
	)
	(segment
		(start 149.049994 -2.726944)
		(end 148.66112 -3.115818)
		(width 0.254)
		(layer "B.Cu")
		(net "GND")
	)
	(segment
		(start 179.649882 -1.690624)
		(end 179.649882 -2.914396)
		(width 0.254)
		(layer "B.Cu")
		(net "GND")
	)
	(segment
		(start 39.0652 -42.672)
		(end 39.574724 -42.672)
		(width 0.3048)
		(layer "B.Cu")
		(net "GND")
	)
	(segment
		(start 164.650166 -70.79996)
		(end 164.650166 -71.950834)
		(width 0.3048)
		(layer "B.Cu")
		(net "GND")
	)
	(segment
		(start 176.949862 -9.13384)
		(end 176.276 -8.459978)
		(width 0.254)
		(layer "B.Cu")
		(net "GND")
	)
	(segment
		(start 152.2222 -36.8046)
		(end 152.2222 -36.068)
		(width 0.3048)
		(layer "B.Cu")
		(net "GND")
	)
	(segment
		(start 69.977 -61.2648)
		(end 69.215 -61.2648)
		(width 0.3048)
		(layer "B.Cu")
		(net "GND")
	)
	(segment
		(start 23.349966 -9.088628)
		(end 22.824948 -9.613646)
		(width 0.7112)
		(layer "B.Cu")
		(net "GND")
	)
	(segment
		(start 83.349846 -5.814568)
		(end 83.349846 -9.098026)
		(width 0.7112)
		(layer "B.Cu")
		(net "GND")
	)
	(segment
		(start 76.8096 -9.6012)
		(end 76.8604 -9.6012)
		(width 0.7112)
		(layer "B.Cu")
		(net "GND")
	)
	(segment
		(start 141.5288 -45.466)
		(end 142.2908 -45.466)
		(width 0.3048)
		(layer "B.Cu")
		(net "GND")
	)
	(segment
		(start 137.349992 -62.599824)
		(end 137.349992 -64.045592)
		(width 0.254)
		(layer "B.Cu")
		(net "GND")
	)
	(segment
		(start 173.03496 -3.164078)
		(end 173.04512 -3.164078)
		(width 0.254)
		(layer "B.Cu")
		(net "GND")
	)
	(segment
		(start 67.82435 -25.6794)
		(end 68.58 -25.6794)
		(width 0.3048)
		(layer "B.Cu")
		(net "GND")
	)
	(segment
		(start 118.6688 -3.36804)
		(end 119.09552 -3.79476)
		(width 0.3048)
		(layer "B.Cu")
		(net "GND")
	)
	(segment
		(start 141.249908 -1.690624)
		(end 141.245844 -1.694688)
		(width 0.254)
		(layer "B.Cu")
		(net "GND")
	)
	(segment
		(start 145.450052 -1.690624)
		(end 145.449798 -1.690878)
		(width 0.254)
		(layer "B.Cu")
		(net "GND")
	)
	(segment
		(start 43.01871 -17.78)
		(end 42.8498 -17.61109)
		(width 0.3048)
		(layer "B.Cu")
		(net "GND")
	)
	(segment
		(start 76.367894 -9.159494)
		(end 76.8096 -9.6012)
		(width 0.7112)
		(layer "B.Cu")
		(net "GND")
	)
	(segment
		(start 38.432994 -21.7932)
		(end 38.813994 -21.4122)
		(width 0.508)
		(layer "B.Cu")
		(net "GND")
	)
	(segment
		(start 49.14519 -21.265896)
		(end 50.399696 -21.265896)
		(width 0.3048)
		(layer "B.Cu")
		(net "GND")
	)
	(segment
		(start 176.04994 -2.86766)
		(end 176.3268 -3.14452)
		(width 0.254)
		(layer "B.Cu")
		(net "GND")
	)
	(segment
		(start 182.050182 -70.79996)
		(end 182.050182 -69.365622)
		(width 0.3048)
		(layer "B.Cu")
		(net "GND")
	)
	(segment
		(start 179.349908 -9.89076)
		(end 179.349908 -8.734552)
		(width 0.254)
		(layer "B.Cu")
		(net "GND")
	)
	(segment
		(start 79.1464 -53.7464)
		(end 79.1464 -52.7304)
		(width 0.3048)
		(layer "B.Cu")
		(net "GND")
	)
	(segment
		(start 144.8562 -22.73681)
		(end 144.8562 -23.495)
		(width 0.3048)
		(layer "B.Cu")
		(net "GND")
	)
	(segment
		(start 147.249896 -2.660142)
		(end 146.96948 -2.940558)
		(width 0.254)
		(layer "B.Cu")
		(net "GND")
	)
	(segment
		(start 64.349884 -5.814568)
		(end 64.349884 -9.140952)
		(width 0.7112)
		(layer "B.Cu")
		(net "GND")
	)
	(segment
		(start 183.850026 -1.690624)
		(end 183.850026 -2.597404)
		(width 0.254)
		(layer "B.Cu")
		(net "GND")
	)
	(segment
		(start 61.29655 -39.98595)
		(end 61.7093 -39.5732)
		(width 0.508)
		(layer "B.Cu")
		(net "GND")
	)
	(segment
		(start 72.39 -36.9824)
		(end 72.39 -38.0746)
		(width 0.3048)
		(layer "B.Cu")
		(net "GND")
	)
	(segment
		(start 69.744082 -33.66516)
		(end 69.43852 -33.970722)
		(width 0.254)
		(layer "B.Cu")
		(net "GND")
	)
	(segment
		(start 52.07 -24.003)
		(end 51.435 -24.638)
		(width 0.3048)
		(layer "B.Cu")
		(net "GND")
	)
	(segment
		(start 207.0608 -39.7002)
		(end 206.3242 -38.9636)
		(width 0.508)
		(layer "B.Cu")
		(net "GND")
	)
	(segment
		(start 56.3499 -5.814568)
		(end 56.3499 -9.059672)
		(width 0.7112)
		(layer "B.Cu")
		(net "GND")
	)
	(segment
		(start 186.5376 -69.39788)
		(end 186.56554 -69.36994)
		(width 0.3048)
		(layer "B.Cu")
		(net "GND")
	)
	(segment
		(start 83.349846 -9.098026)
		(end 82.828384 -9.619488)
		(width 0.7112)
		(layer "B.Cu")
		(net "GND")
	)
	(segment
		(start 175.150018 -9.086596)
		(end 174.7266 -8.663178)
		(width 0.254)
		(layer "B.Cu")
		(net "GND")
	)
	(segment
		(start 48.058578 -51.70678)
		(end 48.058578 -51.995578)
		(width 0.2032)
		(layer "B.Cu")
		(net "GND")
	)
	(segment
		(start 189.1792 -8.383778)
		(end 188.949838 -8.61314)
		(width 0.254)
		(layer "B.Cu")
		(net "GND")
	)
	(segment
		(start 134.050024 -1.690624)
		(end 134.050024 -2.596388)
		(width 0.254)
		(layer "B.Cu")
		(net "GND")
	)
	(segment
		(start 90.39098 -37.8714)
		(end 91.186 -37.8714)
		(width 0.3048)
		(layer "B.Cu")
		(net "GND")
	)
	(segment
		(start 70.2564 -59.8678)
		(end 70.7898 -60.4012)
		(width 0.3048)
		(layer "B.Cu")
		(net "GND")
	)
	(segment
		(start 40.01643 -25.8445)
		(end 40.01643 -24.72309)
		(width 0.3048)
		(layer "B.Cu")
		(net "GND")
	)
	(segment
		(start 20.349972 -5.814568)
		(end 20.349972 -9.056116)
		(width 0.7112)
		(layer "B.Cu")
		(net "GND")
	)
	(segment
		(start 62.1284 -28.702)
		(end 62.1284 -27.2288)
		(width 0.508)
		(layer "B.Cu")
		(net "GND")
	)
	(segment
		(start 99.617784 -33.290002)
		(end 99.597464 -33.269682)
		(width 0.381)
		(layer "B.Cu")
		(net "GND")
	)
	(segment
		(start 164.665914 -69.37756)
		(end 164.665914 -69.450966)
		(width 0.3048)
		(layer "B.Cu")
		(net "GND")
	)
	(segment
		(start 135.265668 -8.710676)
		(end 135.265668 -8.459978)
		(width 0.3048)
		(layer "B.Cu")
		(net "GND")
	)
	(segment
		(start 48.668178 -52.296822)
		(end 48.668178 -51.09718)
		(width 0.2032)
		(layer "B.Cu")
		(net "GND")
	)
	(segment
		(start 63.35014 -17.050004)
		(end 64.9478 -18.647664)
		(width 0.2032)
		(layer "B.Cu")
		(net "GND")
	)
	(segment
		(start 38.9382 -14.605)
		(end 38.9382 -14.17701)
		(width 0.3048)
		(layer "B.Cu")
		(net "GND")
	)
	(segment
		(start 169.450004 -69.536056)
		(end 169.672 -69.31406)
		(width 0.3048)
		(layer "B.Cu")
		(net "GND")
	)
	(segment
		(start 146.96948 -2.940558)
		(end 146.96948 -3.138678)
		(width 0.254)
		(layer "B.Cu")
		(net "GND")
	)
	(segment
		(start 146.349974 -8.991854)
		(end 145.750026 -8.391906)
		(width 0.254)
		(layer "B.Cu")
		(net "GND")
	)
	(segment
		(start 42.342816 -50.697384)
		(end 43.04919 -50.697384)
		(width 0.2032)
		(layer "B.Cu")
		(net "GND")
	)
	(segment
		(start 60.43295 -14.478)
		(end 61.0108 -15.05585)
		(width 0.381)
		(layer "B.Cu")
		(net "GND")
	)
	(segment
		(start 188.05017 -69.579744)
		(end 187.918852 -69.448426)
		(width 0.3048)
		(layer "B.Cu")
		(net "GND")
	)
	(segment
		(start 42.4942 -17.2212)
		(end 42.545 -17.272)
		(width 0.3048)
		(layer "B.Cu")
		(net "GND")
	)
	(segment
		(start 132.12064 -2.926588)
		(end 132.12064 -2.942336)
		(width 0.254)
		(layer "B.Cu")
		(net "GND")
	)
	(segment
		(start 43.51909 -26.590244)
		(end 43.2308 -26.878534)
		(width 0.3048)
		(layer "B.Cu")
		(net "GND")
	)
	(segment
		(start 119.048784 -6.096)
		(end 118.5672 -6.096)
		(width 0.3048)
		(layer "B.Cu")
		(net "GND")
	)
	(segment
		(start 41.3512 -52.4002)
		(end 40.894 -52.4002)
		(width 0.3048)
		(layer "B.Cu")
		(net "GND")
	)
	(segment
		(start 138.7602 -23.622)
		(end 138.7602 -24.384)
		(width 0.3048)
		(layer "B.Cu")
		(net "GND")
	)
	(segment
		(start 135.550148 -63.541148)
		(end 135.914892 -63.905892)
		(width 0.254)
		(layer "B.Cu")
		(net "GND")
	)
	(segment
		(start 69.43852 -33.970722)
		(end 69.43852 -35.43808)
		(width 0.254)
		(layer "B.Cu")
		(net "GND")
	)
	(segment
		(start 141.550136 -63.343536)
		(end 142.3162 -64.1096)
		(width 0.254)
		(layer "B.Cu")
		(net "GND")
	)
	(segment
		(start 19.939 -65.2018)
		(end 19.939 -65.9384)
		(width 0.2032)
		(layer "B.Cu")
		(net "GND")
	)
	(segment
		(start 95.65132 -46.89094)
		(end 95.65132 -46.148244)
		(width 0.3048)
		(layer "B.Cu")
		(net "GND")
	)
	(segment
		(start 145.4912 -69.3928)
		(end 145.4658 -69.3674)
		(width 0.254)
		(layer "B.Cu")
		(net "GND")
	)
	(segment
		(start 99.597464 -33.269682)
		(end 99.126802 -33.269682)
		(width 0.381)
		(layer "B.Cu")
		(net "GND")
	)
	(segment
		(start 164.349938 -63.6524)
		(end 164.5412 -63.843662)
		(width 0.3048)
		(layer "B.Cu")
		(net "GND")
	)
	(segment
		(start 78.867 -15.24)
		(end 79.145892 -14.961108)
		(width 0.508)
		(layer "B.Cu")
		(net "GND")
	)
	(segment
		(start 43.01871 -18.6563)
		(end 43.01871 -17.78)
		(width 0.3048)
		(layer "B.Cu")
		(net "GND")
	)
	(segment
		(start 84.349844 -9.242044)
		(end 84.7598 -9.652)
		(width 0.7112)
		(layer "B.Cu")
		(net "GND")
	)
	(segment
		(start 89.73566 -37.97554)
		(end 90.28684 -37.97554)
		(width 0.3048)
		(layer "B.Cu")
		(net "GND")
	)
	(segment
		(start 179.5526 -69.424804)
		(end 179.5526 -69.342)
		(width 0.254)
		(layer "B.Cu")
		(net "GND")
	)
	(segment
		(start 54.88559 -9.71931)
		(end 57.56656 -12.40028)
		(width 0.3048)
		(layer "B.Cu")
		(net "GND")
	)
	(segment
		(start 90.28684 -37.97554)
		(end 90.39098 -37.8714)
		(width 0.3048)
		(layer "B.Cu")
		(net "GND")
	)
	(segment
		(start 133.2738 -31.115)
		(end 133.2738 -31.877)
		(width 0.3048)
		(layer "B.Cu")
		(net "GND")
	)
	(segment
		(start 40.1066 -30.9372)
		(end 40.9956 -30.0482)
		(width 0.3048)
		(layer "B.Cu")
		(net "GND")
	)
	(segment
		(start 62.18174 -43.78452)
		(end 61.29655 -42.89933)
		(width 0.508)
		(layer "B.Cu")
		(net "GND")
	)
	(segment
		(start 97.917 -52.105052)
		(end 97.699576 -52.322476)
		(width 0.3048)
		(layer "B.Cu")
		(net "GND")
	)
	(segment
		(start 35.349942 -5.814568)
		(end 35.349942 -9.098026)
		(width 0.7112)
		(layer "B.Cu")
		(net "GND")
	)
	(segment
		(start 16.34998 -9.020048)
		(end 16.891 -9.561068)
		(width 0.508)
		(layer "B.Cu")
		(net "GND")
	)
	(segment
		(start 182.050182 -69.365622)
		(end 182.051198 -69.364606)
		(width 0.3048)
		(layer "B.Cu")
		(net "GND")
	)
	(segment
		(start 33.021016 -54.0512)
		(end 34.021014 -53.051202)
		(width 0.3048)
		(layer "B.Cu")
		(net "GND")
	)
	(segment
		(start 40.51681 -25.8445)
		(end 40.51681 -24.93899)
		(width 0.3048)
		(layer "B.Cu")
		(net "GND")
	)
	(segment
		(start 47.583598 -29.498798)
		(end 47.844202 -29.498798)
		(width 0.3048)
		(layer "B.Cu")
		(net "GND")
	)
	(segment
		(start 31.069026 -46.272704)
		(end 31.069026 -45.461174)
		(width 0.3556)
		(layer "B.Cu")
		(net "GND")
	)
	(segment
		(start 52.349908 -9.180576)
		(end 52.7304 -9.561068)
		(width 0.7112)
		(layer "B.Cu")
		(net "GND")
	)
	(segment
		(start 38.39718 -30.9372)
		(end 38.27018 -31.0642)
		(width 0.3048)
		(layer "B.Cu")
		(net "GND")
	)
	(segment
		(start 164.665914 -69.450966)
		(end 164.650166 -69.466714)
		(width 0.3048)
		(layer "B.Cu")
		(net "GND")
	)
	(segment
		(start 36.4998 -25.0698)
		(end 36.449 -25.019)
		(width 0.508)
		(layer "B.Cu")
		(net "GND")
	)
	(segment
		(start 174.850044 -69.466206)
		(end 174.697644 -69.313806)
		(width 0.3048)
		(layer "B.Cu")
		(net "GND")
	)
	(segment
		(start 176.276 -8.459978)
		(end 176.2506 -8.459978)
		(width 0.254)
		(layer "B.Cu")
		(net "GND")
	)
	(segment
		(start 132.249926 -1.690624)
		(end 132.249926 -2.797302)
		(width 0.254)
		(layer "B.Cu")
		(net "GND")
	)
	(segment
		(start 146.349974 -9.89076)
		(end 146.349974 -8.991854)
		(width 0.254)
		(layer "B.Cu")
		(net "GND")
	)
	(segment
		(start 62.093602 -30.731206)
		(end 62.924944 -29.899864)
		(width 0.508)
		(layer "B.Cu")
		(net "GND")
	)
	(segment
		(start 100.584 -45.4406)
		(end 100.584 -45.466)
		(width 0.3048)
		(layer "B.Cu")
		(net "GND")
	)
	(segment
		(start 169.450004 -70.79996)
		(end 169.450004 -69.536056)
		(width 0.3048)
		(layer "B.Cu")
		(net "GND")
	)
	(segment
		(start 143.34998 -62.599824)
		(end 143.34998 -63.39078)
		(width 0.254)
		(layer "B.Cu")
		(net "GND")
	)
	(segment
		(start 137.649966 -2.592832)
		(end 137.442956 -2.799842)
		(width 0.254)
		(layer "B.Cu")
		(net "GND")
	)
	(segment
		(start 135.849868 -1.690624)
		(end 135.849868 -2.81051)
		(width 0.254)
		(layer "B.Cu")
		(net "GND")
	)
	(segment
		(start 61.7093 -38.4937)
		(end 61.7093 -39.5732)
		(width 0.508)
		(layer "B.Cu")
		(net "GND")
	)
	(segment
		(start 148.149818 -9.89076)
		(end 148.149818 -9.07796)
		(width 0.254)
		(layer "B.Cu")
		(net "GND")
	)
	(segment
		(start 51.7398 -49.53)
		(end 51.5366 -49.3268)
		(width 0.3048)
		(layer "B.Cu")
		(net "GND")
	)
	(segment
		(start 71.42226 -31.9024)
		(end 69.342 -31.9024)
		(width 0.508)
		(layer "B.Cu")
		(net "GND")
	)
	(segment
		(start 68.326 -35.9156)
		(end 68.206874 -36.034726)
		(width 0.3048)
		(layer "B.Cu")
		(net "GND")
	)
	(segment
		(start 45.2882 -54.102)
		(end 44.3738 -54.102)
		(width 0.3048)
		(layer "B.Cu")
		(net "GND")
	)
	(segment
		(start 87.5538 -45.608748)
		(end 87.772748 -45.3898)
		(width 0.3048)
		(layer "B.Cu")
		(net "GND")
	)
	(segment
		(start 32.258 -54.0512)
		(end 33.021016 -54.0512)
		(width 0.3048)
		(layer "B.Cu")
		(net "GND")
	)
	(segment
		(start 143.802354 -63.843154)
		(end 143.802354 -64.03721)
		(width 0.254)
		(layer "B.Cu")
		(net "GND")
	)
	(segment
		(start 176.276 -41.6306)
		(end 176.276 -40.513)
		(width 0.3048)
		(layer "B.Cu")
		(net "GND")
	)
	(segment
		(start 63.349886 -9.076182)
		(end 62.865 -9.561068)
		(width 0.7112)
		(layer "B.Cu")
		(net "GND")
	)
	(segment
		(start 186.250072 -69.922898)
		(end 186.5376 -69.63537)
		(width 0.3048)
		(layer "B.Cu")
		(net "GND")
	)
	(segment
		(start 174.7266 -8.663178)
		(end 174.7266 -8.465058)
		(width 0.254)
		(layer "B.Cu")
		(net "GND")
	)
	(segment
		(start 68.3006 -46.1264)
		(end 68.3006 -47.600108)
		(width 0.3048)
		(layer "B.Cu")
		(net "GND")
	)
	(segment
		(start 5.575046 -65.94983)
		(end 4.292346 -65.94983)
		(width 0.3048)
		(layer "B.Cu")
		(net "GND")
	)
	(segment
		(start 143.949928 -9.89076)
		(end 143.949928 -8.775446)
		(width 0.254)
		(layer "B.Cu")
		(net "GND")
	)
	(segment
		(start 77.47 -61.4172)
		(end 76.708 -61.4172)
		(width 0.3048)
		(layer "B.Cu")
		(net "GND")
	)
	(segment
		(start 184.749948 -9.89076)
		(end 184.749948 -8.755126)
		(width 0.254)
		(layer "B.Cu")
		(net "GND")
	)
	(segment
		(start 59.349894 -5.814568)
		(end 59.349894 -9.096248)
		(width 0.7112)
		(layer "B.Cu")
		(net "GND")
	)
	(segment
		(start 57.275984 -20.699984)
		(end 57.658 -21.082)
		(width 0.508)
		(layer "B.Cu")
		(net "GND")
	)
	(segment
		(start 184.55513 -64.153542)
		(end 184.3913 -64.153542)
		(width 0.254)
		(layer "B.Cu")
		(net "GND")
	)
	(segment
		(start 132.12064 -2.942336)
		(end 131.934204 -3.128772)
		(width 0.254)
		(layer "B.Cu")
		(net "GND")
	)
	(segment
		(start 143.649954 -2.997962)
		(end 143.77416 -3.122168)
		(width 0.254)
		(layer "B.Cu")
		(net "GND")
	)
	(segment
		(start 16.891 -9.561068)
		(end 16.647668 -9.8044)
		(width 0.508)
		(layer "B.Cu")
		(net "GND")
	)
	(segment
		(start 95.65132 -46.148244)
		(end 95.692468 -46.107096)
		(width 0.3048)
		(layer "B.Cu")
		(net "GND")
	)
	(segment
		(start 63.349886 -5.814568)
		(end 63.349886 -9.076182)
		(width 0.7112)
		(layer "B.Cu")
		(net "GND")
	)
	(segment
		(start 50.52441 -17.78381)
		(end 50.52441 -18.6563)
		(width 0.3048)
		(layer "B.Cu")
		(net "GND")
	)
	(segment
		(start 53.3654 -34.4932)
		(end 53.3654 -34.086038)
		(width 0.508)
		(layer "B.Cu")
		(net "GND")
	)
	(segment
		(start 152.349962 -9.89076)
		(end 152.349962 -8.596376)
		(width 0.3048)
		(layer "B.Cu")
		(net "GND")
	)
	(segment
		(start 57.096914 -30.299914)
		(end 58.829194 -32.032194)
		(width 0.3048)
		(layer "B.Cu")
		(net "GND")
	)
	(segment
		(start 184.449974 -69.894196)
		(end 184.8612 -69.48297)
		(width 0.3048)
		(layer "B.Cu")
		(net "GND")
	)
	(segment
		(start 76.371958 -59.8424)
		(end 76.7588 -60.229242)
		(width 0.3048)
		(layer "B.Cu")
		(net "GND")
	)
	(segment
		(start 48.4124 -52.3494)
		(end 48.6156 -52.3494)
		(width 0.2032)
		(layer "B.Cu")
		(net "GND")
	)
	(segment
		(start 145.750026 -8.391906)
		(end 145.603468 -8.245348)
		(width 0.254)
		(layer "B.Cu")
		(net "GND")
	)
	(segment
		(start 76.708 -60.827412)
		(end 76.708 -61.4172)
		(width 0.3048)
		(layer "B.Cu")
		(net "GND")
	)
	(segment
		(start 68.6308 -45.7962)
		(end 68.3006 -46.1264)
		(width 0.3048)
		(layer "B.Cu")
		(net "GND")
	)
	(segment
		(start 45.085 -52.8066)
		(end 45.085 -53.213)
		(width 0.2032)
		(layer "B.Cu")
		(net "GND")
	)
	(segment
		(start 68.13804 -43.079924)
		(end 69.294502 -44.236386)
		(width 0.3048)
		(layer "B.Cu")
		(net "GND")
	)
	(segment
		(start 119.75592 -5.388864)
		(end 119.048784 -6.096)
		(width 0.3048)
		(layer "B.Cu")
		(net "GND")
	)
	(segment
		(start 187.149994 -9.89076)
		(end 187.149994 -8.83158)
		(width 0.254)
		(layer "B.Cu")
		(net "GND")
	)
	(segment
		(start 56.631586 -42.29989)
		(end 55.753508 -42.29989)
		(width 0.3048)
		(layer "B.Cu")
		(net "GND")
	)
	(segment
		(start 186.550046 -9.89076)
		(end 186.550046 -8.701024)
		(width 0.254)
		(layer "B.Cu")
		(net "GND")
	)
	(segment
		(start 5.575046 -67.449954)
		(end 4.292346 -67.449954)
		(width 0.3048)
		(layer "B.Cu")
		(net "GND")
	)
	(segment
		(start 133.8072 -46.5582)
		(end 133.8072 -45.5676)
		(width 0.3048)
		(layer "B.Cu")
		(net "GND")
	)
	(segment
		(start 174.249842 -1.690624)
		(end 174.249842 -2.733294)
		(width 0.254)
		(layer "B.Cu")
		(net "GND")
	)
	(segment
		(start 145.4912 -69.4182)
		(end 145.4912 -69.3928)
		(width 0.254)
		(layer "B.Cu")
		(net "GND")
	)
	(segment
		(start 42.4942 -15.5702)
		(end 42.4942 -17.2212)
		(width 0.3048)
		(layer "B.Cu")
		(net "GND")
	)
	(segment
		(start 144.96161 -22.6314)
		(end 144.8562 -22.73681)
		(width 0.3048)
		(layer "B.Cu")
		(net "GND")
	)
	(segment
		(start 54.243732 -25.019)
		(end 54.250336 -25.025604)
		(width 0.508)
		(layer "B.Cu")
		(net "GND")
	)
	(segment
		(start 43.349926 -5.814568)
		(end 43.349926 -9.098026)
		(width 0.7112)
		(layer "B.Cu")
		(net "GND")
	)
	(segment
		(start 141.849856 -1.690624)
		(end 141.849856 -3.147314)
		(width 0.254)
		(layer "B.Cu")
		(net "GND")
	)
	(segment
		(start 38.227 -46.482)
		(end 39.37 -46.482)
		(width 0.508)
		(layer "B.Cu")
		(net "GND")
	)
	(segment
		(start 4.394454 -53.949854)
		(end 5.575046 -53.949854)
		(width 0.3048)
		(layer "B.Cu")
		(net "GND")
	)
	(segment
		(start 55.753508 -30.299914)
		(end 57.096914 -30.299914)
		(width 0.3048)
		(layer "B.Cu")
		(net "GND")
	)
	(segment
		(start 71.501 -36.0934)
		(end 71.628 -35.9664)
		(width 0.3048)
		(layer "B.Cu")
		(net "GND")
	)
	(segment
		(start 191.135 -12.447778)
		(end 191.135 -12.041378)
		(width 0.381)
		(layer "B.Cu")
		(net "GND")
	)
	(segment
		(start 63.946532 -36.108132)
		(end 63.946532 -37.899848)
		(width 0.508)
		(layer "B.Cu")
		(net "GND")
	)
	(segment
		(start 91.8718 -38.5826)
		(end 92.423996 -38.5826)
		(width 0.3048)
		(layer "B.Cu")
		(net "GND")
	)
	(segment
		(start 144.8562 -23.495)
		(end 145.6182 -23.495)
		(width 0.3048)
		(layer "B.Cu")
		(net "GND")
	)
	(segment
		(start 19.939 -65.9384)
		(end 19.9898 -65.9892)
		(width 0.2032)
		(layer "B.Cu")
		(net "GND")
	)
	(segment
		(start 55.753508 -20.699984)
		(end 57.275984 -20.699984)
		(width 0.508)
		(layer "B.Cu")
		(net "GND")
	)
	(segment
		(start 5.575046 -64.44996)
		(end 4.292346 -64.44996)
		(width 0.3048)
		(layer "B.Cu")
		(net "GND")
	)
	(segment
		(start 172.749972 -62.599824)
		(end 172.749972 -63.682372)
		(width 0.3048)
		(layer "B.Cu")
		(net "GND")
	)
	(segment
		(start 128.949958 -8.631936)
		(end 128.651 -8.332978)
		(width 0.3048)
		(layer "B.Cu")
		(net "GND")
	)
	(segment
		(start 131.05003 -70.79996)
		(end 131.05003 -69.571616)
		(width 0.254)
		(layer "B.Cu")
		(net "GND")
	)
	(segment
		(start 181.150006 -8.656066)
		(end 180.9623 -8.46836)
		(width 0.254)
		(layer "B.Cu")
		(net "GND")
	)
	(segment
		(start 64.9478 -18.647664)
		(end 64.9478 -19.652234)
		(width 0.2032)
		(layer "B.Cu")
		(net "GND")
	)
	(segment
		(start 57.518808 -37.4142)
		(end 57.3786 -37.554408)
		(width 0.3048)
		(layer "B.Cu")
		(net "GND")
	)
	(segment
		(start 54.250336 -25.025604)
		(end 54.250336 -26.792936)
		(width 0.508)
		(layer "B.Cu")
		(net "GND")
	)
	(segment
		(start 176.350168 -62.599824)
		(end 176.350168 -63.951612)
		(width 0.3048)
		(layer "B.Cu")
		(net "GND")
	)
	(segment
		(start 47.02175 -19.72945)
		(end 46.8122 -19.939)
		(width 0.3048)
		(layer "B.Cu")
		(net "GND")
	)
	(segment
		(start 44.642532 -14.689582)
		(end 45.0342 -15.08125)
		(width 0.3048)
		(layer "B.Cu")
		(net "GND")
	)
	(segment
		(start 53.3654 -34.086038)
		(end 53.951378 -33.50006)
		(width 0.508)
		(layer "B.Cu")
		(net "GND")
	)
	(segment
		(start 98.933 -69.9262)
		(end 98.443796 -69.436996)
		(width 0.3048)
		(layer "B.Cu")
		(net "GND")
	)
	(segment
		(start 171.85005 -1.690624)
		(end 171.85005 -2.990088)
		(width 0.254)
		(layer "B.Cu")
		(net "GND")
	)
	(segment
		(start 48.058578 -51.995578)
		(end 48.4124 -52.3494)
		(width 0.2032)
		(layer "B.Cu")
		(net "GND")
	)
	(segment
		(start 76.367894 -5.832602)
		(end 76.367894 -9.159494)
		(width 0.7112)
		(layer "B.Cu")
		(net "GND")
	)
	(segment
		(start 149.049994 -1.690624)
		(end 149.049994 -2.726944)
		(width 0.254)
		(layer "B.Cu")
		(net "GND")
	)
	(segment
		(start 186.550046 -8.701024)
		(end 186.317382 -8.46836)
		(width 0.254)
		(layer "B.Cu")
		(net "GND")
	)
	(segment
		(start 95.60306 -49.04486)
		(end 95.7072 -49.149)
		(width 0.3048)
		(layer "B.Cu")
		(net "GND")
	)
	(segment
		(start 182.049928 -1.690624)
		(end 182.049928 -2.532126)
		(width 0.254)
		(layer "B.Cu")
		(net "GND")
	)
	(segment
		(start 131.350004 -62.599824)
		(end 131.350004 -63.925196)
		(width 0.254)
		(layer "B.Cu")
		(net "GND")
	)
	(segment
		(start 20.349972 -9.056116)
		(end 20.881594 -9.587738)
		(width 0.7112)
		(layer "B.Cu")
		(net "GND")
	)
	(segment
		(start 62.103 -39.5732)
		(end 61.7093 -39.5732)
		(width 0.508)
		(layer "B.Cu")
		(net "GND")
	)
	(segment
		(start 133.2738 -36.840414)
		(end 133.2738 -37.719)
		(width 0.3048)
		(layer "B.Cu")
		(net "GND")
	)
	(segment
		(start 90.236802 -39.6748)
		(end 90.274902 -39.6367)
		(width 0.3048)
		(layer "B.Cu")
		(net "GND")
	)
	(segment
		(start 178.150266 -63.464186)
		(end 177.7492 -63.865252)
		(width 0.254)
		(layer "B.Cu")
		(net "GND")
	)
	(segment
		(start 152.1968 -36.83)
		(end 152.2222 -36.8046)
		(width 0.3048)
		(layer "B.Cu")
		(net "GND")
	)
	(segment
		(start 185.35015 -62.599824)
		(end 185.35015 -63.358522)
		(width 0.254)
		(layer "B.Cu")
		(net "GND")
	)
	(segment
		(start 177.25009 -70.79996)
		(end 177.25009 -69.99351)
		(width 0.3048)
		(layer "B.Cu")
		(net "GND")
	)
	(segment
		(start 80.349852 -9.14146)
		(end 80.784192 -9.5758)
		(width 0.7112)
		(layer "B.Cu")
		(net "GND")
	)
	(segment
		(start 44.642532 -13.431266)
		(end 44.642532 -14.689582)
		(width 0.3048)
		(layer "B.Cu")
		(net "GND")
	)
	(segment
		(start 62.865 -15.24)
		(end 62.865 -16.564864)
		(width 0.508)
		(layer "B.Cu")
		(net "GND")
	)
	(segment
		(start 99.832668 -36.353496)
		(end 99.832668 -35.63874)
		(width 0.3048)
		(layer "B.Cu")
		(net "GND")
	)
	(segment
		(start 171.549822 -8.603996)
		(end 171.69638 -8.457438)
		(width 0.254)
		(layer "B.Cu")
		(net "GND")
	)
	(segment
		(start 36.4998 -26.924)
		(end 36.4998 -25.0698)
		(width 0.508)
		(layer "B.Cu")
		(net "GND")
	)
	(segment
		(start 40.9956 -30.0482)
		(end 40.9956 -28.7528)
		(width 0.3048)
		(layer "B.Cu")
		(net "GND")
	)
	(segment
		(start 172.749972 -63.682372)
		(end 173.2026 -64.135)
		(width 0.3048)
		(layer "B.Cu")
		(net "GND")
	)
	(segment
		(start 171.388024 -64.080644)
		(end 171.357544 -64.111124)
		(width 0.254)
		(layer "B.Cu")
		(net "GND")
	)
	(segment
		(start 143.949928 -8.775446)
		(end 143.62938 -8.454898)
		(width 0.254)
		(layer "B.Cu")
		(net "GND")
	)
	(segment
		(start 164.650166 -71.950834)
		(end 164.211 -72.39)
		(width 0.3048)
		(layer "B.Cu")
		(net "GND")
	)
	(segment
		(start 44.349924 -5.814568)
		(end 44.349924 -9.05891)
		(width 0.7112)
		(layer "B.Cu")
		(net "GND")
	)
	(segment
		(start 44.349924 -9.05891)
		(end 44.86656 -9.575546)
		(width 0.7112)
		(layer "B.Cu")
		(net "GND")
	)
	(segment
		(start 179.050188 -69.927216)
		(end 179.5526 -69.424804)
		(width 0.254)
		(layer "B.Cu")
		(net "GND")
	)
	(segment
		(start 177.25009 -69.99351)
		(end 177.8762 -69.3674)
		(width 0.3048)
		(layer "B.Cu")
		(net "GND")
	)
	(segment
		(start 152.349962 -8.596376)
		(end 152.49144 -8.454898)
		(width 0.3048)
		(layer "B.Cu")
		(net "GND")
	)
	(segment
		(start 71.628 -35.9664)
		(end 71.628 -35.5092)
		(width 0.3048)
		(layer "B.Cu")
		(net "GND")
	)
	(segment
		(start 179.95011 -63.464186)
		(end 179.712112 -63.702184)
		(width 0.3048)
		(layer "B.Cu")
		(net "GND")
	)
	(segment
		(start 42.70502 -51.09718)
		(end 42.1386 -51.6636)
		(width 0.2032)
		(layer "B.Cu")
		(net "GND")
	)
	(segment
		(start 135.894572 -69.39534)
		(end 135.86587 -69.366638)
		(width 0.3048)
		(layer "B.Cu")
		(net "GND")
	)
	(segment
		(start 40.105076 -42.7482)
		(end 39.878 -42.975276)
		(width 0.3048)
		(layer "B.Cu")
		(net "GND")
	)
	(segment
		(start 78.994 -35.999674)
		(end 78.554326 -35.999674)
		(width 0.3048)
		(layer "B.Cu")
		(net "GND")
	)
	(segment
		(start 145.3261 -64.0461)
		(end 145.3261 -64.0588)
		(width 0.254)
		(layer "B.Cu")
		(net "GND")
	)
	(segment
		(start 13.335 -35.433)
		(end 15.2908 -35.433)
		(width 0.3048)
		(layer "B.Cu")
		(net "GND")
	)
	(segment
		(start 172.150024 -62.599824)
		(end 172.150024 -63.353696)
		(width 0.254)
		(layer "B.Cu")
		(net "GND")
	)
	(segment
		(start 43.04919 -51.09718)
		(end 42.70502 -51.09718)
		(width 0.2032)
		(layer "B.Cu")
		(net "GND")
	)
	(segment
		(start 101.1682 -45.085)
		(end 100.9396 -45.085)
		(width 0.3048)
		(layer "B.Cu")
		(net "GND")
	)
	(segment
		(start 49.14519 -21.265896)
		(end 47.720504 -21.265896)
		(width 0.3048)
		(layer "B.Cu")
		(net "GND")
	)
	(segment
		(start 174.697644 -69.313806)
		(end 174.671228 -69.313806)
		(width 0.3048)
		(layer "B.Cu")
		(net "GND")
	)
	(segment
		(start 174.249842 -2.733294)
		(end 174.617126 -3.100578)
		(width 0.254)
		(layer "B.Cu")
		(net "GND")
	)
	(segment
		(start 69.215 -60.2996)
		(end 69.6468 -59.8678)
		(width 0.3048)
		(layer "B.Cu")
		(net "GND")
	)
	(segment
		(start 119.75592 -4.151376)
		(end 119.75592 -5.388864)
		(width 0.3048)
		(layer "B.Cu")
		(net "GND")
	)
	(segment
		(start 176.276 -40.513)
		(end 176.403 -40.386)
		(width 0.3048)
		(layer "B.Cu")
		(net "GND")
	)
	(segment
		(start 186.5376 -69.63537)
		(end 186.5376 -69.39788)
		(width 0.3048)
		(layer "B.Cu")
		(net "GND")
	)
	(segment
		(start 31.34995 -5.814568)
		(end 31.34995 -9.072118)
		(width 0.7112)
		(layer "B.Cu")
		(net "GND")
	)
	(segment
		(start 137.050018 -70.79996)
		(end 137.050018 -69.433186)
		(width 0.3048)
		(layer "B.Cu")
		(net "GND")
	)
	(segment
		(start 42.0878 -50.9524)
		(end 42.342816 -50.697384)
		(width 0.2032)
		(layer "B.Cu")
		(net "GND")
	)
	(segment
		(start 118.6688 -1.1176)
		(end 118.6688 -3.36804)
		(width 0.3048)
		(layer "B.Cu")
		(net "GND")
	)
	(segment
		(start 46.8884 -28.8036)
		(end 47.583598 -29.498798)
		(width 0.3048)
		(layer "B.Cu")
		(net "GND")
	)
	(segment
		(start 133.2738 -37.719)
		(end 133.2738 -38.481)
		(width 0.3048)
		(layer "B.Cu")
		(net "GND")
	)
	(segment
		(start 47.720504 -21.265896)
		(end 46.57725 -22.40915)
		(width 0.3048)
		(layer "B.Cu")
		(net "GND")
	)
	(segment
		(start 69.342 -31.9024)
		(end 69.1642 -32.0802)
		(width 0.508)
		(layer "B.Cu")
		(net "GND")
	)
	(segment
		(start 98.9838 -69.9262)
		(end 98.933 -69.9262)
		(width 0.3048)
		(layer "B.Cu")
		(net "GND")
	)
	(segment
		(start 52.6796 -24.003)
		(end 52.07 -24.003)
		(width 0.3048)
		(layer "B.Cu")
		(net "GND")
	)
	(segment
		(start 47.349918 -5.814568)
		(end 47.349918 -9.088882)
		(width 0.7112)
		(layer "B.Cu")
		(net "GND")
	)
	(segment
		(start 129.250186 -69.387974)
		(end 129.347976 -69.290184)
		(width 0.3048)
		(layer "B.Cu")
		(net "GND")
	)
	(segment
		(start 174.850044 -70.79996)
		(end 174.850044 -69.466206)
		(width 0.3048)
		(layer "B.Cu")
		(net "GND")
	)
	(segment
		(start 77.343 -55.5498)
		(end 79.1464 -53.7464)
		(width 0.3048)
		(layer "B.Cu")
		(net "GND")
	)
	(segment
		(start 41.5798 -14.605)
		(end 42.4942 -15.5194)
		(width 0.3048)
		(layer "B.Cu")
		(net "GND")
	)
	(segment
		(start 146.649948 -69.398134)
		(end 146.719544 -69.328538)
		(width 0.254)
		(layer "B.Cu")
		(net "GND")
	)
	(segment
		(start 62.093602 -33.18637)
		(end 62.093602 -30.731206)
		(width 0.508)
		(layer "B.Cu")
		(net "GND")
	)
	(segment
		(start 60.198 -14.478)
		(end 60.43295 -14.478)
		(width 0.381)
		(layer "B.Cu")
		(net "GND")
	)
	(segment
		(start 95.350076 -5.814568)
		(end 95.350076 -9.447276)
		(width 0.7112)
		(layer "B.Cu")
		(net "GND")
	)
	(segment
		(start 24.349964 -5.814568)
		(end 24.349964 -8.892032)
		(width 0.7112)
		(layer "B.Cu")
		(net "GND")
	)
	(segment
		(start 205.6638 -72.6186)
		(end 205.6257 -72.6567)
		(width 0.3048)
		(layer "B.Cu")
		(net "GND")
	)
	(segment
		(start 67.349878 -9.053322)
		(end 66.8274 -9.5758)
		(width 0.7112)
		(layer "B.Cu")
		(net "GND")
	)
	(segment
		(start 189.55004 -63.48984)
		(end 190.119 -64.0588)
		(width 0.3048)
		(layer "B.Cu")
		(net "GND")
	)
	(segment
		(start 130.2766 -59.5122)
		(end 130.3274 -59.563)
		(width 0.508)
		(layer "B.Cu")
		(net "GND")
	)
	(segment
		(start 131.350004 -9.045956)
		(end 131.9276 -8.46836)
		(width 0.254)
		(layer "B.Cu")
		(net "GND")
	)
	(segment
		(start 130.8862 -32.004)
		(end 130.8862 -31.115)
		(width 0.3048)
		(layer "B.Cu")
		(net "GND")
	)
	(segment
		(start 153.249884 -2.529078)
		(end 152.627584 -3.151378)
		(width 0.3048)
		(layer "B.Cu")
		(net "GND")
	)
	(segment
		(start 40.349932 -9.058656)
		(end 40.868092 -9.576816)
		(width 0.7112)
		(layer "B.Cu")
		(net "GND")
	)
	(segment
		(start 73.406 -35.7378)
		(end 72.517 -35.7378)
		(width 0.3048)
		(layer "B.Cu")
		(net "GND")
	)
	(segment
		(start 141.550136 -62.599824)
		(end 141.550136 -63.343536)
		(width 0.254)
		(layer "B.Cu")
		(net "GND")
	)
	(segment
		(start 182.65013 -69.9516)
		(end 183.23433 -69.3674)
		(width 0.3048)
		(layer "B.Cu")
		(net "GND")
	)
	(segment
		(start 172.449998 -1.690624)
		(end 172.449998 -2.579116)
		(width 0.254)
		(layer "B.Cu")
		(net "GND")
	)
	(segment
		(start 43.2308 -26.878534)
		(end 43.2308 -27.516582)
		(width 0.3048)
		(layer "B.Cu")
		(net "GND")
	)
	(segment
		(start 139.15009 -63.56731)
		(end 138.557 -64.1604)
		(width 0.254)
		(layer "B.Cu")
		(net "GND")
	)
	(segment
		(start 32.349948 -9.062212)
		(end 32.851344 -9.563608)
		(width 0.7112)
		(layer "B.Cu")
		(net "GND")
	)
	(segment
		(start 45.466 -15.5702)
		(end 45.0342 -15.5702)
		(width 0.3048)
		(layer "B.Cu")
		(net "GND")
	)
	(segment
		(start 181.150006 -9.89076)
		(end 181.150006 -8.656066)
		(width 0.254)
		(layer "B.Cu")
		(net "GND")
	)
	(segment
		(start 75.349862 -5.814568)
		(end 75.349862 -9.098026)
		(width 0.7112)
		(layer "B.Cu")
		(net "GND")
	)
	(segment
		(start 185.64987 -1.690624)
		(end 185.64987 -2.809748)
		(width 0.254)
		(layer "B.Cu")
		(net "GND")
	)
	(segment
		(start 194.945 -31.0388)
		(end 194.945 -29.21)
		(width 0.508)
		(layer "B.Cu")
		(net "GND")
	)
	(segment
		(start 187.149994 -63.811404)
		(end 186.673998 -64.2874)
		(width 0.3048)
		(layer "B.Cu")
		(net "GND")
	)
	(segment
		(start 68.206874 -36.034726)
		(end 68.1482 -36.034726)
		(width 0.3048)
		(layer "B.Cu")
		(net "GND")
	)
	(segment
		(start 27.349958 -9.095486)
		(end 26.871676 -9.573768)
		(width 0.7112)
		(layer "B.Cu")
		(net "GND")
	)
	(segment
		(start 42.4942 -15.5194)
		(end 42.4942 -15.5702)
		(width 0.3048)
		(layer "B.Cu")
		(net "GND")
	)
	(segment
		(start 81.031334 -32.8168)
		(end 81.361534 -33.147)
		(width 0.3048)
		(layer "B.Cu")
		(net "GND")
	)
	(segment
		(start 16.647668 -9.8044)
		(end 15.9004 -9.8044)
		(width 0.508)
		(layer "B.Cu")
		(net "GND")
	)
	(segment
		(start 176.3268 -3.14452)
		(end 176.3268 -3.430778)
		(width 0.254)
		(layer "B.Cu")
		(net "GND")
	)
	(segment
		(start 95.7072 -45.3644)
		(end 95.7072 -46.092364)
		(width 0.3048)
		(layer "B.Cu")
		(net "GND")
	)
	(segment
		(start 31.34995 -9.072118)
		(end 30.861 -9.561068)
		(width 0.7112)
		(layer "B.Cu")
		(net "GND")
	)
	(segment
		(start 75.349862 -9.098026)
		(end 74.821288 -9.6266)
		(width 0.7112)
		(layer "B.Cu")
		(net "GND")
	)
	(segment
		(start 31.069026 -45.461174)
		(end 31.3182 -45.212)
		(width 0.3556)
		(layer "B.Cu")
		(net "GND")
	)
	(segment
		(start 62.093602 -33.18637)
		(end 62.181232 -33.274)
		(width 0.508)
		(layer "B.Cu")
		(net "GND")
	)
	(segment
		(start 171.85005 -2.990088)
		(end 171.70146 -3.138678)
		(width 0.254)
		(layer "B.Cu")
		(net "GND")
	)
	(segment
		(start 45.258736 -51.70678)
		(end 45.258736 -52.632864)
		(width 0.2032)
		(layer "B.Cu")
		(net "GND")
	)
	(segment
		(start 134.649972 -70.79996)
		(end 134.649972 -69.900546)
		(width 0.3048)
		(layer "B.Cu")
		(net "GND")
	)
	(segment
		(start 189.249812 -1.690624)
		(end 189.249812 -3.09499)
		(width 0.254)
		(layer "B.Cu")
		(net "GND")
	)
	(segment
		(start 49.7586 -47.497238)
		(end 49.784 -47.471838)
		(width 0.2032)
		(layer "B.Cu")
		(net "GND")
	)
	(segment
		(start 69.546724 -44.236386)
		(end 69.7357 -44.425362)
		(width 0.3048)
		(layer "B.Cu")
		(net "GND")
	)
	(segment
		(start 99.06 -41.0972)
		(end 98.331528 -41.0972)
		(width 0.381)
		(layer "B.Cu")
		(net "GND")
	)
	(segment
		(start 135.550148 -62.599824)
		(end 135.550148 -63.541148)
		(width 0.254)
		(layer "B.Cu")
		(net "GND")
	)
	(segment
		(start 139.15009 -62.599824)
		(end 139.15009 -63.56731)
		(width 0.254)
		(layer "B.Cu")
		(net "GND")
	)
	(segment
		(start 5.575046 -58.449972)
		(end 4.093972 -58.449972)
		(width 0.254)
		(layer "B.Cu")
		(net "GND")
	)
	(segment
		(start 140.950188 -63.672212)
		(end 140.58519 -64.03721)
		(width 0.254)
		(layer "B.Cu")
		(net "GND")
	)
	(segment
		(start 68.13804 -42.745914)
		(end 68.13804 -43.079924)
		(width 0.3048)
		(layer "B.Cu")
		(net "GND")
	)
	(segment
		(start 54.243732 -25.019)
		(end 54.562756 -24.699976)
		(width 0.3048)
		(layer "B.Cu")
		(net "GND")
	)
	(segment
		(start 184.8612 -69.48297)
		(end 184.8612 -69.2912)
		(width 0.3048)
		(layer "B.Cu")
		(net "GND")
	)
	(segment
		(start 43.51909 -25.8445)
		(end 43.51909 -26.590244)
		(width 0.3048)
		(layer "B.Cu")
		(net "GND")
	)
	(segment
		(start 54.562756 -24.699976)
		(end 55.753508 -24.699976)
		(width 0.3048)
		(layer "B.Cu")
		(net "GND")
	)
	(segment
		(start 74.4728 -39.2176)
		(end 75.1078 -39.2176)
		(width 0.3048)
		(layer "B.Cu")
		(net "GND")
	)
	(segment
		(start 77.343 -36.6522)
		(end 77.3684 -36.6268)
		(width 0.3048)
		(layer "B.Cu")
		(net "GND")
	)
	(segment
		(start 138.850116 -69.429884)
		(end 138.9126 -69.3674)
		(width 0.3048)
		(layer "B.Cu")
		(net "GND")
	)
	(segment
		(start 143.34998 -63.39078)
		(end 143.802354 -63.843154)
		(width 0.254)
		(layer "B.Cu")
		(net "GND")
	)
	(segment
		(start 69.7357 -44.425362)
		(end 69.7357 -45.350938)
		(width 0.3048)
		(layer "B.Cu")
		(net "GND")
	)
	(segment
		(start 31.9532 -44.45)
		(end 32.7152 -44.45)
		(width 0.3048)
		(layer "B.Cu")
		(net "GND")
	)
	(segment
		(start 19.349974 -5.814568)
		(end 19.349974 -9.007094)
		(width 0.7112)
		(layer "B.Cu")
		(net "GND")
	)
	(segment
		(start 137.349992 -64.045592)
		(end 137.3886 -64.0842)
		(width 0.254)
		(layer "B.Cu")
		(net "GND")
	)
	(segment
		(start 191.135 -12.041378)
		(end 190.9064 -11.812778)
		(width 0.381)
		(layer "B.Cu")
		(net "GND")
	)
	(segment
		(start 177.850038 -1.690624)
		(end 177.850038 -2.994152)
		(width 0.254)
		(layer "B.Cu")
		(net "GND")
	)
	(segment
		(start 62.562232 -32.71774)
		(end 62.093602 -33.18637)
		(width 0.508)
		(layer "B.Cu")
		(net "GND")
	)
	(segment
		(start 197.637654 -72.6567)
		(end 196.034914 -71.05396)
		(width 0.3048)
		(layer "B.Cu")
		(net "GND")
	)
	(segment
		(start 189.55004 -62.599824)
		(end 189.55004 -63.48984)
		(width 0.3048)
		(layer "B.Cu")
		(net "GND")
	)
	(segment
		(start 129.250186 -70.79996)
		(end 129.250186 -69.387974)
		(width 0.3048)
		(layer "B.Cu")
		(net "GND")
	)
	(segment
		(start 45.0342 -15.08125)
		(end 45.0342 -15.5702)
		(width 0.3048)
		(layer "B.Cu")
		(net "GND")
	)
	(segment
		(start 179.649882 -2.914396)
		(end 179.41544 -3.148838)
		(width 0.254)
		(layer "B.Cu")
		(net "GND")
	)
	(segment
		(start 197.7898 -35.9918)
		(end 197.866 -36.068)
		(width 0.381)
		(layer "B.Cu")
		(net "GND")
	)
	(segment
		(start 153.8478 -3.151378)
		(end 153.8478 -3.100578)
		(width 0.3048)
		(layer "B.Cu")
		(net "GND")
	)
	(segment
		(start 129.55016 -62.599824)
		(end 129.55016 -63.50635)
		(width 0.254)
		(layer "B.Cu")
		(net "GND")
	)
	(segment
		(start 71.0692 -60.6806)
		(end 70.7898 -60.4012)
		(width 0.3048)
		(layer "B.Cu")
		(net "GND")
	)
	(segment
		(start 140.64996 -69.584824)
		(end 140.733018 -69.501766)
		(width 0.3048)
		(layer "B.Cu")
		(net "GND")
	)
	(segment
		(start 142.1384 -69.601588)
		(end 142.1384 -69.3166)
		(width 0.3048)
		(layer "B.Cu")
		(net "GND")
	)
	(segment
		(start 134.949946 -9.026398)
		(end 135.265668 -8.710676)
		(width 0.3048)
		(layer "B.Cu")
		(net "GND")
	)
	(segment
		(start 82.5754 -27.9146)
		(end 82.5754 -28.4734)
		(width 0.3048)
		(layer "B.Cu")
		(net "GND")
	)
	(segment
		(start 73.7108 -39.2176)
		(end 73.7362 -39.243)
		(width 0.3048)
		(layer "B.Cu")
		(net "GND")
	)
	(segment
		(start 39.116 -30.9372)
		(end 40.1066 -30.9372)
		(width 0.3048)
		(layer "B.Cu")
		(net "GND")
	)
	(segment
		(start 72.39 -38.0746)
		(end 71.5518 -38.9128)
		(width 0.3048)
		(layer "B.Cu")
		(net "GND")
	)
	(segment
		(start 44.8056 -44.8564)
		(end 45.258736 -45.309536)
		(width 0.2032)
		(layer "B.Cu")
		(net "GND")
	)
	(segment
		(start 175.150018 -9.89076)
		(end 175.150018 -9.086596)
		(width 0.254)
		(layer "B.Cu")
		(net "GND")
	)
	(segment
		(start 39.349934 -9.09828)
		(end 38.884352 -9.563862)
		(width 0.7112)
		(layer "B.Cu")
		(net "GND")
	)
	(segment
		(start 95.60306 -48.5013)
		(end 95.60306 -49.04486)
		(width 0.3048)
		(layer "B.Cu")
		(net "GND")
	)
	(segment
		(start 64.96812 -26.699972)
		(end 63.946532 -26.699972)
		(width 0.508)
		(layer "B.Cu")
		(net "GND")
	)
	(segment
		(start 110.1598 -4.445)
		(end 110.0328 -4.318)
		(width 0.3048)
		(layer "B.Cu")
		(net "GND")
	)
	(segment
		(start 119.09552 -3.79476)
		(end 119.399304 -3.79476)
		(width 0.3048)
		(layer "B.Cu")
		(net "GND")
	)
	(segment
		(start 145.449798 -2.924556)
		(end 145.66138 -3.136138)
		(width 0.254)
		(layer "B.Cu")
		(net "GND")
	)
	(segment
		(start 38.9382 -14.17701)
		(end 39.27221 -13.843)
		(width 0.3048)
		(layer "B.Cu")
		(net "GND")
	)
	(segment
		(start 190.119 -64.0588)
		(end 190.246 -64.0588)
		(width 0.3048)
		(layer "B.Cu")
		(net "GND")
	)
	(segment
		(start 62.829694 -40.299894)
		(end 62.103 -39.5732)
		(width 0.508)
		(layer "B.Cu")
		(net "GND")
	)
	(segment
		(start 136.642856 -3.124454)
		(end 136.642856 -3.128518)
		(width 0.254)
		(layer "B.Cu")
		(net "GND")
	)
	(segment
		(start 183.2356 -64.05118)
		(end 183.23433 -64.05245)
		(width 0.254)
		(layer "B.Cu")
		(net "GND")
	)
	(segment
		(start 173.34992 -9.89076)
		(end 173.34992 -8.77316)
		(width 0.254)
		(layer "B.Cu")
		(net "GND")
	)
	(segment
		(start 154.316176 -8.512302)
		(end 154.316176 -8.46836)
		(width 0.3048)
		(layer "B.Cu")
		(net "GND")
	)
	(segment
		(start 89.662 -39.6748)
		(end 90.236802 -39.6748)
		(width 0.3048)
		(layer "B.Cu")
		(net "GND")
	)
	(segment
		(start 33.7058 -51.054)
		(end 33.7058 -51.833526)
		(width 0.3048)
		(layer "B.Cu")
		(net "GND")
	)
	(segment
		(start 4.1656 -56.949848)
		(end 5.575046 -56.949848)
		(width 0.3048)
		(layer "B.Cu")
		(net "GND")
	)
	(segment
		(start 43.402504 -28.619704)
		(end 43.5356 -28.7528)
		(width 0.3048)
		(layer "B.Cu")
		(net "GND")
	)
	(segment
		(start 133.149848 -9.89076)
		(end 133.149848 -9.06653)
		(width 0.3048)
		(layer "B.Cu")
		(net "GND")
	)
	(segment
		(start 142.450058 -70.79996)
		(end 142.450058 -69.913246)
		(width 0.3048)
		(layer "B.Cu")
		(net "GND")
	)
	(segment
		(start 143.9672 -44.704)
		(end 143.9672 -45.466)
		(width 0.3048)
		(layer "B.Cu")
		(net "GND")
	)
	(segment
		(start 132.850128 -70.010528)
		(end 132.53466 -69.69506)
		(width 0.254)
		(layer "B.Cu")
		(net "GND")
	)
	(segment
		(start 48.6156 -52.3494)
		(end 48.668178 -52.296822)
		(width 0.2032)
		(layer "B.Cu")
		(net "GND")
	)
	(segment
		(start 68.5546 -61.2648)
		(end 68.453 -61.1632)
		(width 0.3048)
		(layer "B.Cu")
		(net "GND")
	)
	(segment
		(start 65.330832 -26.33726)
		(end 64.96812 -26.699972)
		(width 0.508)
		(layer "B.Cu")
		(net "GND")
	)
	(segment
		(start 72.388476 -66.4718)
		(end 72.009 -66.092324)
		(width 0.3048)
		(layer "B.Cu")
		(net "GND")
	)
	(segment
		(start 92.423996 -38.5826)
		(end 92.630498 -38.789102)
		(width 0.3048)
		(layer "B.Cu")
		(net "GND")
	)
	(segment
		(start 92.71 -37.1348)
		(end 91.960446 -37.1348)
		(width 0.3048)
		(layer "B.Cu")
		(net "GND")
	)
	(segment
		(start 179.349908 -8.734552)
		(end 179.617878 -8.466582)
		(width 0.254)
		(layer "B.Cu")
		(net "GND")
	)
	(segment
		(start 72.4154 -32.89554)
		(end 71.42226 -31.9024)
		(width 0.508)
		(layer "B.Cu")
		(net "GND")
	)
	(segment
		(start 42.1386 -51.6636)
		(end 42.0878 -51.6636)
		(width 0.2032)
		(layer "B.Cu")
		(net "GND")
	)
	(segment
		(start 50.399696 -21.265896)
		(end 50.419 -21.2852)
		(width 0.3048)
		(layer "B.Cu")
		(net "GND")
	)
	(segment
		(start 181.44998 -1.690624)
		(end 181.44998 -3.057398)
		(width 0.254)
		(layer "B.Cu")
		(net "GND")
	)
	(segment
		(start 182.94985 -9.89076)
		(end 182.94985 -8.898128)
		(width 0.254)
		(layer "B.Cu")
		(net "GND")
	)
	(segment
		(start 72.48525 -61.982096)
		(end 71.183754 -60.6806)
		(width 0.3048)
		(layer "B.Cu")
		(net "GND")
	)
	(segment
		(start 183.550052 -63.464186)
		(end 183.2356 -63.778638)
		(width 0.254)
		(layer "B.Cu")
		(net "GND")
	)
	(segment
		(start 43.5356 -28.7528)
		(end 44.6024 -28.7528)
		(width 0.508)
		(layer "B.Cu")
		(net "GND")
	)
	(segment
		(start 15.349982 -9.253982)
		(end 15.349982 -5.814568)
		(width 0.508)
		(layer "B.Cu")
		(net "GND")
	)
	(segment
		(start 43.2308 -27.516582)
		(end 43.402504 -27.688286)
		(width 0.3048)
		(layer "B.Cu")
		(net "GND")
	)
	(segment
		(start 68.1482 -36.0426)
		(end 68.1482 -36.034726)
		(width 0.3048)
		(layer "B.Cu")
		(net "GND")
	)
	(segment
		(start 64.9478 -19.652234)
		(end 65.4812 -20.185634)
		(width 0.2032)
		(layer "B.Cu")
		(net "GND")
	)
	(segment
		(start 27.349958 -5.814568)
		(end 27.349958 -9.095486)
		(width 0.7112)
		(layer "B.Cu")
		(net "GND")
	)
	(segment
		(start 16.34998 -6.690868)
		(end 16.34998 -9.020048)
		(width 0.508)
		(layer "B.Cu")
		(net "GND")
	)
	(segment
		(start 183.550052 -62.599824)
		(end 183.550052 -63.464186)
		(width 0.254)
		(layer "B.Cu")
		(net "GND")
	)
	(segment
		(start 131.350004 -9.89076)
		(end 131.350004 -9.045956)
		(width 0.254)
		(layer "B.Cu")
		(net "GND")
	)
	(segment
		(start 87.5538 -45.974)
		(end 87.5538 -45.608748)
		(width 0.3048)
		(layer "B.Cu")
		(net "GND")
	)
	(segment
		(start 63.946532 -40.299894)
		(end 62.829694 -40.299894)
		(width 0.508)
		(layer "B.Cu")
		(net "GND")
	)
	(segment
		(start 136.449816 -1.690624)
		(end 136.449816 -2.931414)
		(width 0.254)
		(layer "B.Cu")
		(net "GND")
	)
	(segment
		(start 131.949952 -63.643002)
		(end 132.5372 -64.23025)
		(width 0.254)
		(layer "B.Cu")
		(net "GND")
	)
	(segment
		(start 72.39 -66.4718)
		(end 72.388476 -66.4718)
		(width 0.3048)
		(layer "B.Cu")
		(net "GND")
	)
	(segment
		(start 133.7564 -46.609)
		(end 133.8072 -46.5582)
		(width 0.3048)
		(layer "B.Cu")
		(net "GND")
	)
	(segment
		(start 40.64 -42.7482)
		(end 40.105076 -42.7482)
		(width 0.3048)
		(layer "B.Cu")
		(net "GND")
	)
	(segment
		(start 45.258736 -52.632864)
		(end 45.085 -52.8066)
		(width 0.2032)
		(layer "B.Cu")
		(net "GND")
	)
	(segment
		(start 39.349934 -5.814568)
		(end 39.349934 -9.09828)
		(width 0.7112)
		(layer "B.Cu")
		(net "GND")
	)
	(segment
		(start 152.2222 -36.068)
		(end 152.8318 -36.068)
		(width 0.3048)
		(layer "B.Cu")
		(net "GND")
	)
	(segment
		(start 136.45007 -70.79996)
		(end 136.45007 -69.94017)
		(width 0.3048)
		(layer "B.Cu")
		(net "GND")
	)
	(segment
		(start 182.049928 -2.532126)
		(end 182.65394 -3.136138)
		(width 0.254)
		(layer "B.Cu")
		(net "GND")
	)
	(segment
		(start 40.0812 -52.4002)
		(end 40.894 -52.4002)
		(width 0.3048)
		(layer "B.Cu")
		(net "GND")
	)
	(segment
		(start 74.4728 -39.2176)
		(end 73.7108 -39.2176)
		(width 0.3048)
		(layer "B.Cu")
		(net "GND")
	)
	(segment
		(start 140.733018 -69.413374)
		(end 140.826236 -69.320156)
		(width 0.3048)
		(layer "B.Cu")
		(net "GND")
	)
	(segment
		(start 42.874946 -9.573006)
		(end 42.872914 -9.573006)
		(width 0.7112)
		(layer "B.Cu")
		(net "GND")
	)
	(segment
		(start 143.6878 -69.469)
		(end 143.6878 -69.3547)
		(width 0.254)
		(layer "B.Cu")
		(net "GND")
	)
	(segment
		(start 71.183754 -60.6806)
		(end 71.0692 -60.6806)
		(width 0.3048)
		(layer "B.Cu")
		(net "GND")
	)
	(segment
		(start 171.549822 -9.89076)
		(end 171.549822 -8.603996)
		(width 0.254)
		(layer "B.Cu")
		(net "GND")
	)
	(segment
		(start 187.918852 -69.448426)
		(end 187.918852 -69.294502)
		(width 0.3048)
		(layer "B.Cu")
		(net "GND")
	)
	(segment
		(start 71.628 -35.5092)
		(end 71.9582 -35.179)
		(width 0.3048)
		(layer "B.Cu")
		(net "GND")
	)
	(segment
		(start 62.181232 -33.274)
		(end 62.181232 -34.342832)
		(width 0.508)
		(layer "B.Cu")
		(net "GND")
	)
	(segment
		(start 178.150012 -62.599824)
		(end 178.150266 -62.600078)
		(width 0.254)
		(layer "B.Cu")
		(net "GND")
	)
	(segment
		(start 94.361 -49.734978)
		(end 94.309946 -49.786032)
		(width 0.3048)
		(layer "B.Cu")
		(net "GND")
	)
	(segment
		(start 68.349876 -5.814568)
		(end 68.349876 -9.117076)
		(width 0.7112)
		(layer "B.Cu")
		(net "GND")
	)
	(segment
		(start 63.35014 -46.34992)
		(end 62.18174 -45.18152)
		(width 0.508)
		(layer "B.Cu")
		(net "GND")
	)
	(segment
		(start 35.349942 -9.098026)
		(end 35.337242 -9.098026)
		(width 0.7112)
		(layer "B.Cu")
		(net "GND")
	)
	(segment
		(start 43.1292 -46.087792)
		(end 43.65879 -46.087792)
		(width 0.2032)
		(layer "B.Cu")
		(net "GND")
	)
	(segment
		(start 130.750056 -9.89076)
		(end 130.750056 -8.679434)
		(width 0.254)
		(layer "B.Cu")
		(net "GND")
	)
	(segment
		(start 62.1284 -27.2288)
		(end 62.657228 -26.699972)
		(width 0.508)
		(layer "B.Cu")
		(net "GND")
	)
	(segment
		(start 170.35018 -63.46444)
		(end 170.16222 -63.6524)
		(width 0.254)
		(layer "B.Cu")
		(net "GND")
	)
	(segment
		(start 72.48525 -63.43015)
		(end 72.48525 -61.982096)
		(width 0.3048)
		(layer "B.Cu")
		(net "GND")
	)
	(segment
		(start 174.617126 -3.100578)
		(end 174.617126 -3.125724)
		(width 0.254)
		(layer "B.Cu")
		(net "GND")
	)
	(segment
		(start 48.124872 -28.6258)
		(end 48.006 -28.6258)
		(width 0.381)
		(layer "B.Cu")
		(net "GND")
	)
	(segment
		(start 134.050024 -2.596388)
		(end 133.604 -3.042412)
		(width 0.254)
		(layer "B.Cu")
		(net "GND")
	)
	(segment
		(start 92.630498 -38.789102)
		(end 92.6338 -38.789102)
		(width 0.3048)
		(layer "B.Cu")
		(net "GND")
	)
	(segment
		(start 64.349884 -9.140952)
		(end 64.77 -9.561068)
		(width 0.7112)
		(layer "B.Cu")
		(net "GND")
	)
	(segment
		(start 133.604 -3.042412)
		(end 133.604 -3.176778)
		(width 0.254)
		(layer "B.Cu")
		(net "GND")
	)
	(segment
		(start 138.7602 -22.748494)
		(end 138.7602 -23.622)
		(width 0.3048)
		(layer "B.Cu")
		(net "GND")
	)
	(segment
		(start 187.749942 -62.599824)
		(end 187.749942 -64.064642)
		(width 0.3048)
		(layer "B.Cu")
		(net "GND")
	)
	(segment
		(start 62.924944 -32.29991)
		(end 62.562232 -32.662622)
		(width 0.508)
		(layer "B.Cu")
		(net "GND")
	)
	(segment
		(start 74.5998 -41.656)
		(end 75.4253 -41.656)
		(width 0.3048)
		(layer "B.Cu")
		(net "GND")
	)
	(segment
		(start 179.95011 -62.599824)
		(end 179.95011 -63.464186)
		(width 0.3048)
		(layer "B.Cu")
		(net "GND")
	)
	(segment
		(start 55.349902 -5.814568)
		(end 55.349902 -9.098534)
		(width 0.7112)
		(layer "B.Cu")
		(net "GND")
	)
	(segment
		(start 78.1558 -36.3982)
		(end 78.1558 -36.6268)
		(width 0.3048)
		(layer "B.Cu")
		(net "GND")
	)
	(segment
		(start 181.749954 -62.599824)
		(end 181.749954 -63.754762)
		(width 0.254)
		(layer "B.Cu")
		(net "GND")
	)
	(segment
		(start 48.006 -28.6258)
		(end 48.006 -29.337)
		(width 0.508)
		(layer "B.Cu")
		(net "GND")
	)
	(segment
		(start 153.249884 -1.690624)
		(end 153.249884 -2.529078)
		(width 0.3048)
		(layer "B.Cu")
		(net "GND")
	)
	(segment
		(start 131.350004 -63.925196)
		(end 131.2164 -64.0588)
		(width 0.254)
		(layer "B.Cu")
		(net "GND")
	)
	(segment
		(start 182.94985 -8.898128)
		(end 182.4609 -8.409178)
		(width 0.254)
		(layer "B.Cu")
		(net "GND")
	)
	(segment
		(start 75.4253 -41.656)
		(end 75.5015 -41.5798)
		(width 0.3048)
		(layer "B.Cu")
		(net "GND")
	)
	(segment
		(start 179.050188 -70.79996)
		(end 179.050188 -69.927216)
		(width 0.254)
		(layer "B.Cu")
		(net "GND")
	)
	(segment
		(start 136.449816 -2.931414)
		(end 136.642856 -3.124454)
		(width 0.254)
		(layer "B.Cu")
		(net "GND")
	)
	(segment
		(start 51.02479 -25.04821)
		(end 51.435 -24.638)
		(width 0.3048)
		(layer "B.Cu")
		(net "GND")
	)
	(segment
		(start 139.44981 -1.690624)
		(end 139.44981 -2.563368)
		(width 0.254)
		(layer "B.Cu")
		(net "GND")
	)
	(segment
		(start 142.14983 -9.89076)
		(end 142.14983 -8.700516)
		(width 0.254)
		(layer "B.Cu")
		(net "GND")
	)
	(segment
		(start 40.01643 -24.72309)
		(end 40.15867 -24.58085)
		(width 0.3048)
		(layer "B.Cu")
		(net "GND")
	)
	(segment
		(start 134.19582 -69.446394)
		(end 134.19582 -69.37756)
		(width 0.3048)
		(layer "B.Cu")
		(net "GND")
	)
	(segment
		(start 5.575046 -61.449966)
		(end 4.292346 -61.449966)
		(width 0.3048)
		(layer "B.Cu")
		(net "GND")
	)
	(segment
		(start 57.3786 -37.554408)
		(end 57.3786 -41.552876)
		(width 0.3048)
		(layer "B.Cu")
		(net "GND")
	)
	(segment
		(start 131.05003 -69.571616)
		(end 131.248658 -69.372988)
		(width 0.254)
		(layer "B.Cu")
		(net "GND")
	)
	(segment
		(start 76.7588 -60.229242)
		(end 76.7588 -60.776612)
		(width 0.3048)
		(layer "B.Cu")
		(net "GND")
	)
	(segment
		(start 78.554326 -35.999674)
		(end 78.1558 -36.3982)
		(width 0.3048)
		(layer "B.Cu")
		(net "GND")
	)
	(segment
		(start 99.126802 -33.269682)
		(end 98.90252 -33.0454)
		(width 0.381)
		(layer "B.Cu")
		(net "GND")
	)
	(segment
		(start 184.315862 -8.32104)
		(end 184.315862 -8.294116)
		(width 0.254)
		(layer "B.Cu")
		(net "GND")
	)
	(segment
		(start 144.250156 -70.79996)
		(end 144.250156 -70.031356)
		(width 0.254)
		(layer "B.Cu")
		(net "GND")
	)
	(segment
		(start 176.949862 -9.89076)
		(end 176.949862 -9.13384)
		(width 0.254)
		(layer "B.Cu")
		(net "GND")
	)
	(segment
		(start 71.501 -36.0934)
		(end 72.39 -36.9824)
		(width 0.3048)
		(layer "B.Cu")
		(net "GND")
	)
	(segment
		(start 67.104006 -24.956008)
		(end 66.334894 -24.956008)
		(width 0.508)
		(layer "B.Cu")
		(net "GND")
	)
	(segment
		(start 78.867 -15.2908)
		(end 78.867 -15.24)
		(width 0.508)
		(layer "B.Cu")
		(net "GND")
	)
	(segment
		(start 139.065 -2.948178)
		(end 139.065 -3.176778)
		(width 0.254)
		(layer "B.Cu")
		(net "GND")
	)
	(segment
		(start 92.350082 -5.814568)
		(end 92.350082 -9.561068)
		(width 0.508)
		(layer "B.Cu")
		(net "GND")
	)
	(segment
		(start 40.1066 -46.6598)
		(end 40.6654 -46.6598)
		(width 0.3048)
		(layer "B.Cu")
		(net "GND")
	)
	(segment
		(start 181.44998 -3.057398)
		(end 181.356 -3.151378)
		(width 0.254)
		(layer "B.Cu")
		(net "GND")
	)
	(segment
		(start 54.557422 -27.100022)
		(end 55.753508 -27.100022)
		(width 0.508)
		(layer "B.Cu")
		(net "GND")
	)
	(segment
		(start 188.05017 -70.79996)
		(end 188.05017 -69.579744)
		(width 0.3048)
		(layer "B.Cu")
		(net "GND")
	)
	(segment
		(start 76.34986 -5.814568)
		(end 76.367894 -5.832602)
		(width 0.7112)
		(layer "B.Cu")
		(net "GND")
	)
	(segment
		(start 146.05 -69.977)
		(end 145.4912 -69.4182)
		(width 0.254)
		(layer "B.Cu")
		(net "GND")
	)
	(segment
		(start 140.64996 -70.79996)
		(end 140.64996 -69.584824)
		(width 0.3048)
		(layer "B.Cu")
		(net "GND")
	)
	(segment
		(start 95.7072 -46.092364)
		(end 95.692468 -46.107096)
		(width 0.3048)
		(layer "B.Cu")
		(net "GND")
	)
	(segment
		(start 181.749954 -63.754762)
		(end 182.051198 -64.056006)
		(width 0.254)
		(layer "B.Cu")
		(net "GND")
	)
	(segment
		(start 140.733018 -69.501766)
		(end 140.733018 -69.413374)
		(width 0.3048)
		(layer "B.Cu")
		(net "GND")
	)
	(segment
		(start 179.712112 -64.077088)
		(end 179.70246 -64.08674)
		(width 0.3048)
		(layer "B.Cu")
		(net "GND")
	)
	(segment
		(start 184.749948 -8.755126)
		(end 184.315862 -8.32104)
		(width 0.254)
		(layer "B.Cu")
		(net "GND")
	)
	(segment
		(start 39.37 -46.482)
		(end 39.6494 -46.2026)
		(width 0.508)
		(layer "B.Cu")
		(net "GND")
	)
	(segment
		(start 174.550324 -62.600078)
		(end 174.550324 -63.646304)
		(width 0.3048)
		(layer "B.Cu")
		(net "GND")
	)
	(segment
		(start 79.145892 -14.961108)
		(end 79.145892 -14.610588)
		(width 0.508)
		(layer "B.Cu")
		(net "GND")
	)
	(segment
		(start 150.10765 -45.54855)
		(end 150.1902 -45.466)
		(width 0.3048)
		(layer "B.Cu")
		(net "GND")
	)
	(segment
		(start 98.331528 -41.0972)
		(end 98.241358 -41.18737)
		(width 0.381)
		(layer "B.Cu")
		(net "GND")
	)
	(segment
		(start 38.227 -46.482)
		(end 38.227 -45.7962)
		(width 0.3048)
		(layer "B.Cu")
		(net "GND")
	)
	(segment
		(start 67.104006 -24.959056)
		(end 67.82435 -25.6794)
		(width 0.3048)
		(layer "B.Cu")
		(net "GND")
	)
	(segment
		(start 57.3786 -41.552876)
		(end 56.631586 -42.29989)
		(width 0.3048)
		(layer "B.Cu")
		(net "GND")
	)
	(segment
		(start 65.4812 -20.185634)
		(end 65.4812 -20.3708)
		(width 0.2032)
		(layer "B.Cu")
		(net "GND")
	)
	(segment
		(start 71.34987 -5.814568)
		(end 71.34987 -9.11733)
		(width 0.7112)
		(layer "B.Cu")
		(net "GND")
	)
	(segment
		(start 142.2908 -46.308772)
		(end 142.2908 -45.466)
		(width 0.3048)
		(layer "B.Cu")
		(net "GND")
	)
	(segment
		(start 96.20504 -43.24096)
		(end 96.647 -42.799)
		(width 0.3048)
		(layer "B.Cu")
		(net "GND")
	)
	(segment
		(start 71.34987 -9.11733)
		(end 70.8914 -9.5758)
		(width 0.7112)
		(layer "B.Cu")
		(net "GND")
	)
	(segment
		(start 184.28462 -3.031998)
		(end 184.28462 -3.176778)
		(width 0.254)
		(layer "B.Cu")
		(net "GND")
	)
	(segment
		(start 70.07352 -33.66516)
		(end 69.744082 -33.66516)
		(width 0.254)
		(layer "B.Cu")
		(net "GND")
	)
	(segment
		(start 189.850014 -69.492622)
		(end 189.671198 -69.313806)
		(width 0.3048)
		(layer "B.Cu")
		(net "GND")
	)
	(segment
		(start 68.43776 -36.33216)
		(end 68.1482 -36.0426)
		(width 0.3048)
		(layer "B.Cu")
		(net "GND")
	)
	(segment
		(start 136.45007 -69.94017)
		(end 135.90524 -69.39534)
		(width 0.3048)
		(layer "B.Cu")
		(net "GND")
	)
	(segment
		(start 176.350168 -63.951612)
		(end 176.24044 -64.06134)
		(width 0.3048)
		(layer "B.Cu")
		(net "GND")
	)
	(segment
		(start 99.949 -20.9042)
		(end 99.949 -21.4884)
		(width 0.381)
		(layer "B.Cu")
		(net "GND")
	)
	(segment
		(start 96.06788 -43.24096)
		(end 96.20504 -43.24096)
		(width 0.3048)
		(layer "B.Cu")
		(net "GND")
	)
	(segment
		(start 181.1274 -69.64553)
		(end 181.1274 -69.342)
		(width 0.3048)
		(layer "B.Cu")
		(net "GND")
	)
	(segment
		(start 80.6958 -32.8168)
		(end 81.031334 -32.8168)
		(width 0.3048)
		(layer "B.Cu")
		(net "GND")
	)
	(segment
		(start 53.951378 -33.50006)
		(end 55.753508 -33.50006)
		(width 0.508)
		(layer "B.Cu")
		(net "GND")
	)
	(segment
		(start 70.8914 -9.5758)
		(end 70.8152 -9.5758)
		(width 0.7112)
		(layer "B.Cu")
		(net "GND")
	)
	(segment
		(start 46.57725 -22.40915)
		(end 42.33037 -22.40915)
		(width 0.3048)
		(layer "B.Cu")
		(net "GND")
	)
	(segment
		(start 138.418316 -46.6344)
		(end 138.3792 -46.595284)
		(width 0.3048)
		(layer "B.Cu")
		(net "GND")
	)
	(segment
		(start 99.6188 -20.574)
		(end 99.949 -20.9042)
		(width 0.381)
		(layer "B.Cu")
		(net "GND")
	)
	(segment
		(start 36.449 -25.019)
		(end 36.449 -24.4348)
		(width 0.508)
		(layer "B.Cu")
		(net "GND")
	)
	(segment
		(start 133.2738 -30.353)
		(end 133.2738 -31.115)
		(width 0.3048)
		(layer "B.Cu")
		(net "GND")
	)
	(segment
		(start 194.945 -29.21)
		(end 195.199 -28.956)
		(width 0.508)
		(layer "B.Cu")
		(net "GND")
	)
	(segment
		(start 77.3684 -36.6268)
		(end 78.1558 -36.6268)
		(width 0.3048)
		(layer "B.Cu")
		(net "GND")
	)
	(segment
		(start 69.215 -61.2648)
		(end 68.5546 -61.2648)
		(width 0.3048)
		(layer "B.Cu")
		(net "GND")
	)
	(segment
		(start 78.828392 -9.619488)
		(end 78.828392 -9.6266)
		(width 0.7112)
		(layer "B.Cu")
		(net "GND")
	)
	(segment
		(start 138.772646 -22.736048)
		(end 138.7602 -22.748494)
		(width 0.3048)
		(layer "B.Cu")
		(net "GND")
	)
	(segment
		(start 178.014122 -8.492998)
		(end 178.03876 -8.46836)
		(width 0.254)
		(layer "B.Cu")
		(net "GND")
	)
	(segment
		(start 48.349916 -5.814568)
		(end 48.349916 -9.041384)
		(width 0.7112)
		(layer "B.Cu")
		(net "GND")
	)
	(segment
		(start 187.7822 -28.5242)
		(end 187.7822 -29.1338)
		(width 0.3048)
		(layer "B.Cu")
		(net "GND")
	)
	(segment
		(start 97.917 -51.816)
		(end 97.917 -52.105052)
		(width 0.3048)
		(layer "B.Cu")
		(net "GND")
	)
	(segment
		(start 69.7357 -45.350938)
		(end 69.290438 -45.7962)
		(width 0.3048)
		(layer "B.Cu")
		(net "GND")
	)
	(segment
		(start 68.961 -35.9156)
		(end 68.326 -35.9156)
		(width 0.3048)
		(layer "B.Cu")
		(net "GND")
	)
	(segment
		(start 173.049946 -70.79996)
		(end 173.049946 -69.595746)
		(width 0.3048)
		(layer "B.Cu")
		(net "GND")
	)
	(segment
		(start 78.0288 -22.733)
		(end 77.7494 -23.0124)
		(width 0.3048)
		(layer "B.Cu")
		(net "GND")
	)
	(segment
		(start 176.2506 -8.459978)
		(end 176.1998 -8.409178)
		(width 0.254)
		(layer "B.Cu")
		(net "GND")
	)
	(segment
		(start 177.7492 -63.865252)
		(end 177.7492 -64.06642)
		(width 0.254)
		(layer "B.Cu")
		(net "GND")
	)
	(segment
		(start 133.9088 -45.466)
		(end 133.9088 -44.704)
		(width 0.3048)
		(layer "B.Cu")
		(net "GND")
	)
	(segment
		(start 84.61375 -18.847308)
		(end 85.598 -18.847308)
		(width 0.3048)
		(layer "B.Cu")
		(net "GND")
	)
	(segment
		(start 68.43776 -36.91128)
		(end 68.43776 -36.33216)
		(width 0.3048)
		(layer "B.Cu")
		(net "GND")
	)
	(segment
		(start 153.406856 -53.4416)
		(end 153.9494 -53.4416)
		(width 0.254)
		(layer "B.Cu")
		(net "GND")
	)
	(segment
		(start 133.75005 -63.82385)
		(end 133.9596 -64.0334)
		(width 0.254)
		(layer "B.Cu")
		(net "GND")
	)
	(segment
		(start 65.330832 -25.96007)
		(end 65.330832 -26.33726)
		(width 0.508)
		(layer "B.Cu")
		(net "GND")
	)
	(segment
		(start 183.850026 -2.597404)
		(end 184.28462 -3.031998)
		(width 0.254)
		(layer "B.Cu")
		(net "GND")
	)
	(segment
		(start 187.149994 -8.83158)
		(end 187.575698 -8.405876)
		(width 0.254)
		(layer "B.Cu")
		(net "GND")
	)
	(segment
		(start 74.821288 -9.6266)
		(end 74.803 -9.6266)
		(width 0.7112)
		(layer "B.Cu")
		(net "GND")
	)
	(segment
		(start 138.3792 -46.595284)
		(end 138.3792 -45.466)
		(width 0.3048)
		(layer "B.Cu")
		(net "GND")
	)
	(segment
		(start 66.334894 -24.956008)
		(end 65.330832 -25.96007)
		(width 0.508)
		(layer "B.Cu")
		(net "GND")
	)
	(segment
		(start 182.051198 -69.364606)
		(end 182.051198 -69.339206)
		(width 0.3048)
		(layer "B.Cu")
		(net "GND")
	)
	(segment
		(start 146.05 -70.79996)
		(end 146.05 -69.977)
		(width 0.254)
		(layer "B.Cu")
		(net "GND")
	)
	(segment
		(start 140.349986 -8.610092)
		(end 140.5255 -8.434578)
		(width 0.254)
		(layer "B.Cu")
		(net "GND")
	)
	(segment
		(start 46.4312 -14.605)
		(end 45.466 -15.5702)
		(width 0.3048)
		(layer "B.Cu")
		(net "GND")
	)
	(segment
		(start 171.250102 -69.922898)
		(end 171.5516 -69.6214)
		(width 0.3048)
		(layer "B.Cu")
		(net "GND")
	)
	(segment
		(start 69.290438 -45.7962)
		(end 68.834 -45.7962)
		(width 0.3048)
		(layer "B.Cu")
		(net "GND")
	)
	(segment
		(start 24.349964 -8.892032)
		(end 25.019 -9.561068)
		(width 0.7112)
		(layer "B.Cu")
		(net "GND")
	)
	(segment
		(start 78.0288 -22.4282)
		(end 78.0288 -22.733)
		(width 0.3048)
		(layer "B.Cu")
		(net "GND")
	)
	(segment
		(start 186.317382 -8.46836)
		(end 186.302396 -8.46836)
		(width 0.254)
		(layer "B.Cu")
		(net "GND")
	)
	(segment
		(start 139.44981 -2.563368)
		(end 139.065 -2.948178)
		(width 0.254)
		(layer "B.Cu")
		(net "GND")
	)
	(segment
		(start 145.150078 -63.870078)
		(end 145.3261 -64.0461)
		(width 0.254)
		(layer "B.Cu")
		(net "GND")
	)
	(segment
		(start 170.35018 -62.599824)
		(end 170.35018 -63.46444)
		(width 0.254)
		(layer "B.Cu")
		(net "GND")
	)
	(segment
		(start 142.354808 -64.1096)
		(end 142.38097 -64.135762)
		(width 0.254)
		(layer "B.Cu")
		(net "GND")
	)
	(segment
		(start 154.15006 -8.678418)
		(end 154.316176 -8.512302)
		(width 0.3048)
		(layer "B.Cu")
		(net "GND")
	)
	(segment
		(start 130.8862 -31.115)
		(end 130.8862 -30.37078)
		(width 0.3048)
		(layer "B.Cu")
		(net "GND")
	)
	(segment
		(start 166.150036 -62.599824)
		(end 166.150036 -63.905384)
		(width 0.3048)
		(layer "B.Cu")
		(net "GND")
	)
	(segment
		(start 136.750044 -8.735822)
		(end 136.4488 -8.434578)
		(width 0.3048)
		(layer "B.Cu")
		(net "GND")
	)
	(segment
		(start 128.649984 -1.690624)
		(end 128.649984 -3.201162)
		(width 0.254)
		(layer "B.Cu")
		(net "GND")
	)
	(segment
		(start 141.96441 -46.635162)
		(end 142.2908 -46.308772)
		(width 0.3048)
		(layer "B.Cu")
		(net "GND")
	)
	(segment
		(start 43.402504 -27.688286)
		(end 43.402504 -28.619704)
		(width 0.3048)
		(layer "B.Cu")
		(net "GND")
	)
	(segment
		(start 79.349854 -9.098026)
		(end 78.828392 -9.619488)
		(width 0.7112)
		(layer "B.Cu")
		(net "GND")
	)
	(segment
		(start 32.349948 -5.814568)
		(end 32.349948 -9.062212)
		(width 0.7112)
		(layer "B.Cu")
		(net "GND")
	)
	(segment
		(start 128.949958 -9.89076)
		(end 128.949958 -8.631936)
		(width 0.3048)
		(layer "B.Cu")
		(net "GND")
	)
	(segment
		(start 174.550324 -63.646304)
		(end 174.93488 -64.03086)
		(width 0.3048)
		(layer "B.Cu")
		(net "GND")
	)
	(segment
		(start 153.9494 -53.4416)
		(end 154.1018 -53.594)
		(width 0.254)
		(layer "B.Cu")
		(net "GND")
	)
	(segment
		(start 189.850014 -70.79996)
		(end 189.850014 -69.492622)
		(width 0.3048)
		(layer "B.Cu")
		(net "GND")
	)
	(segment
		(start 132.850128 -70.79996)
		(end 132.850128 -70.010528)
		(width 0.254)
		(layer "B.Cu")
		(net "GND")
	)
	(segment
		(start 145.150078 -62.599824)
		(end 145.150078 -63.870078)
		(width 0.254)
		(layer "B.Cu")
		(net "GND")
	)
	(segment
		(start 75.6412 -59.8424)
		(end 76.371958 -59.8424)
		(width 0.3048)
		(layer "B.Cu")
		(net "GND")
	)
	(segment
		(start 51.5366 -48.641)
		(end 51.5112 -48.6156)
		(width 0.3048)
		(layer "B.Cu")
		(net "GND")
	)
	(segment
		(start 72.009 -66.092324)
		(end 72.009 -63.9064)
		(width 0.3048)
		(layer "B.Cu")
		(net "GND")
	)
	(segment
		(start 197.7898 -35.306)
		(end 197.7898 -35.9918)
		(width 0.381)
		(layer "B.Cu")
		(net "GND")
	)
	(segment
		(start 98.933 -21.4884)
		(end 98.3488 -22.0726)
		(width 0.381)
		(layer "B.Cu")
		(net "GND")
	)
	(segment
		(start 172.449998 -2.579116)
		(end 173.03496 -3.164078)
		(width 0.254)
		(layer "B.Cu")
		(net "GND")
	)
	(segment
		(start 187.449968 -1.690624)
		(end 187.449968 -2.95021)
		(width 0.254)
		(layer "B.Cu")
		(net "GND")
	)
	(segment
		(start 39.878 -52.6034)
		(end 39.878 -53.8734)
		(width 0.508)
		(layer "B.Cu")
		(net "GND")
	)
	(segment
		(start 141.245844 -2.522474)
		(end 140.64488 -3.123438)
		(width 0.254)
		(layer "B.Cu")
		(net "GND")
	)
	(segment
		(start 144.250156 -70.031356)
		(end 143.6878 -69.469)
		(width 0.254)
		(layer "B.Cu")
		(net "GND")
	)
	(segment
		(start 62.924944 -29.899864)
		(end 63.946532 -29.899864)
		(width 0.508)
		(layer "B.Cu")
		(net "GND")
	)
	(segment
		(start 100.9396 -45.085)
		(end 100.584 -45.4406)
		(width 0.3048)
		(layer "B.Cu")
		(net "GND")
	)
	(segment
		(start 63.946532 -32.29991)
		(end 62.924944 -32.29991)
		(width 0.508)
		(layer "B.Cu")
		(net "GND")
	)
	(segment
		(start 50.1904 -17.4498)
		(end 50.52441 -17.78381)
		(width 0.3048)
		(layer "B.Cu")
		(net "GND")
	)
	(segment
		(start 68.3006 -47.600108)
		(end 68.522088 -47.821596)
		(width 0.3048)
		(layer "B.Cu")
		(net "GND")
	)
	(segment
		(start 63.946532 -37.899848)
		(end 62.303152 -37.899848)
		(width 0.508)
		(layer "B.Cu")
		(net "GND")
	)
	(segment
		(start 42.8498 -17.5768)
		(end 42.545 -17.272)
		(width 0.3048)
		(layer "B.Cu")
		(net "GND")
	)
	(segment
		(start 137.050018 -69.433186)
		(end 137.143998 -69.339206)
		(width 0.3048)
		(layer "B.Cu")
		(net "GND")
	)
	(segment
		(start 187.7822 -29.1338)
		(end 187.833 -29.1846)
		(width 0.3048)
		(layer "B.Cu")
		(net "GND")
	)
	(segment
		(start 137.649966 -1.690624)
		(end 137.649966 -2.592832)
		(width 0.254)
		(layer "B.Cu")
		(net "GND")
	)
	(segment
		(start 147.249896 -1.690624)
		(end 147.249896 -2.660142)
		(width 0.254)
		(layer "B.Cu")
		(net "GND")
	)
	(segment
		(start 145.750026 -9.89076)
		(end 145.750026 -8.391906)
		(width 0.254)
		(layer "B.Cu")
		(net "GND")
	)
	(segment
		(start 61.29655 -42.89933)
		(end 61.29655 -39.98595)
		(width 0.508)
		(layer "B.Cu")
		(net "GND")
	)
	(segment
		(start 62.303152 -37.899848)
		(end 61.7093 -38.4937)
		(width 0.508)
		(layer "B.Cu")
		(net "GND")
	)
	(segment
		(start 54.3179 -44.2341)
		(end 54.3179 -45.6819)
		(width 0.508)
		(layer "B.Cu")
		(net "GND")
	)
	(segment
		(start 58.872628 -9.573514)
		(end 58.87212 -9.573514)
		(width 0.7112)
		(layer "B.Cu")
		(net "GND")
	)
	(segment
		(start 68.834 -45.7962)
		(end 68.6308 -45.7962)
		(width 0.3048)
		(layer "B.Cu")
		(net "GND")
	)
	(segment
		(start 112.79124 -8.17372)
		(end 112.79124 -7.410196)
		(width 0.3048)
		(layer "B.Cu")
		(net "GND")
	)
	(segment
		(start 45.085 -53.213)
		(end 45.2882 -53.4162)
		(width 0.3048)
		(layer "B.Cu")
		(net "GND")
	)
	(segment
		(start 39.878 -53.8734)
		(end 40.3098 -54.3052)
		(width 0.508)
		(layer "B.Cu")
		(net "GND")
	)
	(segment
		(start 47.349918 -9.088882)
		(end 46.863 -9.5758)
		(width 0.7112)
		(layer "B.Cu")
		(net "GND")
	)
	(segment
		(start 40.03802 -24.4602)
		(end 40.15867 -24.58085)
		(width 0.508)
		(layer "B.Cu")
		(net "GND")
	)
	(segment
		(start 40.349932 -5.814568)
		(end 40.349932 -9.058656)
		(width 0.7112)
		(layer "B.Cu")
		(net "GND")
	)
	(segment
		(start 95.350076 -9.447276)
		(end 95.3516 -9.4488)
		(width 0.7112)
		(layer "B.Cu")
		(net "GND")
	)
	(segment
		(start 98.443796 -69.436996)
		(end 98.443796 -68.658994)
		(width 0.3048)
		(layer "B.Cu")
		(net "GND")
	)
	(segment
		(start 75.0062 -60.4774)
		(end 75.6412 -59.8424)
		(width 0.3048)
		(layer "B.Cu")
		(net "GND")
	)
	(segment
		(start 82.5754 -28.4734)
		(end 82.6262 -28.5242)
		(width 0.3048)
		(layer "B.Cu")
		(net "GND")
	)
	(segment
		(start 135.914892 -63.905892)
		(end 135.914892 -64.1604)
		(width 0.254)
		(layer "B.Cu")
		(net "GND")
	)
	(segment
		(start 19.349974 -9.007094)
		(end 18.796 -9.561068)
		(width 0.7112)
		(layer "B.Cu")
		(net "GND")
	)
	(segment
		(start 150.10765 -46.55185)
		(end 150.10765 -45.54855)
		(width 0.3048)
		(layer "B.Cu")
		(net "GND")
	)
	(segment
		(start 165.250114 -69.961506)
		(end 165.872414 -69.339206)
		(width 0.3048)
		(layer "B.Cu")
		(net "GND")
	)
	(segment
		(start 53.975 -43.8912)
		(end 54.3179 -44.2341)
		(width 0.508)
		(layer "B.Cu")
		(net "GND")
	)
	(segment
		(start 42.0878 -51.6636)
		(end 42.0878 -50.9524)
		(width 0.2032)
		(layer "B.Cu")
		(net "GND")
	)
	(segment
		(start 54.88559 -9.562846)
		(end 54.88559 -9.71931)
		(width 0.3048)
		(layer "B.Cu")
		(net "GND")
	)
	(segment
		(start 146.950176 -62.599824)
		(end 146.950176 -63.993776)
		(width 0.3048)
		(layer "B.Cu")
		(net "GND")
	)
	(segment
		(start 154.15006 -9.89076)
		(end 154.15006 -8.678418)
		(width 0.3048)
		(layer "B.Cu")
		(net "GND")
	)
	(segment
		(start 94.361 -48.4886)
		(end 94.361 -49.734978)
		(width 0.3048)
		(layer "B.Cu")
		(net "GND")
	)
	(segment
		(start 100.1268 -68.7832)
		(end 98.9838 -69.9262)
		(width 0.3048)
		(layer "B.Cu")
		(net "GND")
	)
	(segment
		(start 17.018 -55.626)
		(end 16.2052 -56.4388)
		(width 0.3048)
		(layer "B.Cu")
		(net "GND")
	)
	(segment
		(start 63.946532 -29.100018)
		(end 62.526418 -29.100018)
		(width 0.508)
		(layer "B.Cu")
		(net "GND")
	)
	(segment
		(start 140.349986 -9.89076)
		(end 140.349986 -8.610092)
		(width 0.254)
		(layer "B.Cu")
		(net "GND")
	)
	(segment
		(start 138.549888 -9.026398)
		(end 139.015724 -8.560562)
		(width 0.254)
		(layer "B.Cu")
		(net "GND")
	)
	(segment
		(start 185.64987 -2.809748)
		(end 185.95594 -3.115818)
		(width 0.254)
		(layer "B.Cu")
		(net "GND")
	)
	(segment
		(start 186.250072 -70.79996)
		(end 186.250072 -69.922898)
		(width 0.3048)
		(layer "B.Cu")
		(net "GND")
	)
	(segment
		(start 166.150036 -63.905384)
		(end 166.0144 -64.04102)
		(width 0.3048)
		(layer "B.Cu")
		(net "GND")
	)
	(segment
		(start 59.349894 -9.096248)
		(end 58.872628 -9.573514)
		(width 0.7112)
		(layer "B.Cu")
		(net "GND")
	)
	(segment
		(start 39.878 -52.6034)
		(end 40.0812 -52.4002)
		(width 0.3048)
		(layer "B.Cu")
		(net "GND")
	)
	(segment
		(start 15.9004 -9.8044)
		(end 15.349982 -9.253982)
		(width 0.508)
		(layer "B.Cu")
		(net "GND")
	)
	(segment
		(start 142.3162 -64.1096)
		(end 142.354808 -64.1096)
		(width 0.254)
		(layer "B.Cu")
		(net "GND")
	)
	(segment
		(start 69.294502 -44.236386)
		(end 69.546724 -44.236386)
		(width 0.3048)
		(layer "B.Cu")
		(net "GND")
	)
	(segment
		(start 57.658 -21.082)
		(end 58.175144 -21.082)
		(width 0.508)
		(layer "B.Cu")
		(net "GND")
	)
	(segment
		(start 135.849868 -2.81051)
		(end 135.255 -3.405378)
		(width 0.254)
		(layer "B.Cu")
		(net "GND")
	)
	(segment
		(start 140.950188 -62.599824)
		(end 140.950188 -63.672212)
		(width 0.254)
		(layer "B.Cu")
		(net "GND")
	)
	(segment
		(start 206.3242 -38.9636)
		(end 205.0796 -38.9636)
		(width 0.508)
		(layer "B.Cu")
		(net "GND")
	)
	(segment
		(start 75.1078 -39.2176)
		(end 75.1586 -39.1668)
		(width 0.3048)
		(layer "B.Cu")
		(net "GND")
	)
	(segment
		(start 165.250114 -70.79996)
		(end 165.250114 -69.961506)
		(width 0.3048)
		(layer "B.Cu")
		(net "GND")
	)
	(segment
		(start 176.650142 -69.374258)
		(end 176.657 -69.3674)
		(width 0.3048)
		(layer "B.Cu")
		(net "GND")
	)
	(segment
		(start 180.850032 -69.922898)
		(end 181.1274 -69.64553)
		(width 0.3048)
		(layer "B.Cu")
		(net "GND")
	)
	(segment
		(start 178.003962 -8.492998)
		(end 178.014122 -8.492998)
		(width 0.254)
		(layer "B.Cu")
		(net "GND")
	)
	(segment
		(start 80.349852 -5.814568)
		(end 80.349852 -9.14146)
		(width 0.7112)
		(layer "B.Cu")
		(net "GND")
	)
	(segment
		(start 177.850038 -2.994152)
		(end 177.673762 -3.170428)
		(width 0.254)
		(layer "B.Cu")
		(net "GND")
	)
	(segment
		(start 176.04994 -1.690624)
		(end 176.04994 -2.86766)
		(width 0.254)
		(layer "B.Cu")
		(net "GND")
	)
	(segment
		(start 36.449 -24.4348)
		(end 36.4744 -24.4602)
		(width 0.508)
		(layer "B.Cu")
		(net "GND")
	)
	(segment
		(start 184.449974 -70.79996)
		(end 184.449974 -69.894196)
		(width 0.3048)
		(layer "B.Cu")
		(net "GND")
	)
	(segment
		(start 182.65013 -70.79996)
		(end 182.65013 -69.9516)
		(width 0.3048)
		(layer "B.Cu")
		(net "GND")
	)
	(segment
		(start 44.8056 -44.6278)
		(end 44.8056 -44.8564)
		(width 0.2032)
		(layer "B.Cu")
		(net "GND")
	)
	(segment
		(start 36.34994 -5.814568)
		(end 36.34994 -9.063228)
		(width 0.7112)
		(layer "B.Cu")
		(net "GND")
	)
	(segment
		(start 81.361534 -33.147)
		(end 81.361534 -33.154112)
		(width 0.3048)
		(layer "B.Cu")
		(net "GND")
	)
	(segment
		(start 183.2356 -63.778638)
		(end 183.2356 -64.05118)
		(width 0.254)
		(layer "B.Cu")
		(net "GND")
	)
	(segment
		(start 173.049946 -69.595746)
		(end 172.8216 -69.3674)
		(width 0.3048)
		(layer "B.Cu")
		(net "GND")
	)
	(segment
		(start 84.349844 -5.814568)
		(end 84.349844 -9.242044)
		(width 0.7112)
		(layer "B.Cu")
		(net "GND")
	)
	(segment
		(start 129.54 -59.5122)
		(end 130.2766 -59.5122)
		(width 0.508)
		(layer "B.Cu")
		(net "GND")
	)
	(segment
		(start 36.4744 -24.4602)
		(end 40.03802 -24.4602)
		(width 0.508)
		(layer "B.Cu")
		(net "GND")
	)
	(segment
		(start 138.850116 -70.79996)
		(end 138.850116 -69.429884)
		(width 0.3048)
		(layer "B.Cu")
		(net "GND")
	)
	(segment
		(start 51.34991 -5.814568)
		(end 51.34991 -9.087358)
		(width 0.7112)
		(layer "B.Cu")
		(net "GND")
	)
	(segment
		(start 60.349892 -9.060688)
		(end 60.858146 -9.568942)
		(width 0.7112)
		(layer "B.Cu")
		(net "GND")
	)
	(segment
		(start 36.449 -20.8788)
		(end 36.449 -21.7932)
		(width 0.3048)
		(layer "B.Cu")
		(net "GND")
	)
	(segment
		(start 170.16222 -63.6524)
		(end 170.16222 -64.0461)
		(width 0.254)
		(layer "B.Cu")
		(net "GND")
	)
	(segment
		(start 48.006 -29.337)
		(end 47.844202 -29.498798)
		(width 0.508)
		(layer "B.Cu")
		(net "GND")
	)
	(segment
		(start 132.53466 -69.69506)
		(end 132.53466 -69.37756)
		(width 0.254)
		(layer "B.Cu")
		(net "GND")
	)
	(segment
		(start 146.649948 -70.79996)
		(end 146.649948 -69.398134)
		(width 0.254)
		(layer "B.Cu")
		(net "GND")
	)
	(segment
		(start 54.250336 -26.792936)
		(end 54.557422 -27.100022)
		(width 0.508)
		(layer "B.Cu")
		(net "GND")
	)
	(segment
		(start 189.249812 -3.09499)
		(end 189.2554 -3.100578)
		(width 0.254)
		(layer "B.Cu")
		(net "GND")
	)
	(segment
		(start 153.8478 -3.100578)
		(end 153.849832 -3.098546)
		(width 0.3048)
		(layer "B.Cu")
		(net "GND")
	)
	(segment
		(start 134.649972 -69.900546)
		(end 134.19582 -69.446394)
		(width 0.3048)
		(layer "B.Cu")
		(net "GND")
	)
	(segment
		(start 67.349878 -5.814568)
		(end 67.349878 -9.053322)
		(width 0.7112)
		(layer "B.Cu")
		(net "GND")
	)
	(segment
		(start 48.668178 -47.497238)
		(end 49.7586 -47.497238)
		(width 0.2032)
		(layer "B.Cu")
		(net "GND")
	)
	(segment
		(start 164.211 -72.39)
		(end 163.7792 -72.39)
		(width 0.3048)
		(layer "B.Cu")
		(net "GND")
	)
	(segment
		(start 130.449828 -1.690624)
		(end 130.449828 -2.956306)
		(width 0.254)
		(layer "B.Cu")
		(net "GND")
	)
	(segment
		(start 135.90524 -69.39534)
		(end 135.894572 -69.39534)
		(width 0.3048)
		(layer "B.Cu")
		(net "GND")
	)
	(segment
		(start 134.949946 -9.89076)
		(end 134.949946 -9.026398)
		(width 0.3048)
		(layer "B.Cu")
		(net "GND")
	)
	(segment
		(start 173.34992 -8.77316)
		(end 173.04512 -8.46836)
		(width 0.254)
		(layer "B.Cu")
		(net "GND")
	)
	(segment
		(start 119.399304 -3.79476)
		(end 119.75592 -4.151376)
		(width 0.3048)
		(layer "B.Cu")
		(net "GND")
	)
	(segment
		(start 164.349938 -62.599824)
		(end 164.349938 -63.6524)
		(width 0.3048)
		(layer "B.Cu")
		(net "GND")
	)
	(segment
		(start 50.0126 -17.4498)
		(end 50.1904 -17.4498)
		(width 0.3048)
		(layer "B.Cu")
		(net "GND")
	)
	(segment
		(start 142.6464 -44.704)
		(end 142.2908 -45.0596)
		(width 0.3048)
		(layer "B.Cu")
		(net "GND")
	)
	(segment
		(start 142.14983 -8.700516)
		(end 142.40129 -8.449056)
		(width 0.254)
		(layer "B.Cu")
		(net "GND")
	)
	(segment
		(start 69.6468 -59.8678)
		(end 70.2564 -59.8678)
		(width 0.3048)
		(layer "B.Cu")
		(net "GND")
	)
	(segment
		(start 205.0796 -38.9636)
		(end 204.597 -39.4462)
		(width 0.508)
		(layer "B.Cu")
		(net "GND")
	)
	(segment
		(start 43.5356 -32.0548)
		(end 43.6372 -32.1564)
		(width 0.508)
		(layer "B.Cu")
		(net "GND")
	)
	(segment
		(start 76.7588 -60.776612)
		(end 76.708 -60.827412)
		(width 0.3048)
		(layer "B.Cu")
		(net "GND")
	)
	(segment
		(start 68.349876 -9.117076)
		(end 68.834 -9.6012)
		(width 0.7112)
		(layer "B.Cu")
		(net "GND")
	)
	(segment
		(start 130.8862 -30.37078)
		(end 130.81 -30.29458)
		(width 0.3048)
		(layer "B.Cu")
		(net "GND")
	)
	(segment
		(start 69.215 -61.2648)
		(end 69.215 -60.2996)
		(width 0.3048)
		(layer "B.Cu")
		(net "GND")
	)
	(segment
		(start 31.75 -45.212)
		(end 31.9532 -45.0088)
		(width 0.3048)
		(layer "B.Cu")
		(net "GND")
	)
	(segment
		(start 187.149994 -62.599824)
		(end 187.149994 -63.811404)
		(width 0.3048)
		(layer "B.Cu")
		(net "GND")
	)
	(segment
		(start 177.54981 -8.94715)
		(end 178.003962 -8.492998)
		(width 0.254)
		(layer "B.Cu")
		(net "GND")
	)
	(segment
		(start 48.759872 -27.9908)
		(end 48.124872 -28.6258)
		(width 0.381)
		(layer "B.Cu")
		(net "GND")
	)
	(segment
		(start 130.750056 -8.679434)
		(end 130.30327 -8.232648)
		(width 0.254)
		(layer "B.Cu")
		(net "GND")
	)
	(segment
		(start 172.150024 -63.353696)
		(end 171.423076 -64.080644)
		(width 0.254)
		(layer "B.Cu")
		(net "GND")
	)
	(segment
		(start 62.562232 -32.662622)
		(end 62.562232 -32.71774)
		(width 0.508)
		(layer "B.Cu")
		(net "GND")
	)
	(segment
		(start 39.116 -30.9372)
		(end 38.39718 -30.9372)
		(width 0.3048)
		(layer "B.Cu")
		(net "GND")
	)
	(segment
		(start 146.950176 -63.993776)
		(end 147.0152 -64.0588)
		(width 0.3048)
		(layer "B.Cu")
		(net "GND")
	)
	(segment
		(start 110.0328 -4.318)
		(end 109.347 -4.318)
		(width 0.3048)
		(layer "B.Cu")
		(net "GND")
	)
	(segment
		(start 5.575046 -55.449978)
		(end 4.3942 -55.449978)
		(width 0.3048)
		(layer "B.Cu")
		(net "GND")
	)
	(segment
		(start 174.617126 -3.125724)
		(end 174.650908 -3.159506)
		(width 0.254)
		(layer "B.Cu")
		(net "GND")
	)
	(segment
		(start 72.349868 -5.814568)
		(end 72.349868 -9.078468)
		(width 0.7112)
		(layer "B.Cu")
		(net "GND")
	)
	(segment
		(start 69.43852 -35.43808)
		(end 68.961 -35.9156)
		(width 0.254)
		(layer "B.Cu")
		(net "GND")
	)
	(segment
		(start 171.69638 -8.457438)
		(end 171.69638 -8.449818)
		(width 0.254)
		(layer "B.Cu")
		(net "GND")
	)
	(segment
		(start 58.829194 -32.032194)
		(end 58.829194 -35.137344)
		(width 0.3048)
		(layer "B.Cu")
		(net "GND")
	)
	(segment
		(start 31.9532 -45.0088)
		(end 31.9532 -44.45)
		(width 0.3048)
		(layer "B.Cu")
		(net "GND")
	)
	(segment
		(start 140.58519 -64.03721)
		(end 140.58519 -64.092328)
		(width 0.254)
		(layer "B.Cu")
		(net "GND")
	)
	(segment
		(start 171.250102 -70.79996)
		(end 171.250102 -69.922898)
		(width 0.3048)
		(layer "B.Cu")
		(net "GND")
	)
	(segment
		(start 138.3792 -45.466)
		(end 138.9888 -45.466)
		(width 0.3048)
		(layer "B.Cu")
		(net "GND")
	)
	(segment
		(start 171.5516 -69.6214)
		(end 171.5516 -69.3674)
		(width 0.3048)
		(layer "B.Cu")
		(net "GND")
	)
	(segment
		(start 51.02479 -25.8445)
		(end 51.02479 -25.04821)
		(width 0.3048)
		(layer "B.Cu")
		(net "GND")
	)
	(segment
		(start 133.149848 -9.06653)
		(end 133.7818 -8.434578)
		(width 0.3048)
		(layer "B.Cu")
		(net "GND")
	)
	(segment
		(start 153.849832 -3.098546)
		(end 153.849832 -1.690624)
		(width 0.3048)
		(layer "B.Cu")
		(net "GND")
	)
	(segment
		(start 100.33 -68.7832)
		(end 100.1268 -68.7832)
		(width 0.3048)
		(layer "B.Cu")
		(net "GND")
	)
	(segment
		(start 62.526418 -29.100018)
		(end 62.1284 -28.702)
		(width 0.508)
		(layer "B.Cu")
		(net "GND")
	)
	(segment
		(start 28.349956 -5.814568)
		(end 28.349956 -9.061196)
		(width 0.7112)
		(layer "B.Cu")
		(net "GND")
	)
	(segment
		(start 42.8498 -17.61109)
		(end 42.8498 -17.5768)
		(width 0.3048)
		(layer "B.Cu")
		(net "GND")
	)
	(segment
		(start 185.35015 -63.358522)
		(end 184.55513 -64.153542)
		(width 0.254)
		(layer "B.Cu")
		(net "GND")
	)
	(segment
		(start 174.55007 -62.599824)
		(end 174.550324 -62.600078)
		(width 0.3048)
		(layer "B.Cu")
		(net "GND")
	)
	(segment
		(start 189.2554 -3.100578)
		(end 189.2554 -3.113024)
		(width 0.254)
		(layer "B.Cu")
		(net "GND")
	)
	(segment
		(start 48.9966 -27.9908)
		(end 48.759872 -27.9908)
		(width 0.381)
		(layer "B.Cu")
		(net "GND")
	)
	(segment
		(start 131.949952 -62.599824)
		(end 131.949952 -63.643002)
		(width 0.254)
		(layer "B.Cu")
		(net "GND")
	)
	(segment
		(start 62.657228 -26.699972)
		(end 63.946532 -26.699972)
		(width 0.508)
		(layer "B.Cu")
		(net "GND")
	)
	(segment
		(start 79.349854 -5.814568)
		(end 79.349854 -9.098026)
		(width 0.7112)
		(layer "B.Cu")
		(net "GND")
	)
	(segment
		(start 5.575046 -62.949836)
		(end 4.292346 -62.949836)
		(width 0.3048)
		(layer "B.Cu")
		(net "GND")
	)
	(segment
		(start 188.949838 -8.61314)
		(end 188.949838 -9.89076)
		(width 0.254)
		(layer "B.Cu")
		(net "GND")
	)
	(segment
		(start 33.7058 -51.833526)
		(end 33.274762 -52.264564)
		(width 0.3048)
		(layer "B.Cu")
		(net "GND")
	)
	(segment
		(start 62.181232 -34.342832)
		(end 63.946532 -36.108132)
		(width 0.508)
		(layer "B.Cu")
		(net "GND")
	)
	(segment
		(start 15.2908 -35.433)
		(end 15.494 -35.2298)
		(width 0.3048)
		(layer "B.Cu")
		(net "GND")
	)
	(segment
		(start 133.8072 -45.5676)
		(end 133.9088 -45.466)
		(width 0.3048)
		(layer "B.Cu")
		(net "GND")
	)
	(segment
		(start 56.3499 -9.059672)
		(end 56.862472 -9.572244)
		(width 0.7112)
		(layer "B.Cu")
		(net "GND")
	)
	(segment
		(start 51.5366 -49.3268)
		(end 51.5366 -48.641)
		(width 0.3048)
		(layer "B.Cu")
		(net "GND")
	)
	(segment
		(start 179.712112 -63.702184)
		(end 179.712112 -64.077088)
		(width 0.3048)
		(layer "B.Cu")
		(net "GND")
	)
	(segment
		(start 19.939 -66.1924)
		(end 19.9898 -66.1416)
		(width 0.2032)
		(layer "In2.Cu")
		(net "GND")
	)
	(segment
		(start 52.545234 -67.437)
		(end 46.906434 -67.437)
		(width 0.2032)
		(layer "In2.Cu")
		(net "GND")
	)
	(segment
		(start 27.718766 -71.247)
		(end 25.966166 -69.4944)
		(width 0.2032)
		(layer "In2.Cu")
		(net "GND")
	)
	(segment
		(start 46.906434 -67.437)
		(end 43.096434 -71.247)
		(width 0.2032)
		(layer "In2.Cu")
		(net "GND")
	)
	(segment
		(start 53.8226 -64.262)
		(end 53.8226 -66.159634)
		(width 0.2032)
		(layer "In2.Cu")
		(net "GND")
	)
	(segment
		(start 20.261834 -68.9864)
		(end 19.939 -68.663566)
		(width 0.2032)
		(layer "In2.Cu")
		(net "GND")
	)
	(segment
		(start 20.283932 -68.9864)
		(end 20.261834 -68.9864)
		(width 0.2032)
		(layer "In2.Cu")
		(net "GND")
	)
	(segment
		(start 20.791932 -69.4944)
		(end 20.283932 -68.9864)
		(width 0.2032)
		(layer "In2.Cu")
		(net "GND")
	)
	(segment
		(start 19.939 -68.663566)
		(end 19.939 -66.1924)
		(width 0.2032)
		(layer "In2.Cu")
		(net "GND")
	)
	(segment
		(start 19.9898 -66.1416)
		(end 19.9898 -65.9892)
		(width 0.2032)
		(layer "In2.Cu")
		(net "GND")
	)
	(segment
		(start 53.8226 -66.159634)
		(end 52.545234 -67.437)
		(width 0.2032)
		(layer "In2.Cu")
		(net "GND")
	)
	(segment
		(start 25.966166 -69.4944)
		(end 20.791932 -69.4944)
		(width 0.2032)
		(layer "In2.Cu")
		(net "GND")
	)
	(segment
		(start 43.096434 -71.247)
		(end 27.718766 -71.247)
		(width 0.2032)
		(layer "In2.Cu")
		(net "GND")
	)
	(segment
		(start 34.881566 -27.58948)
		(end 34.68116 -27.58948)
		(width 0.1143)
		(layer "F.Cu")
		(net "XDP_DFX_PORT14")
	)
	(segment
		(start 36.37788 -28.05557)
		(end 35.347656 -28.05557)
		(width 0.1143)
		(layer "F.Cu")
		(net "XDP_DFX_PORT14")
	)
	(segment
		(start 77.3176 -46.131734)
		(end 78.06182 -45.387514)
		(width 0.1143)
		(layer "F.Cu")
		(net "XDP_DFX_PORT14")
	)
	(segment
		(start 78.06182 -45.387514)
		(end 80.211168 -45.387514)
		(width 0.1143)
		(layer "F.Cu")
		(net "XDP_DFX_PORT14")
	)
	(segment
		(start 77.3176 -46.228)
		(end 77.3176 -46.131734)
		(width 0.1143)
		(layer "F.Cu")
		(net "XDP_DFX_PORT14")
	)
	(segment
		(start 35.347656 -28.05557)
		(end 34.881566 -27.58948)
		(width 0.1143)
		(layer "F.Cu")
		(net "XDP_DFX_PORT14")
	)
	(via
		(at 33.8328 -28.1432)
		(size 0.7112)
		(drill 0.3556)
		(layers "F.Cu" "B.Cu")
		(net "XDP_DFX_PORT14")
	)
	(via
		(at 77.3176 -46.228)
		(size 0.508)
		(drill 0.254)
		(layers "F.Cu" "B.Cu")
		(net "XDP_DFX_PORT14")
	)
	(via
		(at 34.68116 -27.58948)
		(size 0.508)
		(drill 0.254)
		(layers "F.Cu" "B.Cu")
		(net "XDP_DFX_PORT14")
	)
	(segment
		(start 34.12744 -28.1432)
		(end 34.68116 -27.58948)
		(width 0.1143)
		(layer "B.Cu")
		(net "XDP_DFX_PORT14")
	)
	(segment
		(start 33.8328 -28.1432)
		(end 34.12744 -28.1432)
		(width 0.1143)
		(layer "B.Cu")
		(net "XDP_DFX_PORT14")
	)
	(segment
		(start 76.971398 -46.574202)
		(end 76.284328 -46.574202)
		(width 0.0889)
		(layer "In7.Cu")
		(net "XDP_DFX_PORT14")
	)
	(segment
		(start 74.123296 -46.498002)
		(end 73.199244 -45.57395)
		(width 0.0889)
		(layer "In7.Cu")
		(net "XDP_DFX_PORT14")
	)
	(segment
		(start 39.579296 -34.30905)
		(end 38.258496 -34.30905)
		(width 0.0889)
		(layer "In7.Cu")
		(net "XDP_DFX_PORT14")
	)
	(segment
		(start 62.989206 -43.5864)
		(end 61.607954 -43.5864)
		(width 0.0889)
		(layer "In7.Cu")
		(net "XDP_DFX_PORT14")
	)
	(segment
		(start 35.2933 -28.20162)
		(end 34.68116 -27.58948)
		(width 0.0889)
		(layer "In7.Cu")
		(net "XDP_DFX_PORT14")
	)
	(segment
		(start 60.094114 -42.07256)
		(end 57.52592 -42.07256)
		(width 0.0889)
		(layer "In7.Cu")
		(net "XDP_DFX_PORT14")
	)
	(segment
		(start 57.52592 -42.07256)
		(end 57.16778 -42.4307)
		(width 0.0889)
		(layer "In7.Cu")
		(net "XDP_DFX_PORT14")
	)
	(segment
		(start 77.3176 -46.228)
		(end 76.971398 -46.574202)
		(width 0.0889)
		(layer "In7.Cu")
		(net "XDP_DFX_PORT14")
	)
	(segment
		(start 64.976756 -45.57395)
		(end 62.989206 -43.5864)
		(width 0.0889)
		(layer "In7.Cu")
		(net "XDP_DFX_PORT14")
	)
	(segment
		(start 38.258496 -34.30905)
		(end 35.2933 -31.343854)
		(width 0.0889)
		(layer "In7.Cu")
		(net "XDP_DFX_PORT14")
	)
	(segment
		(start 73.199244 -45.57395)
		(end 64.976756 -45.57395)
		(width 0.0889)
		(layer "In7.Cu")
		(net "XDP_DFX_PORT14")
	)
	(segment
		(start 61.607954 -43.5864)
		(end 60.094114 -42.07256)
		(width 0.0889)
		(layer "In7.Cu")
		(net "XDP_DFX_PORT14")
	)
	(segment
		(start 44.081446 -38.8112)
		(end 39.579296 -34.30905)
		(width 0.0889)
		(layer "In7.Cu")
		(net "XDP_DFX_PORT14")
	)
	(segment
		(start 76.208128 -46.498002)
		(end 74.123296 -46.498002)
		(width 0.0889)
		(layer "In7.Cu")
		(net "XDP_DFX_PORT14")
	)
	(segment
		(start 50.984658 -42.4307)
		(end 47.365158 -38.8112)
		(width 0.0889)
		(layer "In7.Cu")
		(net "XDP_DFX_PORT14")
	)
	(segment
		(start 35.2933 -31.343854)
		(end 35.2933 -28.20162)
		(width 0.0889)
		(layer "In7.Cu")
		(net "XDP_DFX_PORT14")
	)
	(segment
		(start 76.284328 -46.574202)
		(end 76.208128 -46.498002)
		(width 0.0889)
		(layer "In7.Cu")
		(net "XDP_DFX_PORT14")
	)
	(segment
		(start 57.16778 -42.4307)
		(end 50.984658 -42.4307)
		(width 0.0889)
		(layer "In7.Cu")
		(net "XDP_DFX_PORT14")
	)
	(segment
		(start 47.365158 -38.8112)
		(end 44.081446 -38.8112)
		(width 0.0889)
		(layer "In7.Cu")
		(net "XDP_DFX_PORT14")
	)
	(via
		(at 136.271 -58.801)
		(size 0.7112)
		(drill 0.3556)
		(layers "F.Cu" "B.Cu")
		(net "CHA_0_SA0")
	)
	(segment
		(start 136.017 -58.801)
		(end 134.4422 -60.3758)
		(width 0.1143)
		(layer "B.Cu")
		(net "CHA_0_SA0")
	)
	(segment
		(start 128.949958 -61.909452)
		(end 129.35204 -61.50737)
		(width 0.1143)
		(layer "B.Cu")
		(net "CHA_0_SA0")
	)
	(segment
		(start 134.4422 -60.3758)
		(end 133.35 -60.3758)
		(width 0.1143)
		(layer "B.Cu")
		(net "CHA_0_SA0")
	)
	(segment
		(start 136.271 -58.801)
		(end 136.017 -58.801)
		(width 0.1143)
		(layer "B.Cu")
		(net "CHA_0_SA0")
	)
	(segment
		(start 128.949958 -62.599824)
		(end 128.949958 -61.909452)
		(width 0.1143)
		(layer "B.Cu")
		(net "CHA_0_SA0")
	)
	(segment
		(start 132.21843 -61.50737)
		(end 133.35 -60.3758)
		(width 0.1143)
		(layer "B.Cu")
		(net "CHA_0_SA0")
	)
	(segment
		(start 129.35204 -61.50737)
		(end 132.21843 -61.50737)
		(width 0.1143)
		(layer "B.Cu")
		(net "CHA_0_SA0")
	)
	(segment
		(start 136.779 -59.7662)
		(end 136.779 -59.182)
		(width 0.1143)
		(layer "B.Cu")
		(net "CHA_0_SA0")
	)
	(segment
		(start 136.779 -59.182)
		(end 136.398 -58.801)
		(width 0.1143)
		(layer "B.Cu")
		(net "CHA_0_SA0")
	)
	(segment
		(start 136.398 -58.801)
		(end 136.271 -58.801)
		(width 0.1143)
		(layer "B.Cu")
		(net "CHA_0_SA0")
	)
	(via
		(at 205.4606 -45.593)
		(size 0.7112)
		(drill 0.3556)
		(layers "F.Cu" "B.Cu")
		(net "VR_PVDDR_A_VSW_R")
	)
	(segment
		(start 204.0128 -45.593)
		(end 202.6666 -45.593)
		(width 0.508)
		(layer "B.Cu")
		(net "VR_PVDDR_A_VSW_R")
	)
	(segment
		(start 204.0128 -45.593)
		(end 205.4606 -45.593)
		(width 0.508)
		(layer "B.Cu")
		(net "VR_PVDDR_A_VSW_R")
	)
	(segment
		(start 202.6666 -45.593)
		(end 202.438 -45.3644)
		(width 0.508)
		(layer "B.Cu")
		(net "VR_PVDDR_A_VSW_R")
	)
	(segment
		(start 170.349926 -3.006344)
		(end 170.50766 -3.164078)
		(width 0.1778)
		(layer "F.Cu")
		(net "M_B_DQ36")
	)
	(segment
		(start 104.264968 -33.4264)
		(end 103.874824 -33.036256)
		(width 0.1016)
		(layer "F.Cu")
		(net "M_B_DQ36")
	)
	(segment
		(start 170.349926 -1.68402)
		(end 170.349926 -3.006344)
		(width 0.1778)
		(layer "F.Cu")
		(net "M_B_DQ36")
	)
	(segment
		(start 104.264968 -33.426654)
		(end 104.264968 -33.4264)
		(width 0.1016)
		(layer "F.Cu")
		(net "M_B_DQ36")
	)
	(via
		(at 103.874824 -33.036256)
		(size 0.4318)
		(drill 0.2032)
		(layers "F.Cu" "B.Cu")
		(net "M_B_DQ36")
	)
	(via
		(at 170.50766 -3.164078)
		(size 0.4318)
		(drill 0.2032)
		(layers "F.Cu" "B.Cu")
		(net "M_B_DQ36")
	)
	(segment
		(start 170.6499 -3.021838)
		(end 170.50766 -3.164078)
		(width 0.1778)
		(layer "B.Cu")
		(net "M_B_DQ36")
	)
	(segment
		(start 170.6499 -1.690624)
		(end 170.6499 -3.021838)
		(width 0.1778)
		(layer "B.Cu")
		(net "M_B_DQ36")
	)
	(segment
		(start 103.54564 -29.82976)
		(end 103.54564 -31.05404)
		(width 0.1016)
		(layer "In4.Cu")
		(net "M_B_DQ36")
	)
	(segment
		(start 104.521 -28.956)
		(end 104.3432 -29.1338)
		(width 0.1016)
		(layer "In4.Cu")
		(net "M_B_DQ36")
	)
	(segment
		(start 109.5756 -27.4828)
		(end 111.398812 -25.659588)
		(width 0.1524)
		(layer "In4.Cu")
		(net "M_B_DQ36")
	)
	(segment
		(start 166.45128 -14.9606)
		(end 169.30624 -12.10564)
		(width 0.1524)
		(layer "In4.Cu")
		(net "M_B_DQ36")
	)
	(segment
		(start 107.6198 -27.4828)
		(end 109.5756 -27.4828)
		(width 0.1524)
		(layer "In4.Cu")
		(net "M_B_DQ36")
	)
	(segment
		(start 107.1118 -27.9908)
		(end 107.6198 -27.4828)
		(width 0.1524)
		(layer "In4.Cu")
		(net "M_B_DQ36")
	)
	(segment
		(start 103.759 -29.6164)
		(end 103.54564 -29.82976)
		(width 0.1016)
		(layer "In4.Cu")
		(net "M_B_DQ36")
	)
	(segment
		(start 104.3432 -29.3878)
		(end 104.1146 -29.6164)
		(width 0.1016)
		(layer "In4.Cu")
		(net "M_B_DQ36")
	)
	(segment
		(start 169.30624 -4.380738)
		(end 170.50766 -3.179318)
		(width 0.1524)
		(layer "In4.Cu")
		(net "M_B_DQ36")
	)
	(segment
		(start 105.59669 -28.956)
		(end 104.521 -28.956)
		(width 0.1016)
		(layer "In4.Cu")
		(net "M_B_DQ36")
	)
	(segment
		(start 114.6048 -25.654)
		(end 114.7572 -25.5016)
		(width 0.1524)
		(layer "In4.Cu")
		(net "M_B_DQ36")
	)
	(segment
		(start 114.596418 -25.654)
		(end 114.6048 -25.654)
		(width 0.1524)
		(layer "In4.Cu")
		(net "M_B_DQ36")
	)
	(segment
		(start 153.986738 -25.0952)
		(end 164.121338 -14.9606)
		(width 0.1524)
		(layer "In4.Cu")
		(net "M_B_DQ36")
	)
	(segment
		(start 103.54564 -31.05404)
		(end 103.6828 -31.1912)
		(width 0.1016)
		(layer "In4.Cu")
		(net "M_B_DQ36")
	)
	(segment
		(start 111.398812 -25.659588)
		(end 114.59083 -25.659588)
		(width 0.1524)
		(layer "In4.Cu")
		(net "M_B_DQ36")
	)
	(segment
		(start 114.7572 -25.5016)
		(end 114.7572 -25.493218)
		(width 0.1524)
		(layer "In4.Cu")
		(net "M_B_DQ36")
	)
	(segment
		(start 114.7572 -25.493218)
		(end 115.155218 -25.0952)
		(width 0.1524)
		(layer "In4.Cu")
		(net "M_B_DQ36")
	)
	(segment
		(start 103.6828 -32.844232)
		(end 103.874824 -33.036256)
		(width 0.1016)
		(layer "In4.Cu")
		(net "M_B_DQ36")
	)
	(segment
		(start 104.1146 -29.6164)
		(end 103.759 -29.6164)
		(width 0.1016)
		(layer "In4.Cu")
		(net "M_B_DQ36")
	)
	(segment
		(start 103.6828 -31.1912)
		(end 103.6828 -32.844232)
		(width 0.1016)
		(layer "In4.Cu")
		(net "M_B_DQ36")
	)
	(segment
		(start 115.155218 -25.0952)
		(end 153.986738 -25.0952)
		(width 0.1524)
		(layer "In4.Cu")
		(net "M_B_DQ36")
	)
	(segment
		(start 169.30624 -12.10564)
		(end 169.30624 -4.380738)
		(width 0.1524)
		(layer "In4.Cu")
		(net "M_B_DQ36")
	)
	(segment
		(start 114.59083 -25.659588)
		(end 114.596418 -25.654)
		(width 0.1524)
		(layer "In4.Cu")
		(net "M_B_DQ36")
	)
	(segment
		(start 104.3432 -29.1338)
		(end 104.3432 -29.3878)
		(width 0.1016)
		(layer "In4.Cu")
		(net "M_B_DQ36")
	)
	(segment
		(start 164.121338 -14.9606)
		(end 166.45128 -14.9606)
		(width 0.1524)
		(layer "In4.Cu")
		(net "M_B_DQ36")
	)
	(segment
		(start 105.78719 -28.7655)
		(end 106.56189 -27.9908)
		(width 0.1524)
		(layer "In4.Cu")
		(net "M_B_DQ36")
	)
	(segment
		(start 170.50766 -3.179318)
		(end 170.50766 -3.164078)
		(width 0.1524)
		(layer "In4.Cu")
		(net "M_B_DQ36")
	)
	(segment
		(start 105.78719 -28.7655)
		(end 105.59669 -28.956)
		(width 0.1016)
		(layer "In4.Cu")
		(net "M_B_DQ36")
	)
	(segment
		(start 106.56189 -27.9908)
		(end 107.1118 -27.9908)
		(width 0.1524)
		(layer "In4.Cu")
		(net "M_B_DQ36")
	)
	(segment
		(start 34.92246 -30.55366)
		(end 34.92373 -30.55493)
		(width 0.2794)
		(layer "F.Cu")
		(net "VCC_OBS_CD")
	)
	(segment
		(start 33.20034 -30.55366)
		(end 34.92246 -30.55366)
		(width 0.2794)
		(layer "F.Cu")
		(net "VCC_OBS_CD")
	)
	(segment
		(start 34.92373 -30.55493)
		(end 36.37788 -30.55493)
		(width 0.2794)
		(layer "F.Cu")
		(net "VCC_OBS_CD")
	)
	(segment
		(start 33.02 -30.734)
		(end 33.20034 -30.55366)
		(width 0.2794)
		(layer "F.Cu")
		(net "VCC_OBS_CD")
	)
	(via
		(at 33.02 -30.734)
		(size 0.508)
		(drill 0.254)
		(layers "F.Cu" "B.Cu")
		(net "VCC_OBS_CD")
	)
	(via
		(at 23.842218 -14.6558)
		(size 0.7112)
		(drill 0.3556)
		(layers "F.Cu" "B.Cu")
		(net "VCC_OBS_CD")
	)
	(via
		(at 24.4348 -15.4178)
		(size 0.508)
		(drill 0.254)
		(layers "F.Cu" "B.Cu")
		(net "VCC_OBS_CD")
	)
	(segment
		(start 23.842218 -14.825218)
		(end 24.4348 -15.4178)
		(width 0.3048)
		(layer "B.Cu")
		(net "VCC_OBS_CD")
	)
	(segment
		(start 32.0294 -30.734)
		(end 33.02 -30.734)
		(width 0.3048)
		(layer "B.Cu")
		(net "VCC_OBS_CD")
	)
	(segment
		(start 23.842218 -14.6558)
		(end 23.842218 -14.825218)
		(width 0.3048)
		(layer "B.Cu")
		(net "VCC_OBS_CD")
	)
	(segment
		(start 29.6418 -29.686758)
		(end 30.689042 -30.734)
		(width 0.3048)
		(layer "In9.Cu")
		(net "VCC_OBS_CD")
	)
	(segment
		(start 24.4348 -15.4178)
		(end 24.4348 -17.815306)
		(width 0.3048)
		(layer "In9.Cu")
		(net "VCC_OBS_CD")
	)
	(segment
		(start 30.689042 -30.734)
		(end 33.02 -30.734)
		(width 0.3048)
		(layer "In9.Cu")
		(net "VCC_OBS_CD")
	)
	(segment
		(start 24.4348 -17.815306)
		(end 29.6418 -23.022306)
		(width 0.3048)
		(layer "In9.Cu")
		(net "VCC_OBS_CD")
	)
	(segment
		(start 29.6418 -23.022306)
		(end 29.6418 -29.686758)
		(width 0.3048)
		(layer "In9.Cu")
		(net "VCC_OBS_CD")
	)
	(segment
		(start 184.023 -57.023)
		(end 184.7596 -57.7596)
		(width 0.1778)
		(layer "F.Cu")
		(net "DDR3_M_A_VREF_DQ0")
	)
	(segment
		(start 183.769 -57.023)
		(end 184.023 -57.023)
		(width 0.1778)
		(layer "F.Cu")
		(net "DDR3_M_A_VREF_DQ0")
	)
	(segment
		(start 182.499 -56.0578)
		(end 183.4642 -57.023)
		(width 0.1778)
		(layer "F.Cu")
		(net "DDR3_M_A_VREF_DQ0")
	)
	(segment
		(start 183.4642 -57.023)
		(end 183.769 -57.023)
		(width 0.1778)
		(layer "F.Cu")
		(net "DDR3_M_A_VREF_DQ0")
	)
	(via
		(at 183.769 -57.023)
		(size 0.7112)
		(drill 0.3556)
		(layers "F.Cu" "B.Cu")
		(net "DDR3_M_A_VREF_DQ0")
	)
	(via
		(at 184.7596 -57.7596)
		(size 0.508)
		(drill 0.254)
		(layers "F.Cu" "B.Cu")
		(net "DDR3_M_A_VREF_DQ0")
	)
	(segment
		(start 190.149988 -62.599824)
		(end 190.149988 -61.067188)
		(width 0.1778)
		(layer "B.Cu")
		(net "DDR3_M_A_VREF_DQ0")
	)
	(segment
		(start 189.865 -60.7822)
		(end 189.103 -60.7822)
		(width 0.1778)
		(layer "B.Cu")
		(net "DDR3_M_A_VREF_DQ0")
	)
	(segment
		(start 187.6044 -60.6044)
		(end 184.7596 -57.7596)
		(width 0.1778)
		(layer "B.Cu")
		(net "DDR3_M_A_VREF_DQ0")
	)
	(segment
		(start 190.149988 -61.067188)
		(end 189.865 -60.7822)
		(width 0.1778)
		(layer "B.Cu")
		(net "DDR3_M_A_VREF_DQ0")
	)
	(segment
		(start 187.96 -60.6044)
		(end 187.6044 -60.6044)
		(width 0.1778)
		(layer "B.Cu")
		(net "DDR3_M_A_VREF_DQ0")
	)
	(segment
		(start 188.9252 -60.6044)
		(end 189.103 -60.7822)
		(width 0.1778)
		(layer "B.Cu")
		(net "DDR3_M_A_VREF_DQ0")
	)
	(segment
		(start 187.96 -60.6044)
		(end 188.9252 -60.6044)
		(width 0.1778)
		(layer "B.Cu")
		(net "DDR3_M_A_VREF_DQ0")
	)
	(segment
		(start 17.146524 -24.280876)
		(end 17.3228 -24.1046)
		(width 0.254)
		(layer "F.Cu")
		(net "PG_P1V0")
	)
	(segment
		(start 16.292322 -24.280876)
		(end 17.146524 -24.280876)
		(width 0.254)
		(layer "F.Cu")
		(net "PG_P1V0")
	)
	(via
		(at 16.6878 -24.9174)
		(size 0.7112)
		(drill 0.3556)
		(layers "F.Cu" "B.Cu")
		(net "PG_P1V0")
	)
	(via
		(at 17.3228 -24.1046)
		(size 0.508)
		(drill 0.254)
		(layers "F.Cu" "B.Cu")
		(net "PG_P1V0")
	)
	(segment
		(start 16.3068 -24.003)
		(end 16.3068 -24.5364)
		(width 0.254)
		(layer "B.Cu")
		(net "PG_P1V0")
	)
	(segment
		(start 16.3068 -24.5364)
		(end 16.6878 -24.9174)
		(width 0.254)
		(layer "B.Cu")
		(net "PG_P1V0")
	)
	(segment
		(start 16.9418 -24.9174)
		(end 16.6878 -24.9174)
		(width 0.254)
		(layer "B.Cu")
		(net "PG_P1V0")
	)
	(segment
		(start 17.3228 -24.5364)
		(end 16.9418 -24.9174)
		(width 0.254)
		(layer "B.Cu")
		(net "PG_P1V0")
	)
	(segment
		(start 16.3068 -23.114)
		(end 16.3068 -24.003)
		(width 0.254)
		(layer "B.Cu")
		(net "PG_P1V0")
	)
	(segment
		(start 17.3228 -24.1046)
		(end 17.3228 -24.5364)
		(width 0.254)
		(layer "B.Cu")
		(net "PG_P1V0")
	)
	(segment
		(start 16.3068 -22.352)
		(end 16.383 -22.2758)
		(width 0.254)
		(layer "B.Cu")
		(net "PG_P1V0")
	)
	(segment
		(start 16.3068 -23.114)
		(end 16.3068 -22.352)
		(width 0.254)
		(layer "B.Cu")
		(net "PG_P1V0")
	)
	(via
		(at 189.0014 -26.5938)
		(size 0.7112)
		(drill 0.3556)
		(layers "F.Cu" "B.Cu")
		(net "VR_PVDDRA_ISUMP1_R")
	)
	(segment
		(start 189.357 -26.9494)
		(end 189.0014 -26.5938)
		(width 0.2032)
		(layer "B.Cu")
		(net "VR_PVDDRA_ISUMP1_R")
	)
	(segment
		(start 189.357 -27.5082)
		(end 189.357 -26.9494)
		(width 0.2032)
		(layer "B.Cu")
		(net "VR_PVDDRA_ISUMP1_R")
	)
	(segment
		(start 189.357 -27.5082)
		(end 190.119 -27.5082)
		(width 0.2032)
		(layer "B.Cu")
		(net "VR_PVDDRA_ISUMP1_R")
	)
	(segment
		(start 111.10087 -65.547494)
		(end 110.481364 -66.167)
		(width 0.1143)
		(layer "F.Cu")
		(net "M_DRAM_PWROK")
	)
	(segment
		(start 110.993174 -63.63081)
		(end 111.10087 -63.738506)
		(width 0.1143)
		(layer "F.Cu")
		(net "M_DRAM_PWROK")
	)
	(segment
		(start 109.840268 -63.63081)
		(end 110.993174 -63.63081)
		(width 0.1143)
		(layer "F.Cu")
		(net "M_DRAM_PWROK")
	)
	(segment
		(start 104.264968 -31.140654)
		(end 104.468422 -30.9372)
		(width 0.1143)
		(layer "F.Cu")
		(net "M_DRAM_PWROK")
	)
	(segment
		(start 104.358694 -48.783494)
		(end 104.026208 -48.783494)
		(width 0.1143)
		(layer "F.Cu")
		(net "M_DRAM_PWROK")
	)
	(segment
		(start 110.481364 -66.167)
		(end 108.2802 -66.167)
		(width 0.1143)
		(layer "F.Cu")
		(net "M_DRAM_PWROK")
	)
	(segment
		(start 108.56976 -65.29324)
		(end 108.2802 -65.5828)
		(width 0.1143)
		(layer "F.Cu")
		(net "M_DRAM_PWROK")
	)
	(segment
		(start 111.10087 -63.738506)
		(end 111.10087 -65.547494)
		(width 0.1143)
		(layer "F.Cu")
		(net "M_DRAM_PWROK")
	)
	(segment
		(start 108.66628 -65.29324)
		(end 108.56976 -65.29324)
		(width 0.1143)
		(layer "F.Cu")
		(net "M_DRAM_PWROK")
	)
	(segment
		(start 108.3818 -62.172342)
		(end 109.840268 -63.63081)
		(width 0.1143)
		(layer "F.Cu")
		(net "M_DRAM_PWROK")
	)
	(segment
		(start 108.3564 -62.0903)
		(end 108.3818 -62.1157)
		(width 0.1143)
		(layer "F.Cu")
		(net "M_DRAM_PWROK")
	)
	(segment
		(start 104.6988 -48.9204)
		(end 104.4956 -48.9204)
		(width 0.1143)
		(layer "F.Cu")
		(net "M_DRAM_PWROK")
	)
	(segment
		(start 104.4956 -48.9204)
		(end 104.358694 -48.783494)
		(width 0.1143)
		(layer "F.Cu")
		(net "M_DRAM_PWROK")
	)
	(segment
		(start 108.3818 -62.1157)
		(end 108.3818 -62.172342)
		(width 0.1143)
		(layer "F.Cu")
		(net "M_DRAM_PWROK")
	)
	(segment
		(start 104.468422 -30.9372)
		(end 104.9274 -30.9372)
		(width 0.1143)
		(layer "F.Cu")
		(net "M_DRAM_PWROK")
	)
	(segment
		(start 108.2802 -65.5828)
		(end 108.2802 -66.167)
		(width 0.1143)
		(layer "F.Cu")
		(net "M_DRAM_PWROK")
	)
	(via
		(at 108.3564 -62.0903)
		(size 0.508)
		(drill 0.254)
		(layers "F.Cu" "B.Cu")
		(net "M_DRAM_PWROK")
	)
	(via
		(at 106.56951 -59.30011)
		(size 0.7112)
		(drill 0.3556)
		(layers "F.Cu" "B.Cu")
		(net "M_DRAM_PWROK")
	)
	(via
		(at 104.6988 -48.9204)
		(size 0.4318)
		(drill 0.2032)
		(layers "F.Cu" "B.Cu")
		(net "M_DRAM_PWROK")
	)
	(via
		(at 104.9274 -30.9372)
		(size 0.4318)
		(drill 0.2032)
		(layers "F.Cu" "B.Cu")
		(net "M_DRAM_PWROK")
	)
	(segment
		(start 108.3564 -62.0903)
		(end 108.3564 -61.087)
		(width 0.1143)
		(layer "B.Cu")
		(net "M_DRAM_PWROK")
	)
	(segment
		(start 106.56951 -59.30011)
		(end 105.88371 -59.30011)
		(width 0.1143)
		(layer "B.Cu")
		(net "M_DRAM_PWROK")
	)
	(segment
		(start 104.14 -57.5564)
		(end 104.14 -54.483)
		(width 0.1143)
		(layer "B.Cu")
		(net "M_DRAM_PWROK")
	)
	(segment
		(start 104.648 -50.8508)
		(end 104.3686 -50.5714)
		(width 0.1143)
		(layer "B.Cu")
		(net "M_DRAM_PWROK")
	)
	(segment
		(start 105.88371 -59.30011)
		(end 104.14 -57.5564)
		(width 0.1143)
		(layer "B.Cu")
		(net "M_DRAM_PWROK")
	)
	(segment
		(start 108.3564 -61.087)
		(end 106.56951 -59.30011)
		(width 0.1143)
		(layer "B.Cu")
		(net "M_DRAM_PWROK")
	)
	(segment
		(start 104.3686 -49.276)
		(end 104.6988 -48.9458)
		(width 0.1143)
		(layer "B.Cu")
		(net "M_DRAM_PWROK")
	)
	(segment
		(start 104.6988 -48.9458)
		(end 104.6988 -48.9204)
		(width 0.1143)
		(layer "B.Cu")
		(net "M_DRAM_PWROK")
	)
	(segment
		(start 103.5558 -52.832)
		(end 104.0638 -52.324)
		(width 0.1143)
		(layer "B.Cu")
		(net "M_DRAM_PWROK")
	)
	(segment
		(start 104.3178 -52.324)
		(end 104.648 -51.9938)
		(width 0.1143)
		(layer "B.Cu")
		(net "M_DRAM_PWROK")
	)
	(segment
		(start 104.3686 -50.5714)
		(end 104.3686 -49.276)
		(width 0.1143)
		(layer "B.Cu")
		(net "M_DRAM_PWROK")
	)
	(segment
		(start 111.9632 -32.274002)
		(end 111.826802 -32.137604)
		(width 0.1143)
		(layer "B.Cu")
		(net "M_DRAM_PWROK")
	)
	(segment
		(start 105.546906 -31.556706)
		(end 109.098842 -31.556706)
		(width 0.1143)
		(layer "B.Cu")
		(net "M_DRAM_PWROK")
	)
	(segment
		(start 104.14 -54.483)
		(end 103.5558 -53.8988)
		(width 0.1143)
		(layer "B.Cu")
		(net "M_DRAM_PWROK")
	)
	(segment
		(start 104.648 -51.9938)
		(end 104.648 -50.8508)
		(width 0.1143)
		(layer "B.Cu")
		(net "M_DRAM_PWROK")
	)
	(segment
		(start 109.098842 -31.556706)
		(end 109.22 -31.435802)
		(width 0.1143)
		(layer "B.Cu")
		(net "M_DRAM_PWROK")
	)
	(segment
		(start 104.0638 -52.324)
		(end 104.3178 -52.324)
		(width 0.1143)
		(layer "B.Cu")
		(net "M_DRAM_PWROK")
	)
	(segment
		(start 109.22 -31.435802)
		(end 109.982 -31.435802)
		(width 0.1143)
		(layer "B.Cu")
		(net "M_DRAM_PWROK")
	)
	(segment
		(start 111.826802 -32.137604)
		(end 110.683802 -32.137604)
		(width 0.1143)
		(layer "B.Cu")
		(net "M_DRAM_PWROK")
	)
	(segment
		(start 104.9274 -30.9372)
		(end 105.546906 -31.556706)
		(width 0.1143)
		(layer "B.Cu")
		(net "M_DRAM_PWROK")
	)
	(segment
		(start 110.683802 -32.137604)
		(end 109.982 -31.435802)
		(width 0.1143)
		(layer "B.Cu")
		(net "M_DRAM_PWROK")
	)
	(segment
		(start 103.5558 -53.8988)
		(end 103.5558 -52.832)
		(width 0.1143)
		(layer "B.Cu")
		(net "M_DRAM_PWROK")
	)
	(segment
		(start 100.76561 -44.009056)
		(end 100.529898 -44.009056)
		(width 0.0889)
		(layer "In2.Cu")
		(net "M_DRAM_PWROK")
	)
	(segment
		(start 103.349806 -34.089594)
		(end 104.403398 -33.036002)
		(width 0.0889)
		(layer "In2.Cu")
		(net "M_DRAM_PWROK")
	)
	(segment
		(start 104.403398 -31.232602)
		(end 104.648 -30.988)
		(width 0.0889)
		(layer "In2.Cu")
		(net "M_DRAM_PWROK")
	)
	(segment
		(start 99.094798 -42.552874)
		(end 99.094798 -37.934138)
		(width 0.0889)
		(layer "In2.Cu")
		(net "M_DRAM_PWROK")
	)
	(segment
		(start 102.20452 -36.118546)
		(end 103.349806 -34.97326)
		(width 0.0889)
		(layer "In2.Cu")
		(net "M_DRAM_PWROK")
	)
	(segment
		(start 103.349806 -34.97326)
		(end 103.349806 -34.089594)
		(width 0.0889)
		(layer "In2.Cu")
		(net "M_DRAM_PWROK")
	)
	(segment
		(start 99.511866 -37.04463)
		(end 100.43795 -36.118546)
		(width 0.0889)
		(layer "In2.Cu")
		(net "M_DRAM_PWROK")
	)
	(segment
		(start 104.14 -48.2092)
		(end 103.5304 -47.5996)
		(width 0.0889)
		(layer "In2.Cu")
		(net "M_DRAM_PWROK")
	)
	(segment
		(start 99.788218 -43.246294)
		(end 99.094798 -42.552874)
		(width 0.0889)
		(layer "In2.Cu")
		(net "M_DRAM_PWROK")
	)
	(segment
		(start 104.403398 -33.036002)
		(end 104.403398 -31.232602)
		(width 0.0889)
		(layer "In2.Cu")
		(net "M_DRAM_PWROK")
	)
	(segment
		(start 103.046022 -47.358046)
		(end 102.704646 -47.358046)
		(width 0.0889)
		(layer "In2.Cu")
		(net "M_DRAM_PWROK")
	)
	(segment
		(start 102.108 -45.566076)
		(end 100.977446 -44.435522)
		(width 0.0889)
		(layer "In2.Cu")
		(net "M_DRAM_PWROK")
	)
	(segment
		(start 104.648 -30.988)
		(end 104.8766 -30.988)
		(width 0.0889)
		(layer "In2.Cu")
		(net "M_DRAM_PWROK")
	)
	(segment
		(start 104.8766 -30.988)
		(end 104.9274 -30.9372)
		(width 0.0889)
		(layer "In2.Cu")
		(net "M_DRAM_PWROK")
	)
	(segment
		(start 102.108 -46.7614)
		(end 102.108 -45.566076)
		(width 0.0889)
		(layer "In2.Cu")
		(net "M_DRAM_PWROK")
	)
	(segment
		(start 99.511866 -37.51707)
		(end 99.511866 -37.04463)
		(width 0.0889)
		(layer "In2.Cu")
		(net "M_DRAM_PWROK")
	)
	(segment
		(start 99.993704 -43.246294)
		(end 99.788218 -43.246294)
		(width 0.0889)
		(layer "In2.Cu")
		(net "M_DRAM_PWROK")
	)
	(segment
		(start 99.094798 -37.934138)
		(end 99.511866 -37.51707)
		(width 0.0889)
		(layer "In2.Cu")
		(net "M_DRAM_PWROK")
	)
	(segment
		(start 100.43795 -36.118546)
		(end 102.20452 -36.118546)
		(width 0.0889)
		(layer "In2.Cu")
		(net "M_DRAM_PWROK")
	)
	(segment
		(start 100.529898 -44.009056)
		(end 100.2792 -43.758358)
		(width 0.0889)
		(layer "In2.Cu")
		(net "M_DRAM_PWROK")
	)
	(segment
		(start 100.2792 -43.53179)
		(end 99.993704 -43.246294)
		(width 0.0889)
		(layer "In2.Cu")
		(net "M_DRAM_PWROK")
	)
	(segment
		(start 104.6988 -48.9204)
		(end 104.4448 -48.9204)
		(width 0.0889)
		(layer "In2.Cu")
		(net "M_DRAM_PWROK")
	)
	(segment
		(start 103.5304 -47.5996)
		(end 103.287576 -47.5996)
		(width 0.0889)
		(layer "In2.Cu")
		(net "M_DRAM_PWROK")
	)
	(segment
		(start 102.704646 -47.358046)
		(end 102.108 -46.7614)
		(width 0.0889)
		(layer "In2.Cu")
		(net "M_DRAM_PWROK")
	)
	(segment
		(start 100.977446 -44.435522)
		(end 100.977446 -44.220892)
		(width 0.0889)
		(layer "In2.Cu")
		(net "M_DRAM_PWROK")
	)
	(segment
		(start 104.14 -48.6156)
		(end 104.14 -48.2092)
		(width 0.0889)
		(layer "In2.Cu")
		(net "M_DRAM_PWROK")
	)
	(segment
		(start 104.4448 -48.9204)
		(end 104.14 -48.6156)
		(width 0.0889)
		(layer "In2.Cu")
		(net "M_DRAM_PWROK")
	)
	(segment
		(start 100.2792 -43.758358)
		(end 100.2792 -43.53179)
		(width 0.0889)
		(layer "In2.Cu")
		(net "M_DRAM_PWROK")
	)
	(segment
		(start 103.287576 -47.5996)
		(end 103.046022 -47.358046)
		(width 0.0889)
		(layer "In2.Cu")
		(net "M_DRAM_PWROK")
	)
	(segment
		(start 100.977446 -44.220892)
		(end 100.76561 -44.009056)
		(width 0.0889)
		(layer "In2.Cu")
		(net "M_DRAM_PWROK")
	)
	(segment
		(start 140.64996 -9.206738)
		(end 140.0937 -8.650478)
		(width 0.1778)
		(layer "F.Cu")
		(net "M_B_DQ17")
	)
	(segment
		(start 140.64996 -9.897364)
		(end 140.64996 -9.206738)
		(width 0.1778)
		(layer "F.Cu")
		(net "M_B_DQ17")
	)
	(segment
		(start 100.1014 -23.2156)
		(end 100.4697 -23.5839)
		(width 0.1016)
		(layer "F.Cu")
		(net "M_B_DQ17")
	)
	(segment
		(start 140.0937 -8.650478)
		(end 140.0937 -8.189214)
		(width 0.1778)
		(layer "F.Cu")
		(net "M_B_DQ17")
	)
	(segment
		(start 100.4697 -23.5839)
		(end 100.4697 -24.8285)
		(width 0.1016)
		(layer "F.Cu")
		(net "M_B_DQ17")
	)
	(segment
		(start 100.8761 -25.353772)
		(end 101.214428 -25.6921)
		(width 0.1016)
		(layer "F.Cu")
		(net "M_B_DQ17")
	)
	(segment
		(start 100.8761 -25.2349)
		(end 100.8761 -25.353772)
		(width 0.1016)
		(layer "F.Cu")
		(net "M_B_DQ17")
	)
	(segment
		(start 101.214428 -25.6921)
		(end 101.214428 -26.393394)
		(width 0.1016)
		(layer "F.Cu")
		(net "M_B_DQ17")
	)
	(segment
		(start 100.4697 -24.8285)
		(end 100.8761 -25.2349)
		(width 0.1016)
		(layer "F.Cu")
		(net "M_B_DQ17")
	)
	(segment
		(start 140.0937 -8.189214)
		(end 140.482066 -7.800848)
		(width 0.1778)
		(layer "F.Cu")
		(net "M_B_DQ17")
	)
	(via
		(at 100.1014 -23.2156)
		(size 0.4318)
		(drill 0.2032)
		(layers "F.Cu" "B.Cu")
		(net "M_B_DQ17")
	)
	(via
		(at 140.482066 -7.800848)
		(size 0.4318)
		(drill 0.2032)
		(layers "F.Cu" "B.Cu")
		(net "M_B_DQ17")
	)
	(segment
		(start 139.9794 -8.713978)
		(end 139.9794 -8.303514)
		(width 0.1778)
		(layer "B.Cu")
		(net "M_B_DQ17")
	)
	(segment
		(start 139.9794 -8.303514)
		(end 140.482066 -7.800848)
		(width 0.1778)
		(layer "B.Cu")
		(net "M_B_DQ17")
	)
	(segment
		(start 139.750038 -8.94334)
		(end 139.9794 -8.713978)
		(width 0.1778)
		(layer "B.Cu")
		(net "M_B_DQ17")
	)
	(segment
		(start 139.750038 -9.89076)
		(end 139.750038 -8.94334)
		(width 0.1778)
		(layer "B.Cu")
		(net "M_B_DQ17")
	)
	(segment
		(start 136.0424 -11.0744)
		(end 135.255 -11.0744)
		(width 0.1524)
		(layer "In4.Cu")
		(net "M_B_DQ17")
	)
	(segment
		(start 135.5598 -11.9888)
		(end 135.7122 -12.1412)
		(width 0.1524)
		(layer "In4.Cu")
		(net "M_B_DQ17")
	)
	(segment
		(start 134.3406 -12.6746)
		(end 134.493 -12.827)
		(width 0.1524)
		(layer "In4.Cu")
		(net "M_B_DQ17")
	)
	(segment
		(start 135.4074 -11.684)
		(end 135.5598 -11.8364)
		(width 0.1524)
		(layer "In4.Cu")
		(net "M_B_DQ17")
	)
	(segment
		(start 135.5598 -11.8364)
		(end 135.5598 -11.9888)
		(width 0.1524)
		(layer "In4.Cu")
		(net "M_B_DQ17")
	)
	(segment
		(start 134.493 -12.827)
		(end 134.7978 -12.827)
		(width 0.1524)
		(layer "In4.Cu")
		(net "M_B_DQ17")
	)
	(segment
		(start 135.255 -10.4902)
		(end 138.954256 -10.4902)
		(width 0.1524)
		(layer "In4.Cu")
		(net "M_B_DQ17")
	)
	(segment
		(start 136.1948 -11.9888)
		(end 136.1948 -11.2268)
		(width 0.1524)
		(layer "In4.Cu")
		(net "M_B_DQ17")
	)
	(segment
		(start 135.1026 -10.922)
		(end 135.1026 -10.6426)
		(width 0.1524)
		(layer "In4.Cu")
		(net "M_B_DQ17")
	)
	(segment
		(start 134.9502 -11.8364)
		(end 135.1026 -11.684)
		(width 0.1524)
		(layer "In4.Cu")
		(net "M_B_DQ17")
	)
	(segment
		(start 100.1014 -20.410932)
		(end 100.1014 -23.2156)
		(width 0.1016)
		(layer "In4.Cu")
		(net "M_B_DQ17")
	)
	(segment
		(start 103.875332 -16.637)
		(end 109.47019 -16.637)
		(width 0.1524)
		(layer "In4.Cu")
		(net "M_B_DQ17")
	)
	(segment
		(start 136.0424 -12.1412)
		(end 136.1948 -11.9888)
		(width 0.1524)
		(layer "In4.Cu")
		(net "M_B_DQ17")
	)
	(segment
		(start 135.1026 -10.6426)
		(end 135.255 -10.4902)
		(width 0.1524)
		(layer "In4.Cu")
		(net "M_B_DQ17")
	)
	(segment
		(start 131.8514 -11.9126)
		(end 134.1882 -11.9126)
		(width 0.1524)
		(layer "In4.Cu")
		(net "M_B_DQ17")
	)
	(segment
		(start 134.7978 -12.827)
		(end 134.9502 -12.6746)
		(width 0.1524)
		(layer "In4.Cu")
		(net "M_B_DQ17")
	)
	(segment
		(start 138.954256 -10.4902)
		(end 140.0302 -9.414256)
		(width 0.1524)
		(layer "In4.Cu")
		(net "M_B_DQ17")
	)
	(segment
		(start 131.5466 -12.6238)
		(end 131.699 -12.4714)
		(width 0.1524)
		(layer "In4.Cu")
		(net "M_B_DQ17")
	)
	(segment
		(start 100.1014 -20.410932)
		(end 103.875332 -16.637)
		(width 0.1524)
		(layer "In4.Cu")
		(net "M_B_DQ17")
	)
	(segment
		(start 109.47019 -16.637)
		(end 113.48339 -12.6238)
		(width 0.1524)
		(layer "In4.Cu")
		(net "M_B_DQ17")
	)
	(segment
		(start 134.3406 -12.065)
		(end 134.3406 -12.6746)
		(width 0.1524)
		(layer "In4.Cu")
		(net "M_B_DQ17")
	)
	(segment
		(start 134.1882 -11.9126)
		(end 134.3406 -12.065)
		(width 0.1524)
		(layer "In4.Cu")
		(net "M_B_DQ17")
	)
	(segment
		(start 131.699 -12.065)
		(end 131.8514 -11.9126)
		(width 0.1524)
		(layer "In4.Cu")
		(net "M_B_DQ17")
	)
	(segment
		(start 135.1026 -11.684)
		(end 135.4074 -11.684)
		(width 0.1524)
		(layer "In4.Cu")
		(net "M_B_DQ17")
	)
	(segment
		(start 136.1948 -11.2268)
		(end 136.0424 -11.0744)
		(width 0.1524)
		(layer "In4.Cu")
		(net "M_B_DQ17")
	)
	(segment
		(start 131.699 -12.4714)
		(end 131.699 -12.065)
		(width 0.1524)
		(layer "In4.Cu")
		(net "M_B_DQ17")
	)
	(segment
		(start 140.0302 -9.414256)
		(end 140.0302 -8.252714)
		(width 0.1524)
		(layer "In4.Cu")
		(net "M_B_DQ17")
	)
	(segment
		(start 135.255 -11.0744)
		(end 135.1026 -10.922)
		(width 0.1524)
		(layer "In4.Cu")
		(net "M_B_DQ17")
	)
	(segment
		(start 113.48339 -12.6238)
		(end 131.5466 -12.6238)
		(width 0.1524)
		(layer "In4.Cu")
		(net "M_B_DQ17")
	)
	(segment
		(start 135.7122 -12.1412)
		(end 136.0424 -12.1412)
		(width 0.1524)
		(layer "In4.Cu")
		(net "M_B_DQ17")
	)
	(segment
		(start 140.0302 -8.252714)
		(end 140.482066 -7.800848)
		(width 0.1524)
		(layer "In4.Cu")
		(net "M_B_DQ17")
	)
	(segment
		(start 134.9502 -12.6746)
		(end 134.9502 -11.8364)
		(width 0.1524)
		(layer "In4.Cu")
		(net "M_B_DQ17")
	)
	(segment
		(start 34.788348 -35.5219)
		(end 34.955988 -35.5219)
		(width 0.1143)
		(layer "F.Cu")
		(net "XDP_P60")
	)
	(segment
		(start 34.394648 -35.9156)
		(end 34.788348 -35.5219)
		(width 0.1143)
		(layer "F.Cu")
		(net "XDP_P60")
	)
	(segment
		(start 34.417 -38.1254)
		(end 34.417 -35.941)
		(width 0.1143)
		(layer "F.Cu")
		(net "XDP_P60")
	)
	(segment
		(start 35.365944 -35.111944)
		(end 35.365944 -34.6964)
		(width 0.1143)
		(layer "F.Cu")
		(net "XDP_P60")
	)
	(segment
		(start 34.394648 -35.918648)
		(end 34.394648 -35.9156)
		(width 0.1143)
		(layer "F.Cu")
		(net "XDP_P60")
	)
	(segment
		(start 34.955988 -35.5219)
		(end 35.365944 -35.111944)
		(width 0.1143)
		(layer "F.Cu")
		(net "XDP_P60")
	)
	(segment
		(start 34.417 -35.941)
		(end 34.394648 -35.918648)
		(width 0.1143)
		(layer "F.Cu")
		(net "XDP_P60")
	)
	(segment
		(start 35.365944 -34.6964)
		(end 35.506914 -34.55543)
		(width 0.1143)
		(layer "F.Cu")
		(net "XDP_P60")
	)
	(segment
		(start 35.506914 -34.55543)
		(end 36.37788 -34.55543)
		(width 0.1143)
		(layer "F.Cu")
		(net "XDP_P60")
	)
	(via
		(at 34.394648 -35.9156)
		(size 0.508)
		(drill 0.254)
		(layers "F.Cu" "B.Cu")
		(net "XDP_P60")
	)
	(via
		(at 20.2438 -17.145)
		(size 0.508)
		(drill 0.254)
		(layers "F.Cu" "B.Cu")
		(net "XDP_P60")
	)
	(via
		(at 19.177 -15.113)
		(size 0.7112)
		(drill 0.3556)
		(layers "F.Cu" "B.Cu")
		(net "XDP_P60")
	)
	(segment
		(start 19.177 -16.276574)
		(end 20.045426 -17.145)
		(width 0.1143)
		(layer "B.Cu")
		(net "XDP_P60")
	)
	(segment
		(start 19.177 -15.113)
		(end 19.177 -16.276574)
		(width 0.1143)
		(layer "B.Cu")
		(net "XDP_P60")
	)
	(segment
		(start 20.045426 -17.145)
		(end 20.2438 -17.145)
		(width 0.1143)
		(layer "B.Cu")
		(net "XDP_P60")
	)
	(segment
		(start 23.55977 -20.8788)
		(end 22.5425 -19.86153)
		(width 0.0889)
		(layer "In9.Cu")
		(net "XDP_P60")
	)
	(segment
		(start 29.518356 -32.824674)
		(end 28.20035 -31.506668)
		(width 0.0889)
		(layer "In9.Cu")
		(net "XDP_P60")
	)
	(segment
		(start 25.43683 -20.8788)
		(end 23.55977 -20.8788)
		(width 0.0889)
		(layer "In9.Cu")
		(net "XDP_P60")
	)
	(segment
		(start 28.20035 -31.506668)
		(end 28.20035 -23.64232)
		(width 0.0889)
		(layer "In9.Cu")
		(net "XDP_P60")
	)
	(segment
		(start 30.99308 -32.824674)
		(end 29.518356 -32.824674)
		(width 0.0889)
		(layer "In9.Cu")
		(net "XDP_P60")
	)
	(segment
		(start 28.20035 -23.64232)
		(end 25.43683 -20.8788)
		(width 0.0889)
		(layer "In9.Cu")
		(net "XDP_P60")
	)
	(segment
		(start 22.5425 -19.4437)
		(end 20.2438 -17.145)
		(width 0.0889)
		(layer "In9.Cu")
		(net "XDP_P60")
	)
	(segment
		(start 22.5425 -19.86153)
		(end 22.5425 -19.4437)
		(width 0.0889)
		(layer "In9.Cu")
		(net "XDP_P60")
	)
	(segment
		(start 34.084006 -35.9156)
		(end 30.99308 -32.824674)
		(width 0.0889)
		(layer "In9.Cu")
		(net "XDP_P60")
	)
	(segment
		(start 34.394648 -35.9156)
		(end 34.084006 -35.9156)
		(width 0.0889)
		(layer "In9.Cu")
		(net "XDP_P60")
	)
	(segment
		(start 192.449196 -32.975804)
		(end 192.786 -32.639)
		(width 0.2032)
		(layer "F.Cu")
		(net "VR_PVDDR_A_BOOT1")
	)
	(segment
		(start 191.656716 -32.975804)
		(end 192.449196 -32.975804)
		(width 0.2032)
		(layer "F.Cu")
		(net "VR_PVDDR_A_BOOT1")
	)
	(segment
		(start 194.691 -32.8168)
		(end 193.7512 -32.8168)
		(width 0.3048)
		(layer "F.Cu")
		(net "VR_PVDDR_A_BOOT1")
	)
	(segment
		(start 192.786 -32.639)
		(end 193.5734 -32.639)
		(width 0.3048)
		(layer "F.Cu")
		(net "VR_PVDDR_A_BOOT1")
	)
	(segment
		(start 193.5734 -32.639)
		(end 193.7512 -32.8168)
		(width 0.3048)
		(layer "F.Cu")
		(net "VR_PVDDR_A_BOOT1")
	)
	(via
		(at 193.7512 -32.8168)
		(size 0.7112)
		(drill 0.3556)
		(layers "F.Cu" "B.Cu")
		(net "VR_PVDDR_A_BOOT1")
	)
	(segment
		(start 102.367588 -48.730154)
		(end 102.039928 -48.402494)
		(width 0.1016)
		(layer "F.Cu")
		(net "M_A_CK_DP1")
	)
	(segment
		(start 102.367588 -48.791876)
		(end 102.367588 -48.730154)
		(width 0.1016)
		(layer "F.Cu")
		(net "M_A_CK_DP1")
	)
	(via
		(at 153.6954 -68.6054)
		(size 0.4318)
		(drill 0.2032)
		(layers "F.Cu" "B.Cu")
		(net "M_A_CK_DP1")
	)
	(via
		(at 102.367588 -48.791876)
		(size 0.4318)
		(drill 0.2032)
		(layers "F.Cu" "B.Cu")
		(net "M_A_CK_DP1")
	)
	(segment
		(start 154.373834 -69.283834)
		(end 153.6954 -68.6054)
		(width 0.2159)
		(layer "B.Cu")
		(net "M_A_CK_DP1")
	)
	(segment
		(start 154.373834 -69.9516)
		(end 154.373834 -69.283834)
		(width 0.2159)
		(layer "B.Cu")
		(net "M_A_CK_DP1")
	)
	(segment
		(start 154.450034 -70.0278)
		(end 154.373834 -69.9516)
		(width 0.2159)
		(layer "B.Cu")
		(net "M_A_CK_DP1")
	)
	(segment
		(start 154.450034 -70.79996)
		(end 154.450034 -70.0278)
		(width 0.2159)
		(layer "B.Cu")
		(net "M_A_CK_DP1")
	)
	(segment
		(start 153.4795 -68.3895)
		(end 153.4795 -67.613784)
		(width 0.1905)
		(layer "In7.Cu")
		(net "M_A_CK_DP1")
	)
	(segment
		(start 150.332186 -57.10555)
		(end 149.763226 -56.53659)
		(width 0.1905)
		(layer "In7.Cu")
		(net "M_A_CK_DP1")
	)
	(segment
		(start 142.766542 -55.2704)
		(end 142.614142 -55.4228)
		(width 0.1905)
		(layer "In7.Cu")
		(net "M_A_CK_DP1")
	)
	(segment
		(start 152.129236 -59.643264)
		(end 152.129236 -59.0804)
		(width 0.1905)
		(layer "In7.Cu")
		(net "M_A_CK_DP1")
	)
	(segment
		(start 152.853644 -65.731644)
		(end 152.853644 -65.723262)
		(width 0.1905)
		(layer "In7.Cu")
		(net "M_A_CK_DP1")
	)
	(segment
		(start 150.997412 -58.51144)
		(end 149.961092 -59.54776)
		(width 0.1905)
		(layer "In7.Cu")
		(net "M_A_CK_DP1")
	)
	(segment
		(start 106.939588 -54.27599)
		(end 107.112816 -54.27599)
		(width 0.1016)
		(layer "In7.Cu")
		(net "M_A_CK_DP1")
	)
	(segment
		(start 142.182342 -55.4228)
		(end 142.004542 -55.245)
		(width 0.1905)
		(layer "In7.Cu")
		(net "M_A_CK_DP1")
	)
	(segment
		(start 149.206966 -59.062366)
		(end 149.206966 -58.793634)
		(width 0.1905)
		(layer "In7.Cu")
		(net "M_A_CK_DP1")
	)
	(segment
		(start 151.560276 -58.51144)
		(end 150.997412 -58.51144)
		(width 0.1905)
		(layer "In7.Cu")
		(net "M_A_CK_DP1")
	)
	(segment
		(start 153.6954 -68.6054)
		(end 153.4795 -68.3895)
		(width 0.1905)
		(layer "In7.Cu")
		(net "M_A_CK_DP1")
	)
	(segment
		(start 144.11325 -53.96865)
		(end 143.202406 -53.96865)
		(width 0.1905)
		(layer "In7.Cu")
		(net "M_A_CK_DP1")
	)
	(segment
		(start 153.787348 -66.665348)
		(end 152.853644 -65.731644)
		(width 0.1905)
		(layer "In7.Cu")
		(net "M_A_CK_DP1")
	)
	(segment
		(start 151.092916 -60.948316)
		(end 151.092916 -60.679584)
		(width 0.1905)
		(layer "In7.Cu")
		(net "M_A_CK_DP1")
	)
	(segment
		(start 149.763226 -56.53659)
		(end 149.200362 -56.53659)
		(width 0.1905)
		(layer "In7.Cu")
		(net "M_A_CK_DP1")
	)
	(segment
		(start 149.69236 -59.54776)
		(end 149.206966 -59.062366)
		(width 0.1905)
		(layer "In7.Cu")
		(net "M_A_CK_DP1")
	)
	(segment
		(start 152.335992 -65.213992)
		(end 151.9555 -64.8335)
		(width 0.1905)
		(layer "In7.Cu")
		(net "M_A_CK_DP1")
	)
	(segment
		(start 147.80641 -57.66181)
		(end 144.11325 -53.96865)
		(width 0.1905)
		(layer "In7.Cu")
		(net "M_A_CK_DP1")
	)
	(segment
		(start 153.787348 -67.305936)
		(end 153.787348 -66.665348)
		(width 0.1905)
		(layer "In7.Cu")
		(net "M_A_CK_DP1")
	)
	(segment
		(start 107.967526 -55.1307)
		(end 107.116118 -54.279292)
		(width 0.1905)
		(layer "In7.Cu")
		(net "M_A_CK_DP1")
	)
	(segment
		(start 153.4795 -67.613784)
		(end 153.787348 -67.305936)
		(width 0.1905)
		(layer "In7.Cu")
		(net "M_A_CK_DP1")
	)
	(segment
		(start 120.3452 -53.58765)
		(end 118.80215 -55.1307)
		(width 0.1905)
		(layer "In7.Cu")
		(net "M_A_CK_DP1")
	)
	(segment
		(start 102.6668 -51.2572)
		(end 104.971596 -53.561996)
		(width 0.1016)
		(layer "In7.Cu")
		(net "M_A_CK_DP1")
	)
	(segment
		(start 129.085086 -53.58765)
		(end 120.3452 -53.58765)
		(width 0.1905)
		(layer "In7.Cu")
		(net "M_A_CK_DP1")
	)
	(segment
		(start 107.112816 -54.27599)
		(end 107.116118 -54.279292)
		(width 0.1016)
		(layer "In7.Cu")
		(net "M_A_CK_DP1")
	)
	(segment
		(start 102.75824 -49.35982)
		(end 102.75824 -49.7205)
		(width 0.1016)
		(layer "In7.Cu")
		(net "M_A_CK_DP1")
	)
	(segment
		(start 106.225594 -53.561996)
		(end 106.939588 -54.27599)
		(width 0.1016)
		(layer "In7.Cu")
		(net "M_A_CK_DP1")
	)
	(segment
		(start 142.614142 -55.4228)
		(end 142.182342 -55.4228)
		(width 0.1905)
		(layer "In7.Cu")
		(net "M_A_CK_DP1")
	)
	(segment
		(start 149.961092 -59.54776)
		(end 149.69236 -59.54776)
		(width 0.1905)
		(layer "In7.Cu")
		(net "M_A_CK_DP1")
	)
	(segment
		(start 142.004542 -55.245)
		(end 142.004542 -54.404514)
		(width 0.1905)
		(layer "In7.Cu")
		(net "M_A_CK_DP1")
	)
	(segment
		(start 104.971596 -53.561996)
		(end 106.225594 -53.561996)
		(width 0.1016)
		(layer "In7.Cu")
		(net "M_A_CK_DP1")
	)
	(segment
		(start 102.367588 -48.791876)
		(end 102.367588 -48.969168)
		(width 0.1016)
		(layer "In7.Cu")
		(net "M_A_CK_DP1")
	)
	(segment
		(start 151.092916 -60.679584)
		(end 152.129236 -59.643264)
		(width 0.1905)
		(layer "In7.Cu")
		(net "M_A_CK_DP1")
	)
	(segment
		(start 142.766542 -54.404514)
		(end 142.766542 -55.2704)
		(width 0.1905)
		(layer "In7.Cu")
		(net "M_A_CK_DP1")
	)
	(segment
		(start 152.344374 -65.213992)
		(end 152.335992 -65.213992)
		(width 0.1905)
		(layer "In7.Cu")
		(net "M_A_CK_DP1")
	)
	(segment
		(start 152.129236 -59.0804)
		(end 151.560276 -58.51144)
		(width 0.1905)
		(layer "In7.Cu")
		(net "M_A_CK_DP1")
	)
	(segment
		(start 150.332186 -57.668414)
		(end 150.332186 -57.10555)
		(width 0.1905)
		(layer "In7.Cu")
		(net "M_A_CK_DP1")
	)
	(segment
		(start 102.75824 -49.7205)
		(end 102.6668 -49.81194)
		(width 0.1016)
		(layer "In7.Cu")
		(net "M_A_CK_DP1")
	)
	(segment
		(start 102.367588 -48.969168)
		(end 102.75824 -49.35982)
		(width 0.1016)
		(layer "In7.Cu")
		(net "M_A_CK_DP1")
	)
	(segment
		(start 149.200362 -56.53659)
		(end 148.075142 -57.66181)
		(width 0.1905)
		(layer "In7.Cu")
		(net "M_A_CK_DP1")
	)
	(segment
		(start 142.004542 -54.404514)
		(end 141.568678 -53.96865)
		(width 0.1905)
		(layer "In7.Cu")
		(net "M_A_CK_DP1")
	)
	(segment
		(start 141.568678 -53.96865)
		(end 129.466086 -53.96865)
		(width 0.1905)
		(layer "In7.Cu")
		(net "M_A_CK_DP1")
	)
	(segment
		(start 148.075142 -57.66181)
		(end 147.80641 -57.66181)
		(width 0.1905)
		(layer "In7.Cu")
		(net "M_A_CK_DP1")
	)
	(segment
		(start 149.206966 -58.793634)
		(end 150.332186 -57.668414)
		(width 0.1905)
		(layer "In7.Cu")
		(net "M_A_CK_DP1")
	)
	(segment
		(start 118.80215 -55.1307)
		(end 107.967526 -55.1307)
		(width 0.1905)
		(layer "In7.Cu")
		(net "M_A_CK_DP1")
	)
	(segment
		(start 129.466086 -53.96865)
		(end 129.085086 -53.58765)
		(width 0.1905)
		(layer "In7.Cu")
		(net "M_A_CK_DP1")
	)
	(segment
		(start 151.9555 -64.8335)
		(end 151.9555 -61.8109)
		(width 0.1905)
		(layer "In7.Cu")
		(net "M_A_CK_DP1")
	)
	(segment
		(start 151.9555 -61.8109)
		(end 151.092916 -60.948316)
		(width 0.1905)
		(layer "In7.Cu")
		(net "M_A_CK_DP1")
	)
	(segment
		(start 143.202406 -53.96865)
		(end 142.766542 -54.404514)
		(width 0.1905)
		(layer "In7.Cu")
		(net "M_A_CK_DP1")
	)
	(segment
		(start 102.6668 -49.81194)
		(end 102.6668 -51.2572)
		(width 0.1016)
		(layer "In7.Cu")
		(net "M_A_CK_DP1")
	)
	(segment
		(start 152.853644 -65.723262)
		(end 152.344374 -65.213992)
		(width 0.1905)
		(layer "In7.Cu")
		(net "M_A_CK_DP1")
	)
	(segment
		(start 150.0632 -8.561578)
		(end 149.8854 -8.383778)
		(width 0.1778)
		(layer "F.Cu")
		(net "M_B_ECC0")
	)
	(segment
		(start 104.2416 -26.001726)
		(end 104.541828 -26.301954)
		(width 0.1016)
		(layer "F.Cu")
		(net "M_B_ECC0")
	)
	(segment
		(start 104.541828 -26.995628)
		(end 104.958388 -27.412188)
		(width 0.1016)
		(layer "F.Cu")
		(net "M_B_ECC0")
	)
	(segment
		(start 104.541828 -26.301954)
		(end 104.541828 -26.995628)
		(width 0.1016)
		(layer "F.Cu")
		(net "M_B_ECC0")
	)
	(segment
		(start 104.394 -23.3934)
		(end 104.2416 -23.5458)
		(width 0.1016)
		(layer "F.Cu")
		(net "M_B_ECC0")
	)
	(segment
		(start 104.2416 -23.5458)
		(end 104.2416 -26.001726)
		(width 0.1016)
		(layer "F.Cu")
		(net "M_B_ECC0")
	)
	(segment
		(start 149.649942 -9.897364)
		(end 149.649942 -9.203436)
		(width 0.1778)
		(layer "F.Cu")
		(net "M_B_ECC0")
	)
	(segment
		(start 150.0632 -8.790178)
		(end 150.0632 -8.561578)
		(width 0.1778)
		(layer "F.Cu")
		(net "M_B_ECC0")
	)
	(segment
		(start 104.958388 -27.412188)
		(end 104.958388 -27.658314)
		(width 0.1016)
		(layer "F.Cu")
		(net "M_B_ECC0")
	)
	(segment
		(start 149.649942 -9.203436)
		(end 150.0632 -8.790178)
		(width 0.1778)
		(layer "F.Cu")
		(net "M_B_ECC0")
	)
	(segment
		(start 149.8854 -8.383778)
		(end 149.6822 -8.383778)
		(width 0.1778)
		(layer "F.Cu")
		(net "M_B_ECC0")
	)
	(via
		(at 149.6822 -8.383778)
		(size 0.4318)
		(drill 0.2032)
		(layers "F.Cu" "B.Cu")
		(net "M_B_ECC0")
	)
	(via
		(at 104.394 -23.3934)
		(size 0.4318)
		(drill 0.2032)
		(layers "F.Cu" "B.Cu")
		(net "M_B_ECC0")
	)
	(segment
		(start 148.75002 -9.209278)
		(end 149.57552 -8.383778)
		(width 0.1778)
		(layer "B.Cu")
		(net "M_B_ECC0")
	)
	(segment
		(start 149.57552 -8.383778)
		(end 149.6822 -8.383778)
		(width 0.1778)
		(layer "B.Cu")
		(net "M_B_ECC0")
	)
	(segment
		(start 148.75002 -9.89076)
		(end 148.75002 -9.209278)
		(width 0.1778)
		(layer "B.Cu")
		(net "M_B_ECC0")
	)
	(segment
		(start 150.1648 -12.0904)
		(end 149.8854 -12.0904)
		(width 0.1524)
		(layer "In2.Cu")
		(net "M_B_ECC0")
	)
	(segment
		(start 149.8854 -12.0904)
		(end 149.733 -11.938)
		(width 0.1524)
		(layer "In2.Cu")
		(net "M_B_ECC0")
	)
	(segment
		(start 150.1648 -10.8712)
		(end 149.8854 -10.8712)
		(width 0.1524)
		(layer "In2.Cu")
		(net "M_B_ECC0")
	)
	(segment
		(start 119.627396 -19.811746)
		(end 119.779796 -19.659346)
		(width 0.1524)
		(layer "In2.Cu")
		(net "M_B_ECC0")
	)
	(segment
		(start 122.2756 -19.177)
		(end 122.428 -19.0246)
		(width 0.1524)
		(layer "In2.Cu")
		(net "M_B_ECC0")
	)
	(segment
		(start 122.1232 -19.659346)
		(end 122.2756 -19.506946)
		(width 0.1524)
		(layer "In2.Cu")
		(net "M_B_ECC0")
	)
	(segment
		(start 118.865396 -19.659346)
		(end 119.017796 -19.811746)
		(width 0.1524)
		(layer "In2.Cu")
		(net "M_B_ECC0")
	)
	(segment
		(start 150.3172 -12.5476)
		(end 150.3172 -12.2428)
		(width 0.1524)
		(layer "In2.Cu")
		(net "M_B_ECC0")
	)
	(segment
		(start 122.9868 -19.177)
		(end 122.9868 -19.3548)
		(width 0.1524)
		(layer "In2.Cu")
		(net "M_B_ECC0")
	)
	(segment
		(start 104.3686 -21.0312)
		(end 107.0864 -21.0312)
		(width 0.1016)
		(layer "In2.Cu")
		(net "M_B_ECC0")
	)
	(segment
		(start 123.58243 -19.5072)
		(end 123.7488 -19.34083)
		(width 0.1524)
		(layer "In2.Cu")
		(net "M_B_ECC0")
	)
	(segment
		(start 149.8854 -10.8712)
		(end 149.733 -10.7188)
		(width 0.1524)
		(layer "In2.Cu")
		(net "M_B_ECC0")
	)
	(segment
		(start 150.3172 -11.0236)
		(end 150.1648 -10.8712)
		(width 0.1524)
		(layer "In2.Cu")
		(net "M_B_ECC0")
	)
	(segment
		(start 123.9012 -18.2626)
		(end 149.225 -18.2626)
		(width 0.1524)
		(layer "In2.Cu")
		(net "M_B_ECC0")
	)
	(segment
		(start 118.408196 -19.811746)
		(end 118.560596 -19.659346)
		(width 0.1524)
		(layer "In2.Cu")
		(net "M_B_ECC0")
	)
	(segment
		(start 149.225 -18.2626)
		(end 149.733 -17.7546)
		(width 0.1524)
		(layer "In2.Cu")
		(net "M_B_ECC0")
	)
	(segment
		(start 122.2756 -19.506946)
		(end 122.2756 -19.177)
		(width 0.1524)
		(layer "In2.Cu")
		(net "M_B_ECC0")
	)
	(segment
		(start 119.017796 -19.811746)
		(end 119.017796 -20.2692)
		(width 0.1524)
		(layer "In2.Cu")
		(net "M_B_ECC0")
	)
	(segment
		(start 119.474996 -20.4216)
		(end 119.627396 -20.2692)
		(width 0.1524)
		(layer "In2.Cu")
		(net "M_B_ECC0")
	)
	(segment
		(start 150.1648 -12.7)
		(end 150.3172 -12.5476)
		(width 0.1524)
		(layer "In2.Cu")
		(net "M_B_ECC0")
	)
	(segment
		(start 149.733 -12.8524)
		(end 149.8854 -12.7)
		(width 0.1524)
		(layer "In2.Cu")
		(net "M_B_ECC0")
	)
	(segment
		(start 150.1648 -11.4808)
		(end 150.3172 -11.3284)
		(width 0.1524)
		(layer "In2.Cu")
		(net "M_B_ECC0")
	)
	(segment
		(start 149.6822 -8.543798)
		(end 149.6822 -8.383778)
		(width 0.1524)
		(layer "In2.Cu")
		(net "M_B_ECC0")
	)
	(segment
		(start 117.950996 -20.4216)
		(end 118.255796 -20.4216)
		(width 0.1524)
		(layer "In2.Cu")
		(net "M_B_ECC0")
	)
	(segment
		(start 119.627396 -20.2692)
		(end 119.627396 -19.811746)
		(width 0.1524)
		(layer "In2.Cu")
		(net "M_B_ECC0")
	)
	(segment
		(start 122.8344 -19.0246)
		(end 122.9868 -19.177)
		(width 0.1524)
		(layer "In2.Cu")
		(net "M_B_ECC0")
	)
	(segment
		(start 150.3172 -11.3284)
		(end 150.3172 -11.0236)
		(width 0.1524)
		(layer "In2.Cu")
		(net "M_B_ECC0")
	)
	(segment
		(start 149.733 -11.938)
		(end 149.733 -11.6332)
		(width 0.1524)
		(layer "In2.Cu")
		(net "M_B_ECC0")
	)
	(segment
		(start 103.9368 -21.463)
		(end 104.3686 -21.0312)
		(width 0.1016)
		(layer "In2.Cu")
		(net "M_B_ECC0")
	)
	(segment
		(start 149.733 -11.6332)
		(end 149.8854 -11.4808)
		(width 0.1524)
		(layer "In2.Cu")
		(net "M_B_ECC0")
	)
	(segment
		(start 122.9868 -19.3548)
		(end 123.1392 -19.5072)
		(width 0.1524)
		(layer "In2.Cu")
		(net "M_B_ECC0")
	)
	(segment
		(start 123.1392 -19.5072)
		(end 123.58243 -19.5072)
		(width 0.1524)
		(layer "In2.Cu")
		(net "M_B_ECC0")
	)
	(segment
		(start 119.779796 -19.659346)
		(end 122.1232 -19.659346)
		(width 0.1524)
		(layer "In2.Cu")
		(net "M_B_ECC0")
	)
	(segment
		(start 117.798596 -19.811746)
		(end 117.798596 -20.2692)
		(width 0.1524)
		(layer "In2.Cu")
		(net "M_B_ECC0")
	)
	(segment
		(start 118.408196 -20.2692)
		(end 118.408196 -19.811746)
		(width 0.1524)
		(layer "In2.Cu")
		(net "M_B_ECC0")
	)
	(segment
		(start 107.0864 -21.0312)
		(end 109.5248 -21.0312)
		(width 0.1524)
		(layer "In2.Cu")
		(net "M_B_ECC0")
	)
	(segment
		(start 149.8854 -11.4808)
		(end 150.1648 -11.4808)
		(width 0.1524)
		(layer "In2.Cu")
		(net "M_B_ECC0")
	)
	(segment
		(start 118.560596 -19.659346)
		(end 118.865396 -19.659346)
		(width 0.1524)
		(layer "In2.Cu")
		(net "M_B_ECC0")
	)
	(segment
		(start 109.5248 -21.0312)
		(end 110.896654 -19.659346)
		(width 0.1524)
		(layer "In2.Cu")
		(net "M_B_ECC0")
	)
	(segment
		(start 123.7488 -18.415)
		(end 123.9012 -18.2626)
		(width 0.1524)
		(layer "In2.Cu")
		(net "M_B_ECC0")
	)
	(segment
		(start 103.9368 -22.9362)
		(end 103.9368 -21.463)
		(width 0.1016)
		(layer "In2.Cu")
		(net "M_B_ECC0")
	)
	(segment
		(start 149.733 -17.7546)
		(end 149.733 -12.8524)
		(width 0.1524)
		(layer "In2.Cu")
		(net "M_B_ECC0")
	)
	(segment
		(start 150.3172 -12.2428)
		(end 150.1648 -12.0904)
		(width 0.1524)
		(layer "In2.Cu")
		(net "M_B_ECC0")
	)
	(segment
		(start 119.017796 -20.2692)
		(end 119.170196 -20.4216)
		(width 0.1524)
		(layer "In2.Cu")
		(net "M_B_ECC0")
	)
	(segment
		(start 117.798596 -20.2692)
		(end 117.950996 -20.4216)
		(width 0.1524)
		(layer "In2.Cu")
		(net "M_B_ECC0")
	)
	(segment
		(start 117.646196 -19.659346)
		(end 117.798596 -19.811746)
		(width 0.1524)
		(layer "In2.Cu")
		(net "M_B_ECC0")
	)
	(segment
		(start 149.733 -8.594598)
		(end 149.6822 -8.543798)
		(width 0.1524)
		(layer "In2.Cu")
		(net "M_B_ECC0")
	)
	(segment
		(start 118.255796 -20.4216)
		(end 118.408196 -20.2692)
		(width 0.1524)
		(layer "In2.Cu")
		(net "M_B_ECC0")
	)
	(segment
		(start 149.733 -10.7188)
		(end 149.733 -8.594598)
		(width 0.1524)
		(layer "In2.Cu")
		(net "M_B_ECC0")
	)
	(segment
		(start 104.394 -23.3934)
		(end 103.9368 -22.9362)
		(width 0.1016)
		(layer "In2.Cu")
		(net "M_B_ECC0")
	)
	(segment
		(start 123.7488 -19.34083)
		(end 123.7488 -18.415)
		(width 0.1524)
		(layer "In2.Cu")
		(net "M_B_ECC0")
	)
	(segment
		(start 122.428 -19.0246)
		(end 122.8344 -19.0246)
		(width 0.1524)
		(layer "In2.Cu")
		(net "M_B_ECC0")
	)
	(segment
		(start 110.896654 -19.659346)
		(end 117.646196 -19.659346)
		(width 0.1524)
		(layer "In2.Cu")
		(net "M_B_ECC0")
	)
	(segment
		(start 149.8854 -12.7)
		(end 150.1648 -12.7)
		(width 0.1524)
		(layer "In2.Cu")
		(net "M_B_ECC0")
	)
	(segment
		(start 119.170196 -20.4216)
		(end 119.474996 -20.4216)
		(width 0.1524)
		(layer "In2.Cu")
		(net "M_B_ECC0")
	)
	(segment
		(start 86.388448 -29.997654)
		(end 86.388448 -29.997146)
		(width 0.1143)
		(layer "F.Cu")
		(net "SATA2_OBS_P")
	)
	(segment
		(start 86.388448 -29.997146)
		(end 86.047072 -29.65577)
		(width 0.1143)
		(layer "F.Cu")
		(net "SATA2_OBS_P")
	)
	(via
		(at 83.947 -27.686)
		(size 0.7112)
		(drill 0.3556)
		(layers "F.Cu" "B.Cu")
		(net "SATA2_OBS_P")
	)
	(via
		(at 86.047072 -29.65577)
		(size 0.4318)
		(drill 0.2032)
		(layers "F.Cu" "B.Cu")
		(net "SATA2_OBS_P")
	)
	(segment
		(start 86.264242 -29.4386)
		(end 86.047072 -29.65577)
		(width 0.1143)
		(layer "B.Cu")
		(net "SATA2_OBS_P")
	)
	(segment
		(start 83.3374 -28.281884)
		(end 83.3374 -28.4734)
		(width 0.1143)
		(layer "B.Cu")
		(net "SATA2_OBS_P")
	)
	(segment
		(start 83.947 -27.686)
		(end 83.933284 -27.686)
		(width 0.1143)
		(layer "B.Cu")
		(net "SATA2_OBS_P")
	)
	(segment
		(start 86.047072 -29.65577)
		(end 85.91677 -29.65577)
		(width 0.1143)
		(layer "B.Cu")
		(net "SATA2_OBS_P")
	)
	(segment
		(start 87.122 -29.4386)
		(end 86.264242 -29.4386)
		(width 0.1143)
		(layer "B.Cu")
		(net "SATA2_OBS_P")
	)
	(segment
		(start 85.91677 -29.65577)
		(end 83.947 -27.686)
		(width 0.1143)
		(layer "B.Cu")
		(net "SATA2_OBS_P")
	)
	(segment
		(start 83.933284 -27.686)
		(end 83.3374 -28.281884)
		(width 0.1143)
		(layer "B.Cu")
		(net "SATA2_OBS_P")
	)
	(segment
		(start 34.92119 -28.26385)
		(end 34.73577 -28.26385)
		(width 0.1143)
		(layer "F.Cu")
		(net "XDP_DFX_PORT15")
	)
	(segment
		(start 83.267296 -42.702226)
		(end 83.346036 -42.702226)
		(width 0.1143)
		(layer "F.Cu")
		(net "XDP_DFX_PORT15")
	)
	(segment
		(start 35.21202 -28.55468)
		(end 34.92119 -28.26385)
		(width 0.1143)
		(layer "F.Cu")
		(net "XDP_DFX_PORT15")
	)
	(segment
		(start 34.16935 -27.69743)
		(end 34.16935 -25.443688)
		(width 0.1143)
		(layer "F.Cu")
		(net "XDP_DFX_PORT15")
	)
	(segment
		(start 83.346036 -42.702226)
		(end 83.687412 -43.043602)
		(width 0.1143)
		(layer "F.Cu")
		(net "XDP_DFX_PORT15")
	)
	(segment
		(start 31.24073 -21.23567)
		(end 31.24073 -20.117308)
		(width 0.1143)
		(layer "F.Cu")
		(net "XDP_DFX_PORT15")
	)
	(segment
		(start 31.24073 -20.117308)
		(end 30.80893 -19.685508)
		(width 0.1143)
		(layer "F.Cu")
		(net "XDP_DFX_PORT15")
	)
	(segment
		(start 36.37788 -28.55468)
		(end 35.21202 -28.55468)
		(width 0.1143)
		(layer "F.Cu")
		(net "XDP_DFX_PORT15")
	)
	(segment
		(start 34.16935 -25.443688)
		(end 31.14675 -22.421088)
		(width 0.1143)
		(layer "F.Cu")
		(net "XDP_DFX_PORT15")
	)
	(segment
		(start 83.266788 -42.702734)
		(end 83.267296 -42.702226)
		(width 0.1143)
		(layer "F.Cu")
		(net "XDP_DFX_PORT15")
	)
	(segment
		(start 83.687412 -43.043602)
		(end 83.678268 -43.043602)
		(width 0.1143)
		(layer "F.Cu")
		(net "XDP_DFX_PORT15")
	)
	(segment
		(start 34.73577 -28.26385)
		(end 34.16935 -27.69743)
		(width 0.1143)
		(layer "F.Cu")
		(net "XDP_DFX_PORT15")
	)
	(segment
		(start 31.14675 -21.32965)
		(end 31.24073 -21.23567)
		(width 0.1143)
		(layer "F.Cu")
		(net "XDP_DFX_PORT15")
	)
	(segment
		(start 31.14675 -22.421088)
		(end 31.14675 -21.32965)
		(width 0.1143)
		(layer "F.Cu")
		(net "XDP_DFX_PORT15")
	)
	(via
		(at 30.46476 -18.993866)
		(size 0.7112)
		(drill 0.3556)
		(layers "F.Cu" "B.Cu")
		(net "XDP_DFX_PORT15")
	)
	(via
		(at 83.678268 -43.043602)
		(size 0.4318)
		(drill 0.2032)
		(layers "F.Cu" "B.Cu")
		(net "XDP_DFX_PORT15")
	)
	(via
		(at 30.80893 -19.685508)
		(size 0.508)
		(drill 0.254)
		(layers "F.Cu" "B.Cu")
		(net "XDP_DFX_PORT15")
	)
	(segment
		(start 30.80893 -19.685508)
		(end 30.80893 -19.338036)
		(width 0.1143)
		(layer "B.Cu")
		(net "XDP_DFX_PORT15")
	)
	(segment
		(start 30.80893 -19.338036)
		(end 30.46476 -18.993866)
		(width 0.1143)
		(layer "B.Cu")
		(net "XDP_DFX_PORT15")
	)
	(segment
		(start 74.3458 -34.879788)
		(end 74.3458 -35.242754)
		(width 0.0889)
		(layer "In7.Cu")
		(net "XDP_DFX_PORT15")
	)
	(segment
		(start 83.678268 -43.019218)
		(end 83.678268 -43.043602)
		(width 0.0889)
		(layer "In7.Cu")
		(net "XDP_DFX_PORT15")
	)
	(segment
		(start 48.663606 -27.94)
		(end 52.460906 -31.7373)
		(width 0.0889)
		(layer "In7.Cu")
		(net "XDP_DFX_PORT15")
	)
	(segment
		(start 64.760856 -31.7373)
		(end 66.742056 -33.7185)
		(width 0.0889)
		(layer "In7.Cu")
		(net "XDP_DFX_PORT15")
	)
	(segment
		(start 33.087818 -18.242788)
		(end 40.917876 -18.242788)
		(width 0.0889)
		(layer "In7.Cu")
		(net "XDP_DFX_PORT15")
	)
	(segment
		(start 82.676238 -42.475404)
		(end 83.134454 -42.475404)
		(width 0.0889)
		(layer "In7.Cu")
		(net "XDP_DFX_PORT15")
	)
	(segment
		(start 75.110594 -36.318444)
		(end 77.049122 -38.256972)
		(width 0.0889)
		(layer "In7.Cu")
		(net "XDP_DFX_PORT15")
	)
	(segment
		(start 46.610778 -24.578056)
		(end 46.610778 -25.195022)
		(width 0.0889)
		(layer "In7.Cu")
		(net "XDP_DFX_PORT15")
	)
	(segment
		(start 82.528156 -42.623486)
		(end 82.676238 -42.475404)
		(width 0.0889)
		(layer "In7.Cu")
		(net "XDP_DFX_PORT15")
	)
	(segment
		(start 30.80893 -19.685508)
		(end 31.645098 -19.685508)
		(width 0.0889)
		(layer "In7.Cu")
		(net "XDP_DFX_PORT15")
	)
	(segment
		(start 77.049122 -38.256972)
		(end 77.049122 -38.63721)
		(width 0.0889)
		(layer "In7.Cu")
		(net "XDP_DFX_PORT15")
	)
	(segment
		(start 46.0756 -23.400512)
		(end 46.0756 -24.042878)
		(width 0.0889)
		(layer "In7.Cu")
		(net "XDP_DFX_PORT15")
	)
	(segment
		(start 46.215554 -25.590246)
		(end 46.215554 -27.200606)
		(width 0.0889)
		(layer "In7.Cu")
		(net "XDP_DFX_PORT15")
	)
	(segment
		(start 66.742056 -33.7185)
		(end 73.184512 -33.7185)
		(width 0.0889)
		(layer "In7.Cu")
		(net "XDP_DFX_PORT15")
	)
	(segment
		(start 46.215554 -27.200606)
		(end 46.954948 -27.94)
		(width 0.0889)
		(layer "In7.Cu")
		(net "XDP_DFX_PORT15")
	)
	(segment
		(start 77.844396 -39.432484)
		(end 78.682088 -39.432484)
		(width 0.0889)
		(layer "In7.Cu")
		(net "XDP_DFX_PORT15")
	)
	(segment
		(start 74.3458 -35.242754)
		(end 75.110594 -36.007548)
		(width 0.0889)
		(layer "In7.Cu")
		(net "XDP_DFX_PORT15")
	)
	(segment
		(start 46.0756 -24.042878)
		(end 46.610778 -24.578056)
		(width 0.0889)
		(layer "In7.Cu")
		(net "XDP_DFX_PORT15")
	)
	(segment
		(start 75.110594 -36.007548)
		(end 75.110594 -36.318444)
		(width 0.0889)
		(layer "In7.Cu")
		(net "XDP_DFX_PORT15")
	)
	(segment
		(start 77.049122 -38.63721)
		(end 77.844396 -39.432484)
		(width 0.0889)
		(layer "In7.Cu")
		(net "XDP_DFX_PORT15")
	)
	(segment
		(start 31.645098 -19.685508)
		(end 33.087818 -18.242788)
		(width 0.0889)
		(layer "In7.Cu")
		(net "XDP_DFX_PORT15")
	)
	(segment
		(start 46.610778 -25.195022)
		(end 46.215554 -25.590246)
		(width 0.0889)
		(layer "In7.Cu")
		(net "XDP_DFX_PORT15")
	)
	(segment
		(start 46.954948 -27.94)
		(end 48.663606 -27.94)
		(width 0.0889)
		(layer "In7.Cu")
		(net "XDP_DFX_PORT15")
	)
	(segment
		(start 83.134454 -42.475404)
		(end 83.678268 -43.019218)
		(width 0.0889)
		(layer "In7.Cu")
		(net "XDP_DFX_PORT15")
	)
	(segment
		(start 40.917876 -18.242788)
		(end 46.0756 -23.400512)
		(width 0.0889)
		(layer "In7.Cu")
		(net "XDP_DFX_PORT15")
	)
	(segment
		(start 81.87309 -42.623486)
		(end 82.528156 -42.623486)
		(width 0.0889)
		(layer "In7.Cu")
		(net "XDP_DFX_PORT15")
	)
	(segment
		(start 52.460906 -31.7373)
		(end 64.760856 -31.7373)
		(width 0.0889)
		(layer "In7.Cu")
		(net "XDP_DFX_PORT15")
	)
	(segment
		(start 73.184512 -33.7185)
		(end 74.3458 -34.879788)
		(width 0.0889)
		(layer "In7.Cu")
		(net "XDP_DFX_PORT15")
	)
	(segment
		(start 78.682088 -39.432484)
		(end 81.87309 -42.623486)
		(width 0.0889)
		(layer "In7.Cu")
		(net "XDP_DFX_PORT15")
	)
	(segment
		(start 196.6214 -33.782)
		(end 195.5292 -33.782)
		(width 0.508)
		(layer "F.Cu")
		(net "VR_PVDDR_A_GH1")
	)
	(segment
		(start 191.656716 -33.375854)
		(end 192.557146 -33.375854)
		(width 0.2032)
		(layer "F.Cu")
		(net "VR_PVDDR_A_GH1")
	)
	(segment
		(start 192.557146 -33.375854)
		(end 192.659 -33.274)
		(width 0.2032)
		(layer "F.Cu")
		(net "VR_PVDDR_A_GH1")
	)
	(segment
		(start 192.659 -33.274)
		(end 192.8876 -33.274)
		(width 0.2032)
		(layer "F.Cu")
		(net "VR_PVDDR_A_GH1")
	)
	(via
		(at 192.8876 -33.274)
		(size 0.508)
		(drill 0.254)
		(layers "F.Cu" "B.Cu")
		(net "VR_PVDDR_A_GH1")
	)
	(via
		(at 195.5292 -33.782)
		(size 0.508)
		(drill 0.254)
		(layers "F.Cu" "B.Cu")
		(net "VR_PVDDR_A_GH1")
	)
	(via
		(at 193.5988 -34.3408)
		(size 0.7112)
		(drill 0.3556)
		(layers "F.Cu" "B.Cu")
		(net "VR_PVDDR_A_GH1")
	)
	(segment
		(start 193.5988 -34.3408)
		(end 192.8876 -33.6296)
		(width 0.508)
		(layer "B.Cu")
		(net "VR_PVDDR_A_GH1")
	)
	(segment
		(start 192.8876 -33.6296)
		(end 192.8876 -33.274)
		(width 0.508)
		(layer "B.Cu")
		(net "VR_PVDDR_A_GH1")
	)
	(segment
		(start 194.9704 -34.3408)
		(end 193.5988 -34.3408)
		(width 0.508)
		(layer "B.Cu")
		(net "VR_PVDDR_A_GH1")
	)
	(segment
		(start 195.5292 -33.782)
		(end 194.9704 -34.3408)
		(width 0.508)
		(layer "B.Cu")
		(net "VR_PVDDR_A_GH1")
	)
	(segment
		(start 160.27527 -6.505448)
		(end 160.26257 -6.492748)
		(width 0.2413)
		(layer "F.Cu")
		(net "M_B_MA6")
	)
	(segment
		(start 160.27527 -8.51916)
		(end 160.27527 -6.505448)
		(width 0.2413)
		(layer "F.Cu")
		(net "M_B_MA6")
	)
	(segment
		(start 160.26257 -6.492748)
		(end 160.26257 -6.402578)
		(width 0.2413)
		(layer "F.Cu")
		(net "M_B_MA6")
	)
	(segment
		(start 160.450022 -8.693912)
		(end 160.27527 -8.51916)
		(width 0.2413)
		(layer "F.Cu")
		(net "M_B_MA6")
	)
	(segment
		(start 160.450022 -9.897364)
		(end 160.450022 -8.693912)
		(width 0.2413)
		(layer "F.Cu")
		(net "M_B_MA6")
	)
	(segment
		(start 102.743 -30.100778)
		(end 102.750366 -30.100778)
		(width 0.1016)
		(layer "F.Cu")
		(net "M_B_MA6")
	)
	(segment
		(start 102.278688 -29.997654)
		(end 102.639876 -29.997654)
		(width 0.1016)
		(layer "F.Cu")
		(net "M_B_MA6")
	)
	(segment
		(start 102.639876 -29.997654)
		(end 102.743 -30.100778)
		(width 0.1016)
		(layer "F.Cu")
		(net "M_B_MA6")
	)
	(via
		(at 160.26257 -6.402578)
		(size 0.4318)
		(drill 0.2032)
		(layers "F.Cu" "B.Cu")
		(net "M_B_MA6")
	)
	(via
		(at 102.750366 -30.100778)
		(size 0.4318)
		(drill 0.2032)
		(layers "F.Cu" "B.Cu")
		(net "M_B_MA6")
	)
	(segment
		(start 160.450022 -2.899156)
		(end 160.40735 -2.941828)
		(width 0.2413)
		(layer "B.Cu")
		(net "M_B_MA6")
	)
	(segment
		(start 160.40735 -3.35915)
		(end 160.752028 -3.703828)
		(width 0.2413)
		(layer "B.Cu")
		(net "M_B_MA6")
	)
	(segment
		(start 160.450022 -1.690624)
		(end 160.450022 -2.899156)
		(width 0.2413)
		(layer "B.Cu")
		(net "M_B_MA6")
	)
	(segment
		(start 160.314386 -6.402578)
		(end 160.26257 -6.402578)
		(width 0.2413)
		(layer "B.Cu")
		(net "M_B_MA6")
	)
	(segment
		(start 160.752028 -3.703828)
		(end 160.752028 -5.964936)
		(width 0.2413)
		(layer "B.Cu")
		(net "M_B_MA6")
	)
	(segment
		(start 160.752028 -5.964936)
		(end 160.314386 -6.402578)
		(width 0.2413)
		(layer "B.Cu")
		(net "M_B_MA6")
	)
	(segment
		(start 160.40735 -2.941828)
		(end 160.40735 -3.35915)
		(width 0.2413)
		(layer "B.Cu")
		(net "M_B_MA6")
	)
	(segment
		(start 152.554432 -20.03806)
		(end 152.113742 -20.47875)
		(width 0.1905)
		(layer "In7.Cu")
		(net "M_B_MA6")
	)
	(segment
		(start 156.602684 -15.19301)
		(end 156.866336 -15.456916)
		(width 0.1905)
		(layer "In7.Cu")
		(net "M_B_MA6")
	)
	(segment
		(start 152.829768 -18.965926)
		(end 152.560528 -18.965926)
		(width 0.1905)
		(layer "In7.Cu")
		(net "M_B_MA6")
	)
	(segment
		(start 102.4636 -29.106368)
		(end 103.690166 -27.879802)
		(width 0.1016)
		(layer "In7.Cu")
		(net "M_B_MA6")
	)
	(segment
		(start 102.750366 -30.100778)
		(end 102.744778 -30.100778)
		(width 0.1016)
		(layer "In7.Cu")
		(net "M_B_MA6")
	)
	(segment
		(start 159.9946 -9.653778)
		(end 158.1658 -11.482578)
		(width 0.1905)
		(layer "In7.Cu")
		(net "M_B_MA6")
	)
	(segment
		(start 156.327348 -15.995904)
		(end 156.063696 -15.731998)
		(width 0.1905)
		(layer "In7.Cu")
		(net "M_B_MA6")
	)
	(segment
		(start 157.405324 -14.917928)
		(end 157.141672 -14.654022)
		(width 0.1905)
		(layer "In7.Cu")
		(net "M_B_MA6")
	)
	(segment
		(start 151.200104 -20.828)
		(end 116.35359 -20.828)
		(width 0.1905)
		(layer "In7.Cu")
		(net "M_B_MA6")
	)
	(segment
		(start 155.524708 -16.270986)
		(end 155.78836 -16.534892)
		(width 0.1905)
		(layer "In7.Cu")
		(net "M_B_MA6")
	)
	(segment
		(start 156.866336 -15.726156)
		(end 156.596588 -15.995904)
		(width 0.1905)
		(layer "In7.Cu")
		(net "M_B_MA6")
	)
	(segment
		(start 109.414564 -25.4508)
		(end 110.265464 -24.5999)
		(width 0.1016)
		(layer "In7.Cu")
		(net "M_B_MA6")
	)
	(segment
		(start 154.440636 -18.151856)
		(end 154.171396 -18.151856)
		(width 0.1905)
		(layer "In7.Cu")
		(net "M_B_MA6")
	)
	(segment
		(start 105.234486 -27.879802)
		(end 107.663488 -25.4508)
		(width 0.1016)
		(layer "In7.Cu")
		(net "M_B_MA6")
	)
	(segment
		(start 153.632408 -18.690844)
		(end 153.632408 -18.960084)
		(width 0.1905)
		(layer "In7.Cu")
		(net "M_B_MA6")
	)
	(segment
		(start 154.171396 -18.151856)
		(end 153.907744 -17.88795)
		(width 0.1905)
		(layer "In7.Cu")
		(net "M_B_MA6")
	)
	(segment
		(start 110.265464 -24.5999)
		(end 110.6424 -24.5999)
		(width 0.1016)
		(layer "In7.Cu")
		(net "M_B_MA6")
	)
	(segment
		(start 156.866336 -15.456916)
		(end 156.866336 -15.726156)
		(width 0.1905)
		(layer "In7.Cu")
		(net "M_B_MA6")
	)
	(segment
		(start 151.549354 -20.47875)
		(end 151.200104 -20.828)
		(width 0.1905)
		(layer "In7.Cu")
		(net "M_B_MA6")
	)
	(segment
		(start 157.674564 -14.917928)
		(end 157.405324 -14.917928)
		(width 0.1905)
		(layer "In7.Cu")
		(net "M_B_MA6")
	)
	(segment
		(start 155.794456 -15.731998)
		(end 155.524708 -16.001746)
		(width 0.1905)
		(layer "In7.Cu")
		(net "M_B_MA6")
	)
	(segment
		(start 154.710384 -17.612868)
		(end 154.710384 -17.882108)
		(width 0.1905)
		(layer "In7.Cu")
		(net "M_B_MA6")
	)
	(segment
		(start 155.518612 -17.07388)
		(end 155.249372 -17.07388)
		(width 0.1905)
		(layer "In7.Cu")
		(net "M_B_MA6")
	)
	(segment
		(start 154.98572 -16.809974)
		(end 154.71648 -16.809974)
		(width 0.1905)
		(layer "In7.Cu")
		(net "M_B_MA6")
	)
	(segment
		(start 153.368756 -18.426938)
		(end 153.632408 -18.690844)
		(width 0.1905)
		(layer "In7.Cu")
		(net "M_B_MA6")
	)
	(segment
		(start 160.26257 -6.402578)
		(end 160.26257 -6.845808)
		(width 0.1905)
		(layer "In7.Cu")
		(net "M_B_MA6")
	)
	(segment
		(start 110.7059 -24.5364)
		(end 110.6424 -24.5999)
		(width 0.1905)
		(layer "In7.Cu")
		(net "M_B_MA6")
	)
	(segment
		(start 154.446732 -17.348962)
		(end 154.710384 -17.612868)
		(width 0.1905)
		(layer "In7.Cu")
		(net "M_B_MA6")
	)
	(segment
		(start 156.596588 -15.995904)
		(end 156.327348 -15.995904)
		(width 0.1905)
		(layer "In7.Cu")
		(net "M_B_MA6")
	)
	(segment
		(start 158.1658 -11.482578)
		(end 158.1658 -14.426692)
		(width 0.1905)
		(layer "In7.Cu")
		(net "M_B_MA6")
	)
	(segment
		(start 116.35359 -20.828)
		(end 112.64519 -24.5364)
		(width 0.1905)
		(layer "In7.Cu")
		(net "M_B_MA6")
	)
	(segment
		(start 155.249372 -17.07388)
		(end 154.98572 -16.809974)
		(width 0.1905)
		(layer "In7.Cu")
		(net "M_B_MA6")
	)
	(segment
		(start 155.524708 -16.001746)
		(end 155.524708 -16.270986)
		(width 0.1905)
		(layer "In7.Cu")
		(net "M_B_MA6")
	)
	(segment
		(start 156.602684 -14.92377)
		(end 156.602684 -15.19301)
		(width 0.1905)
		(layer "In7.Cu")
		(net "M_B_MA6")
	)
	(segment
		(start 154.71648 -16.809974)
		(end 154.446732 -17.079722)
		(width 0.1905)
		(layer "In7.Cu")
		(net "M_B_MA6")
	)
	(segment
		(start 153.36266 -19.229832)
		(end 153.09342 -19.229832)
		(width 0.1905)
		(layer "In7.Cu")
		(net "M_B_MA6")
	)
	(segment
		(start 102.744778 -30.100778)
		(end 102.4636 -29.8196)
		(width 0.1016)
		(layer "In7.Cu")
		(net "M_B_MA6")
	)
	(segment
		(start 153.09342 -19.229832)
		(end 152.829768 -18.965926)
		(width 0.1905)
		(layer "In7.Cu")
		(net "M_B_MA6")
	)
	(segment
		(start 156.063696 -15.731998)
		(end 155.794456 -15.731998)
		(width 0.1905)
		(layer "In7.Cu")
		(net "M_B_MA6")
	)
	(segment
		(start 107.663488 -25.4508)
		(end 109.414564 -25.4508)
		(width 0.1016)
		(layer "In7.Cu")
		(net "M_B_MA6")
	)
	(segment
		(start 152.560528 -18.965926)
		(end 152.29078 -19.235674)
		(width 0.1905)
		(layer "In7.Cu")
		(net "M_B_MA6")
	)
	(segment
		(start 153.638504 -17.88795)
		(end 153.368756 -18.157698)
		(width 0.1905)
		(layer "In7.Cu")
		(net "M_B_MA6")
	)
	(segment
		(start 155.78836 -16.534892)
		(end 155.78836 -16.804132)
		(width 0.1905)
		(layer "In7.Cu")
		(net "M_B_MA6")
	)
	(segment
		(start 152.29078 -19.235674)
		(end 152.29078 -19.504914)
		(width 0.1905)
		(layer "In7.Cu")
		(net "M_B_MA6")
	)
	(segment
		(start 152.554432 -19.76882)
		(end 152.554432 -20.03806)
		(width 0.1905)
		(layer "In7.Cu")
		(net "M_B_MA6")
	)
	(segment
		(start 157.141672 -14.654022)
		(end 156.872432 -14.654022)
		(width 0.1905)
		(layer "In7.Cu")
		(net "M_B_MA6")
	)
	(segment
		(start 153.368756 -18.157698)
		(end 153.368756 -18.426938)
		(width 0.1905)
		(layer "In7.Cu")
		(net "M_B_MA6")
	)
	(segment
		(start 154.710384 -17.882108)
		(end 154.440636 -18.151856)
		(width 0.1905)
		(layer "In7.Cu")
		(net "M_B_MA6")
	)
	(segment
		(start 158.1658 -14.426692)
		(end 157.674564 -14.917928)
		(width 0.1905)
		(layer "In7.Cu")
		(net "M_B_MA6")
	)
	(segment
		(start 153.907744 -17.88795)
		(end 153.638504 -17.88795)
		(width 0.1905)
		(layer "In7.Cu")
		(net "M_B_MA6")
	)
	(segment
		(start 153.632408 -18.960084)
		(end 153.36266 -19.229832)
		(width 0.1905)
		(layer "In7.Cu")
		(net "M_B_MA6")
	)
	(segment
		(start 152.113742 -20.47875)
		(end 151.549354 -20.47875)
		(width 0.1905)
		(layer "In7.Cu")
		(net "M_B_MA6")
	)
	(segment
		(start 154.446732 -17.079722)
		(end 154.446732 -17.348962)
		(width 0.1905)
		(layer "In7.Cu")
		(net "M_B_MA6")
	)
	(segment
		(start 102.4636 -29.8196)
		(end 102.4636 -29.106368)
		(width 0.1016)
		(layer "In7.Cu")
		(net "M_B_MA6")
	)
	(segment
		(start 103.690166 -27.879802)
		(end 105.234486 -27.879802)
		(width 0.1016)
		(layer "In7.Cu")
		(net "M_B_MA6")
	)
	(segment
		(start 152.29078 -19.504914)
		(end 152.554432 -19.76882)
		(width 0.1905)
		(layer "In7.Cu")
		(net "M_B_MA6")
	)
	(segment
		(start 156.872432 -14.654022)
		(end 156.602684 -14.92377)
		(width 0.1905)
		(layer "In7.Cu")
		(net "M_B_MA6")
	)
	(segment
		(start 112.64519 -24.5364)
		(end 110.7059 -24.5364)
		(width 0.1905)
		(layer "In7.Cu")
		(net "M_B_MA6")
	)
	(segment
		(start 160.26257 -6.845808)
		(end 159.9946 -7.113778)
		(width 0.1905)
		(layer "In7.Cu")
		(net "M_B_MA6")
	)
	(segment
		(start 155.78836 -16.804132)
		(end 155.518612 -17.07388)
		(width 0.1905)
		(layer "In7.Cu")
		(net "M_B_MA6")
	)
	(segment
		(start 159.9946 -7.113778)
		(end 159.9946 -9.653778)
		(width 0.1905)
		(layer "In7.Cu")
		(net "M_B_MA6")
	)
	(segment
		(start 86.388448 -30.759654)
		(end 86.388448 -30.759146)
		(width 0.1143)
		(layer "F.Cu")
		(net "SATA2_OBS_N")
	)
	(segment
		(start 86.388448 -30.759146)
		(end 86.047072 -30.41777)
		(width 0.1143)
		(layer "F.Cu")
		(net "SATA2_OBS_N")
	)
	(via
		(at 86.047072 -30.41777)
		(size 0.4318)
		(drill 0.2032)
		(layers "F.Cu" "B.Cu")
		(net "SATA2_OBS_N")
	)
	(via
		(at 85.4202 -30.0228)
		(size 0.7112)
		(drill 0.3556)
		(layers "F.Cu" "B.Cu")
		(net "SATA2_OBS_N")
	)
	(segment
		(start 85.81517 -30.41777)
		(end 86.047072 -30.41777)
		(width 0.1143)
		(layer "B.Cu")
		(net "SATA2_OBS_N")
	)
	(segment
		(start 83.3374 -29.337)
		(end 83.60791 -29.60751)
		(width 0.1143)
		(layer "B.Cu")
		(net "SATA2_OBS_N")
	)
	(segment
		(start 85.4202 -30.0228)
		(end 85.81517 -30.41777)
		(width 0.1143)
		(layer "B.Cu")
		(net "SATA2_OBS_N")
	)
	(segment
		(start 87.122 -30.7594)
		(end 86.388702 -30.7594)
		(width 0.1143)
		(layer "B.Cu")
		(net "SATA2_OBS_N")
	)
	(segment
		(start 83.60791 -29.60751)
		(end 85.00491 -29.60751)
		(width 0.1143)
		(layer "B.Cu")
		(net "SATA2_OBS_N")
	)
	(segment
		(start 85.00491 -29.60751)
		(end 85.4202 -30.0228)
		(width 0.1143)
		(layer "B.Cu")
		(net "SATA2_OBS_N")
	)
	(segment
		(start 86.388702 -30.7594)
		(end 86.047072 -30.41777)
		(width 0.1143)
		(layer "B.Cu")
		(net "SATA2_OBS_N")
	)
	(segment
		(start 44.4754 -24.13)
		(end 43.785282 -24.13)
		(width 0.127)
		(layer "F.Cu")
		(net "TP_XDP_DFX_PORT_CLK1")
	)
	(segment
		(start 43.142154 -25.05456)
		(end 42.10177 -25.05456)
		(width 0.127)
		(layer "F.Cu")
		(net "TP_XDP_DFX_PORT_CLK1")
	)
	(segment
		(start 43.785282 -24.13)
		(end 43.42257 -24.492712)
		(width 0.127)
		(layer "F.Cu")
		(net "TP_XDP_DFX_PORT_CLK1")
	)
	(segment
		(start 44.6024 -24.003)
		(end 44.4754 -24.13)
		(width 0.127)
		(layer "F.Cu")
		(net "TP_XDP_DFX_PORT_CLK1")
	)
	(segment
		(start 43.42257 -24.774144)
		(end 43.142154 -25.05456)
		(width 0.127)
		(layer "F.Cu")
		(net "TP_XDP_DFX_PORT_CLK1")
	)
	(segment
		(start 43.42257 -24.492712)
		(end 43.42257 -24.774144)
		(width 0.127)
		(layer "F.Cu")
		(net "TP_XDP_DFX_PORT_CLK1")
	)
	(segment
		(start 192.287398 -32.575754)
		(end 191.656716 -32.575754)
		(width 0.2032)
		(layer "F.Cu")
		(net "VR_PVDDR_A_PROG1")
	)
	(segment
		(start 194.691 -32.0548)
		(end 194.6402 -32.004)
		(width 0.2032)
		(layer "F.Cu")
		(net "VR_PVDDR_A_PROG1")
	)
	(segment
		(start 194.6402 -32.004)
		(end 192.859152 -32.004)
		(width 0.2032)
		(layer "F.Cu")
		(net "VR_PVDDR_A_PROG1")
	)
	(segment
		(start 192.859152 -32.004)
		(end 192.287398 -32.575754)
		(width 0.2032)
		(layer "F.Cu")
		(net "VR_PVDDR_A_PROG1")
	)
	(segment
		(start 102.550468 -26.684986)
		(end 102.250748 -26.984706)
		(width 0.1016)
		(layer "F.Cu")
		(net "M_B_DQ23")
	)
	(segment
		(start 143.34998 -1.68402)
		(end 143.34998 -2.777998)
		(width 0.1778)
		(layer "F.Cu")
		(net "M_B_DQ23")
	)
	(segment
		(start 102.250748 -26.984706)
		(end 102.250748 -27.300174)
		(width 0.1016)
		(layer "F.Cu")
		(net "M_B_DQ23")
	)
	(segment
		(start 143.2052 -2.922778)
		(end 143.2052 -3.481578)
		(width 0.1778)
		(layer "F.Cu")
		(net "M_B_DQ23")
	)
	(segment
		(start 102.108 -25.2984)
		(end 102.474268 -25.664668)
		(width 0.1016)
		(layer "F.Cu")
		(net "M_B_DQ23")
	)
	(segment
		(start 102.550468 -26.432002)
		(end 102.550468 -26.684986)
		(width 0.1016)
		(layer "F.Cu")
		(net "M_B_DQ23")
	)
	(segment
		(start 101.7016 -23.4188)
		(end 102.108 -23.8252)
		(width 0.1016)
		(layer "F.Cu")
		(net "M_B_DQ23")
	)
	(segment
		(start 102.474268 -25.664668)
		(end 102.474268 -26.355802)
		(width 0.1016)
		(layer "F.Cu")
		(net "M_B_DQ23")
	)
	(segment
		(start 102.474268 -26.355802)
		(end 102.550468 -26.432002)
		(width 0.1016)
		(layer "F.Cu")
		(net "M_B_DQ23")
	)
	(segment
		(start 143.34998 -2.777998)
		(end 143.2052 -2.922778)
		(width 0.1778)
		(layer "F.Cu")
		(net "M_B_DQ23")
	)
	(segment
		(start 102.108 -23.8252)
		(end 102.108 -25.2984)
		(width 0.1016)
		(layer "F.Cu")
		(net "M_B_DQ23")
	)
	(segment
		(start 143.2052 -3.481578)
		(end 143.3576 -3.633978)
		(width 0.1778)
		(layer "F.Cu")
		(net "M_B_DQ23")
	)
	(via
		(at 101.7016 -23.4188)
		(size 0.4318)
		(drill 0.2032)
		(layers "F.Cu" "B.Cu")
		(net "M_B_DQ23")
	)
	(via
		(at 143.3576 -3.633978)
		(size 0.4318)
		(drill 0.2032)
		(layers "F.Cu" "B.Cu")
		(net "M_B_DQ23")
	)
	(segment
		(start 143.050006 -3.326384)
		(end 143.3576 -3.633978)
		(width 0.1778)
		(layer "B.Cu")
		(net "M_B_DQ23")
	)
	(segment
		(start 143.050006 -1.690624)
		(end 143.050006 -3.326384)
		(width 0.1778)
		(layer "B.Cu")
		(net "M_B_DQ23")
	)
	(segment
		(start 141.986 -10.16)
		(end 139.5476 -12.5984)
		(width 0.1524)
		(layer "In4.Cu")
		(net "M_B_DQ23")
	)
	(segment
		(start 143.3576 -3.659378)
		(end 143.1798 -3.837178)
		(width 0.1524)
		(layer "In4.Cu")
		(net "M_B_DQ23")
	)
	(segment
		(start 114.2238 -14.9098)
		(end 110.4646 -18.669)
		(width 0.1524)
		(layer "In4.Cu")
		(net "M_B_DQ23")
	)
	(segment
		(start 141.986 -8.626602)
		(end 141.986 -10.16)
		(width 0.1524)
		(layer "In4.Cu")
		(net "M_B_DQ23")
	)
	(segment
		(start 104.1908 -19.0754)
		(end 104.5972 -18.669)
		(width 0.1016)
		(layer "In4.Cu")
		(net "M_B_DQ23")
	)
	(segment
		(start 103.505 -19.0754)
		(end 104.1908 -19.0754)
		(width 0.1016)
		(layer "In4.Cu")
		(net "M_B_DQ23")
	)
	(segment
		(start 141.98219 -8.27532)
		(end 141.98219 -8.622792)
		(width 0.1524)
		(layer "In4.Cu")
		(net "M_B_DQ23")
	)
	(segment
		(start 143.3576 -3.633978)
		(end 143.3576 -3.659378)
		(width 0.1524)
		(layer "In4.Cu")
		(net "M_B_DQ23")
	)
	(segment
		(start 101.7016 -20.8788)
		(end 103.505 -19.0754)
		(width 0.1016)
		(layer "In4.Cu")
		(net "M_B_DQ23")
	)
	(segment
		(start 141.986 -8.27151)
		(end 141.98219 -8.27532)
		(width 0.1524)
		(layer "In4.Cu")
		(net "M_B_DQ23")
	)
	(segment
		(start 136.244076 -14.9098)
		(end 114.2238 -14.9098)
		(width 0.1524)
		(layer "In4.Cu")
		(net "M_B_DQ23")
	)
	(segment
		(start 141.98219 -8.622792)
		(end 141.986 -8.626602)
		(width 0.1524)
		(layer "In4.Cu")
		(net "M_B_DQ23")
	)
	(segment
		(start 110.4646 -18.669)
		(end 104.5972 -18.669)
		(width 0.1524)
		(layer "In4.Cu")
		(net "M_B_DQ23")
	)
	(segment
		(start 143.1798 -3.837178)
		(end 143.1798 -6.326378)
		(width 0.1524)
		(layer "In4.Cu")
		(net "M_B_DQ23")
	)
	(segment
		(start 138.555476 -12.5984)
		(end 136.244076 -14.9098)
		(width 0.1524)
		(layer "In4.Cu")
		(net "M_B_DQ23")
	)
	(segment
		(start 101.7016 -23.4188)
		(end 101.7016 -20.8788)
		(width 0.1016)
		(layer "In4.Cu")
		(net "M_B_DQ23")
	)
	(segment
		(start 139.5476 -12.5984)
		(end 138.555476 -12.5984)
		(width 0.1524)
		(layer "In4.Cu")
		(net "M_B_DQ23")
	)
	(segment
		(start 141.986 -7.520178)
		(end 141.986 -8.27151)
		(width 0.1524)
		(layer "In4.Cu")
		(net "M_B_DQ23")
	)
	(segment
		(start 143.1798 -6.326378)
		(end 141.986 -7.520178)
		(width 0.1524)
		(layer "In4.Cu")
		(net "M_B_DQ23")
	)
	(segment
		(start 78.40853 -32.69107)
		(end 78.00467 -32.69107)
		(width 0.1397)
		(layer "F.Cu")
		(net "SATA3_TX_DN0")
	)
	(segment
		(start 78.00467 -32.69107)
		(end 74.81697 -29.50337)
		(width 0.1397)
		(layer "F.Cu")
		(net "SATA3_TX_DN0")
	)
	(segment
		(start 71.44893 -28.57627)
		(end 71.0311 -28.15844)
		(width 0.1397)
		(layer "F.Cu")
		(net "SATA3_TX_DN0")
	)
	(segment
		(start 70.1675 -27.80284)
		(end 69.81444 -28.1559)
		(width 0.1397)
		(layer "F.Cu")
		(net "SATA3_TX_DN0")
	)
	(segment
		(start 79.830168 -33.411414)
		(end 79.743808 -33.497774)
		(width 0.1397)
		(layer "F.Cu")
		(net "SATA3_TX_DN0")
	)
	(segment
		(start 71.0311 -28.15844)
		(end 71.0311 -26.4414)
		(width 0.1397)
		(layer "F.Cu")
		(net "SATA3_TX_DN0")
	)
	(segment
		(start 69.81444 -28.1559)
		(end 69.384164 -28.1559)
		(width 0.1397)
		(layer "F.Cu")
		(net "SATA3_TX_DN0")
	)
	(segment
		(start 79.215234 -33.497774)
		(end 78.40853 -32.69107)
		(width 0.1397)
		(layer "F.Cu")
		(net "SATA3_TX_DN0")
	)
	(segment
		(start 69.384164 -28.1559)
		(end 69.13499 -28.405074)
		(width 0.1397)
		(layer "F.Cu")
		(net "SATA3_TX_DN0")
	)
	(segment
		(start 80.602328 -33.411414)
		(end 79.830168 -33.411414)
		(width 0.1397)
		(layer "F.Cu")
		(net "SATA3_TX_DN0")
	)
	(segment
		(start 71.0311 -26.4414)
		(end 70.8787 -26.289)
		(width 0.1397)
		(layer "F.Cu")
		(net "SATA3_TX_DN0")
	)
	(segment
		(start 70.8787 -26.289)
		(end 70.3199 -26.289)
		(width 0.1397)
		(layer "F.Cu")
		(net "SATA3_TX_DN0")
	)
	(segment
		(start 79.743808 -33.497774)
		(end 79.215234 -33.497774)
		(width 0.1397)
		(layer "F.Cu")
		(net "SATA3_TX_DN0")
	)
	(segment
		(start 70.1675 -26.4414)
		(end 70.1675 -27.80284)
		(width 0.1397)
		(layer "F.Cu")
		(net "SATA3_TX_DN0")
	)
	(segment
		(start 74.52233 -28.57627)
		(end 71.44893 -28.57627)
		(width 0.1397)
		(layer "F.Cu")
		(net "SATA3_TX_DN0")
	)
	(segment
		(start 74.81697 -28.87091)
		(end 74.52233 -28.57627)
		(width 0.1397)
		(layer "F.Cu")
		(net "SATA3_TX_DN0")
	)
	(segment
		(start 74.81697 -29.50337)
		(end 74.81697 -28.87091)
		(width 0.1397)
		(layer "F.Cu")
		(net "SATA3_TX_DN0")
	)
	(segment
		(start 70.3199 -26.289)
		(end 70.1675 -26.4414)
		(width 0.1397)
		(layer "F.Cu")
		(net "SATA3_TX_DN0")
	)
	(via
		(at 69.13499 -28.405074)
		(size 0.508)
		(drill 0.254)
		(layers "F.Cu" "B.Cu")
		(net "SATA3_TX_DN0")
	)
	(segment
		(start 67.6402 -28.321)
		(end 67.8434 -28.1178)
		(width 0.1397)
		(layer "B.Cu")
		(net "SATA3_TX_DN0")
	)
	(segment
		(start 67.8434 -28.1178)
		(end 68.847716 -28.1178)
		(width 0.1397)
		(layer "B.Cu")
		(net "SATA3_TX_DN0")
	)
	(segment
		(start 68.847716 -28.1178)
		(end 69.13499 -28.405074)
		(width 0.1397)
		(layer "B.Cu")
		(net "SATA3_TX_DN0")
	)
	(segment
		(start 15.34795 -60.72505)
		(end 15.34795 -62.902846)
		(width 0.1143)
		(layer "F.Cu")
		(net "SVID_CPU_DATA")
	)
	(segment
		(start 181.7116 -38.862)
		(end 182.334662 -39.485062)
		(width 0.1143)
		(layer "F.Cu")
		(net "SVID_CPU_DATA")
	)
	(segment
		(start 13.3604 -62.8396)
		(end 13.865098 -62.8396)
		(width 0.1143)
		(layer "F.Cu")
		(net "SVID_CPU_DATA")
	)
	(segment
		(start 13.3604 -62.8396)
		(end 13.3604 -62.0776)
		(width 0.1143)
		(layer "F.Cu")
		(net "SVID_CPU_DATA")
	)
	(segment
		(start 181.5338 -38.862)
		(end 181.7116 -38.862)
		(width 0.1143)
		(layer "F.Cu")
		(net "SVID_CPU_DATA")
	)
	(segment
		(start 15.4178 -60.6552)
		(end 15.34795 -60.72505)
		(width 0.1143)
		(layer "F.Cu")
		(net "SVID_CPU_DATA")
	)
	(segment
		(start 183.2102 -38.862)
		(end 182.587138 -39.485062)
		(width 0.1143)
		(layer "F.Cu")
		(net "SVID_CPU_DATA")
	)
	(segment
		(start 182.587138 -39.485062)
		(end 182.58155 -39.485062)
		(width 0.1143)
		(layer "F.Cu")
		(net "SVID_CPU_DATA")
	)
	(segment
		(start 15.34795 -62.902846)
		(end 14.849094 -63.401702)
		(width 0.1143)
		(layer "F.Cu")
		(net "SVID_CPU_DATA")
	)
	(segment
		(start 182.334662 -39.485062)
		(end 182.58155 -39.485062)
		(width 0.1143)
		(layer "F.Cu")
		(net "SVID_CPU_DATA")
	)
	(segment
		(start 14.849094 -63.401702)
		(end 14.4272 -63.401702)
		(width 0.1143)
		(layer "F.Cu")
		(net "SVID_CPU_DATA")
	)
	(segment
		(start 13.865098 -62.8396)
		(end 14.4272 -63.401702)
		(width 0.1143)
		(layer "F.Cu")
		(net "SVID_CPU_DATA")
	)
	(via
		(at 14.4272 -63.401702)
		(size 0.508)
		(drill 0.254)
		(layers "F.Cu" "B.Cu")
		(net "SVID_CPU_DATA")
	)
	(via
		(at 81.026 -64.5668)
		(size 0.508)
		(drill 0.254)
		(layers "F.Cu" "B.Cu")
		(net "SVID_CPU_DATA")
	)
	(via
		(at 182.58155 -39.485062)
		(size 0.508)
		(drill 0.254)
		(layers "F.Cu" "B.Cu")
		(net "SVID_CPU_DATA")
	)
	(via
		(at 182.4482 -40.4622)
		(size 0.7112)
		(drill 0.3556)
		(layers "F.Cu" "B.Cu")
		(net "SVID_CPU_DATA")
	)
	(segment
		(start 182.4482 -39.618412)
		(end 182.58155 -39.485062)
		(width 0.1143)
		(layer "B.Cu")
		(net "SVID_CPU_DATA")
	)
	(segment
		(start 182.4482 -40.4622)
		(end 182.4482 -39.618412)
		(width 0.1143)
		(layer "B.Cu")
		(net "SVID_CPU_DATA")
	)
	(segment
		(start 81.026 -63.6778)
		(end 81.026 -64.5668)
		(width 0.1143)
		(layer "B.Cu")
		(net "SVID_CPU_DATA")
	)
	(segment
		(start 81.026 -65.3542)
		(end 81.026 -64.5668)
		(width 0.1143)
		(layer "B.Cu")
		(net "SVID_CPU_DATA")
	)
	(segment
		(start 190.005716 -52.6288)
		(end 182.7022 -45.325284)
		(width 0.0889)
		(layer "In4.Cu")
		(net "SVID_CPU_DATA")
	)
	(segment
		(start 84.862162 -69.69125)
		(end 88.02751 -69.69125)
		(width 0.0889)
		(layer "In4.Cu")
		(net "SVID_CPU_DATA")
	)
	(segment
		(start 16.728186 -71.31685)
		(end 44.27982 -71.31685)
		(width 0.0889)
		(layer "In4.Cu")
		(net "SVID_CPU_DATA")
	)
	(segment
		(start 182.0672 -40.943784)
		(end 182.1688 -40.842184)
		(width 0.0889)
		(layer "In4.Cu")
		(net "SVID_CPU_DATA")
	)
	(segment
		(start 181.991 -44.131484)
		(end 182.0799 -44.042584)
		(width 0.0889)
		(layer "In4.Cu")
		(net "SVID_CPU_DATA")
	)
	(segment
		(start 182.7022 -40.753284)
		(end 182.7022 -39.605712)
		(width 0.0889)
		(layer "In4.Cu")
		(net "SVID_CPU_DATA")
	)
	(segment
		(start 84.504276 -69.691504)
		(end 84.861908 -69.691504)
		(width 0.0889)
		(layer "In4.Cu")
		(net "SVID_CPU_DATA")
	)
	(segment
		(start 44.27982 -71.31685)
		(end 46.70552 -68.89115)
		(width 0.0889)
		(layer "In4.Cu")
		(net "SVID_CPU_DATA")
	)
	(segment
		(start 191.643 -52.6288)
		(end 190.005716 -52.6288)
		(width 0.0889)
		(layer "In4.Cu")
		(net "SVID_CPU_DATA")
	)
	(segment
		(start 182.7022 -45.325284)
		(end 182.7022 -44.664884)
		(width 0.0889)
		(layer "In4.Cu")
		(net "SVID_CPU_DATA")
	)
	(segment
		(start 182.7022 -41.820084)
		(end 182.7022 -41.464484)
		(width 0.0889)
		(layer "In4.Cu")
		(net "SVID_CPU_DATA")
	)
	(segment
		(start 182.1307 -42.442384)
		(end 182.0418 -42.353484)
		(width 0.0889)
		(layer "In4.Cu")
		(net "SVID_CPU_DATA")
	)
	(segment
		(start 182.1688 -40.842184)
		(end 182.6133 -40.842184)
		(width 0.0889)
		(layer "In4.Cu")
		(net "SVID_CPU_DATA")
	)
	(segment
		(start 182.0672 -41.273984)
		(end 182.0672 -40.943784)
		(width 0.0889)
		(layer "In4.Cu")
		(net "SVID_CPU_DATA")
	)
	(segment
		(start 182.7022 -39.605712)
		(end 182.58155 -39.485062)
		(width 0.0889)
		(layer "In4.Cu")
		(net "SVID_CPU_DATA")
	)
	(segment
		(start 84.861908 -69.691504)
		(end 84.862162 -69.69125)
		(width 0.0889)
		(layer "In4.Cu")
		(net "SVID_CPU_DATA")
	)
	(segment
		(start 182.0799 -44.575984)
		(end 181.991 -44.487084)
		(width 0.0889)
		(layer "In4.Cu")
		(net "SVID_CPU_DATA")
	)
	(segment
		(start 182.0418 -43.420284)
		(end 182.0418 -43.064684)
		(width 0.0889)
		(layer "In4.Cu")
		(net "SVID_CPU_DATA")
	)
	(segment
		(start 84.110322 -69.29755)
		(end 84.504276 -69.691504)
		(width 0.0889)
		(layer "In4.Cu")
		(net "SVID_CPU_DATA")
	)
	(segment
		(start 182.6133 -44.042584)
		(end 182.7022 -43.953684)
		(width 0.0889)
		(layer "In4.Cu")
		(net "SVID_CPU_DATA")
	)
	(segment
		(start 182.1688 -41.375584)
		(end 182.0672 -41.273984)
		(width 0.0889)
		(layer "In4.Cu")
		(net "SVID_CPU_DATA")
	)
	(segment
		(start 182.0418 -41.997884)
		(end 182.1307 -41.908984)
		(width 0.0889)
		(layer "In4.Cu")
		(net "SVID_CPU_DATA")
	)
	(segment
		(start 182.6133 -41.908984)
		(end 182.7022 -41.820084)
		(width 0.0889)
		(layer "In4.Cu")
		(net "SVID_CPU_DATA")
	)
	(segment
		(start 182.6133 -41.375584)
		(end 182.1688 -41.375584)
		(width 0.0889)
		(layer "In4.Cu")
		(net "SVID_CPU_DATA")
	)
	(segment
		(start 182.1307 -42.975784)
		(end 182.6133 -42.975784)
		(width 0.0889)
		(layer "In4.Cu")
		(net "SVID_CPU_DATA")
	)
	(segment
		(start 182.1307 -43.509184)
		(end 182.0418 -43.420284)
		(width 0.0889)
		(layer "In4.Cu")
		(net "SVID_CPU_DATA")
	)
	(segment
		(start 182.7022 -41.464484)
		(end 182.6133 -41.375584)
		(width 0.0889)
		(layer "In4.Cu")
		(net "SVID_CPU_DATA")
	)
	(segment
		(start 182.0418 -43.064684)
		(end 182.1307 -42.975784)
		(width 0.0889)
		(layer "In4.Cu")
		(net "SVID_CPU_DATA")
	)
	(segment
		(start 182.0418 -42.353484)
		(end 182.0418 -41.997884)
		(width 0.0889)
		(layer "In4.Cu")
		(net "SVID_CPU_DATA")
	)
	(segment
		(start 182.6133 -42.442384)
		(end 182.1307 -42.442384)
		(width 0.0889)
		(layer "In4.Cu")
		(net "SVID_CPU_DATA")
	)
	(segment
		(start 182.6133 -40.842184)
		(end 182.7022 -40.753284)
		(width 0.0889)
		(layer "In4.Cu")
		(net "SVID_CPU_DATA")
	)
	(segment
		(start 182.7022 -42.531284)
		(end 182.6133 -42.442384)
		(width 0.0889)
		(layer "In4.Cu")
		(net "SVID_CPU_DATA")
	)
	(segment
		(start 58.55335 -68.89115)
		(end 60.019692 -70.357492)
		(width 0.0889)
		(layer "In4.Cu")
		(net "SVID_CPU_DATA")
	)
	(segment
		(start 90.821764 -72.485504)
		(end 191.129412 -72.485504)
		(width 0.0889)
		(layer "In4.Cu")
		(net "SVID_CPU_DATA")
	)
	(segment
		(start 182.6133 -44.575984)
		(end 182.0799 -44.575984)
		(width 0.0889)
		(layer "In4.Cu")
		(net "SVID_CPU_DATA")
	)
	(segment
		(start 182.1307 -41.908984)
		(end 182.6133 -41.908984)
		(width 0.0889)
		(layer "In4.Cu")
		(net "SVID_CPU_DATA")
	)
	(segment
		(start 13.64615 -63.2079)
		(end 13.64615 -68.234814)
		(width 0.0889)
		(layer "In4.Cu")
		(net "SVID_CPU_DATA")
	)
	(segment
		(start 74.82078 -69.29755)
		(end 84.110322 -69.29755)
		(width 0.0889)
		(layer "In4.Cu")
		(net "SVID_CPU_DATA")
	)
	(segment
		(start 60.019692 -70.357492)
		(end 73.760838 -70.357492)
		(width 0.0889)
		(layer "In4.Cu")
		(net "SVID_CPU_DATA")
	)
	(segment
		(start 194.408298 -69.206618)
		(end 194.408298 -55.394098)
		(width 0.0889)
		(layer "In4.Cu")
		(net "SVID_CPU_DATA")
	)
	(segment
		(start 13.64615 -68.234814)
		(end 16.728186 -71.31685)
		(width 0.0889)
		(layer "In4.Cu")
		(net "SVID_CPU_DATA")
	)
	(segment
		(start 14.4272 -62.9539)
		(end 14.3383 -62.865)
		(width 0.0889)
		(layer "In4.Cu")
		(net "SVID_CPU_DATA")
	)
	(segment
		(start 194.408298 -55.394098)
		(end 191.643 -52.6288)
		(width 0.0889)
		(layer "In4.Cu")
		(net "SVID_CPU_DATA")
	)
	(segment
		(start 13.98905 -62.865)
		(end 13.64615 -63.2079)
		(width 0.0889)
		(layer "In4.Cu")
		(net "SVID_CPU_DATA")
	)
	(segment
		(start 46.70552 -68.89115)
		(end 58.55335 -68.89115)
		(width 0.0889)
		(layer "In4.Cu")
		(net "SVID_CPU_DATA")
	)
	(segment
		(start 182.7022 -43.953684)
		(end 182.7022 -43.598084)
		(width 0.0889)
		(layer "In4.Cu")
		(net "SVID_CPU_DATA")
	)
	(segment
		(start 181.991 -44.487084)
		(end 181.991 -44.131484)
		(width 0.0889)
		(layer "In4.Cu")
		(net "SVID_CPU_DATA")
	)
	(segment
		(start 182.7022 -44.664884)
		(end 182.6133 -44.575984)
		(width 0.0889)
		(layer "In4.Cu")
		(net "SVID_CPU_DATA")
	)
	(segment
		(start 182.7022 -42.886884)
		(end 182.7022 -42.531284)
		(width 0.0889)
		(layer "In4.Cu")
		(net "SVID_CPU_DATA")
	)
	(segment
		(start 88.02751 -69.69125)
		(end 90.821764 -72.485504)
		(width 0.0889)
		(layer "In4.Cu")
		(net "SVID_CPU_DATA")
	)
	(segment
		(start 14.3383 -62.865)
		(end 13.98905 -62.865)
		(width 0.0889)
		(layer "In4.Cu")
		(net "SVID_CPU_DATA")
	)
	(segment
		(start 182.6133 -42.975784)
		(end 182.7022 -42.886884)
		(width 0.0889)
		(layer "In4.Cu")
		(net "SVID_CPU_DATA")
	)
	(segment
		(start 182.6133 -43.509184)
		(end 182.1307 -43.509184)
		(width 0.0889)
		(layer "In4.Cu")
		(net "SVID_CPU_DATA")
	)
	(segment
		(start 73.760838 -70.357492)
		(end 74.82078 -69.29755)
		(width 0.0889)
		(layer "In4.Cu")
		(net "SVID_CPU_DATA")
	)
	(segment
		(start 182.0799 -44.042584)
		(end 182.6133 -44.042584)
		(width 0.0889)
		(layer "In4.Cu")
		(net "SVID_CPU_DATA")
	)
	(segment
		(start 14.4272 -63.401702)
		(end 14.4272 -62.9539)
		(width 0.0889)
		(layer "In4.Cu")
		(net "SVID_CPU_DATA")
	)
	(segment
		(start 191.129412 -72.485504)
		(end 194.408298 -69.206618)
		(width 0.0889)
		(layer "In4.Cu")
		(net "SVID_CPU_DATA")
	)
	(segment
		(start 182.7022 -43.598084)
		(end 182.6133 -43.509184)
		(width 0.0889)
		(layer "In4.Cu")
		(net "SVID_CPU_DATA")
	)
	(segment
		(start 15.24 -65.60693)
		(end 15.3289 -65.69583)
		(width 0.0889)
		(layer "In7.Cu")
		(net "SVID_CPU_DATA")
	)
	(segment
		(start 15.7988 -67.2084)
		(end 19.81835 -71.22795)
		(width 0.0889)
		(layer "In7.Cu")
		(net "SVID_CPU_DATA")
	)
	(segment
		(start 14.4272 -63.401702)
		(end 15.7988 -64.773302)
		(width 0.0889)
		(layer "In7.Cu")
		(net "SVID_CPU_DATA")
	)
	(segment
		(start 68.706238 -66.040762)
		(end 68.834 -65.913)
		(width 0.0889)
		(layer "In7.Cu")
		(net "SVID_CPU_DATA")
	)
	(segment
		(start 15.24 -65.2399)
		(end 15.24 -65.60693)
		(width 0.0889)
		(layer "In7.Cu")
		(net "SVID_CPU_DATA")
	)
	(segment
		(start 45.309282 -70.612)
		(end 45.517308 -70.403974)
		(width 0.0889)
		(layer "In7.Cu")
		(net "SVID_CPU_DATA")
	)
	(segment
		(start 44.704 -70.612)
		(end 44.849034 -70.466966)
		(width 0.0889)
		(layer "In7.Cu")
		(net "SVID_CPU_DATA")
	)
	(segment
		(start 68.072 -66.675)
		(end 68.45173 -66.675)
		(width 0.0889)
		(layer "In7.Cu")
		(net "SVID_CPU_DATA")
	)
	(segment
		(start 19.81835 -71.22795)
		(end 44.693332 -71.22795)
		(width 0.0889)
		(layer "In7.Cu")
		(net "SVID_CPU_DATA")
	)
	(segment
		(start 45.72 -69.785738)
		(end 45.784262 -69.85)
		(width 0.0889)
		(layer "In7.Cu")
		(net "SVID_CPU_DATA")
	)
	(segment
		(start 80.01 -65.5828)
		(end 81.026 -64.5668)
		(width 0.0889)
		(layer "In7.Cu")
		(net "SVID_CPU_DATA")
	)
	(segment
		(start 45.530262 -69.785738)
		(end 45.72 -69.785738)
		(width 0.0889)
		(layer "In7.Cu")
		(net "SVID_CPU_DATA")
	)
	(segment
		(start 44.693332 -71.22795)
		(end 44.825412 -71.09587)
		(width 0.0889)
		(layer "In7.Cu")
		(net "SVID_CPU_DATA")
	)
	(segment
		(start 15.621 -65.151)
		(end 15.3289 -65.151)
		(width 0.0889)
		(layer "In7.Cu")
		(net "SVID_CPU_DATA")
	)
	(segment
		(start 45.950124 -69.85)
		(end 46.089062 -69.711062)
		(width 0.0889)
		(layer "In7.Cu")
		(net "SVID_CPU_DATA")
	)
	(segment
		(start 46.089062 -69.711062)
		(end 46.089062 -69.203316)
		(width 0.0889)
		(layer "In7.Cu")
		(net "SVID_CPU_DATA")
	)
	(segment
		(start 68.45173 -66.675)
		(end 68.706238 -66.420492)
		(width 0.0889)
		(layer "In7.Cu")
		(net "SVID_CPU_DATA")
	)
	(segment
		(start 68.834 -65.913)
		(end 69.21373 -65.913)
		(width 0.0889)
		(layer "In7.Cu")
		(net "SVID_CPU_DATA")
	)
	(segment
		(start 45.401738 -70.104)
		(end 45.401738 -69.914262)
		(width 0.0889)
		(layer "In7.Cu")
		(net "SVID_CPU_DATA")
	)
	(segment
		(start 66.251328 -68.875402)
		(end 66.251328 -68.495672)
		(width 0.0889)
		(layer "In7.Cu")
		(net "SVID_CPU_DATA")
	)
	(segment
		(start 67.182238 -67.944492)
		(end 67.182238 -67.691762)
		(width 0.0889)
		(layer "In7.Cu")
		(net "SVID_CPU_DATA")
	)
	(segment
		(start 69.54393 -65.5828)
		(end 80.01 -65.5828)
		(width 0.0889)
		(layer "In7.Cu")
		(net "SVID_CPU_DATA")
	)
	(segment
		(start 44.825412 -70.860412)
		(end 44.704 -70.739)
		(width 0.0889)
		(layer "In7.Cu")
		(net "SVID_CPU_DATA")
	)
	(segment
		(start 66.251328 -68.495672)
		(end 66.421 -68.326)
		(width 0.0889)
		(layer "In7.Cu")
		(net "SVID_CPU_DATA")
	)
	(segment
		(start 67.182238 -67.691762)
		(end 67.437 -67.437)
		(width 0.0889)
		(layer "In7.Cu")
		(net "SVID_CPU_DATA")
	)
	(segment
		(start 67.437 -67.437)
		(end 67.68973 -67.437)
		(width 0.0889)
		(layer "In7.Cu")
		(net "SVID_CPU_DATA")
	)
	(segment
		(start 15.3289 -65.69583)
		(end 15.7099 -65.69583)
		(width 0.0889)
		(layer "In7.Cu")
		(net "SVID_CPU_DATA")
	)
	(segment
		(start 69.21373 -65.913)
		(end 69.54393 -65.5828)
		(width 0.0889)
		(layer "In7.Cu")
		(net "SVID_CPU_DATA")
	)
	(segment
		(start 44.704 -70.739)
		(end 44.704 -70.612)
		(width 0.0889)
		(layer "In7.Cu")
		(net "SVID_CPU_DATA")
	)
	(segment
		(start 67.944238 -67.182492)
		(end 67.944238 -66.802762)
		(width 0.0889)
		(layer "In7.Cu")
		(net "SVID_CPU_DATA")
	)
	(segment
		(start 66.07683 -69.0499)
		(end 66.251328 -68.875402)
		(width 0.0889)
		(layer "In7.Cu")
		(net "SVID_CPU_DATA")
	)
	(segment
		(start 67.68973 -67.437)
		(end 67.944238 -67.182492)
		(width 0.0889)
		(layer "In7.Cu")
		(net "SVID_CPU_DATA")
	)
	(segment
		(start 66.421 -68.326)
		(end 66.80073 -68.326)
		(width 0.0889)
		(layer "In7.Cu")
		(net "SVID_CPU_DATA")
	)
	(segment
		(start 15.7988 -65.78473)
		(end 15.7988 -67.2084)
		(width 0.0889)
		(layer "In7.Cu")
		(net "SVID_CPU_DATA")
	)
	(segment
		(start 67.944238 -66.802762)
		(end 68.072 -66.675)
		(width 0.0889)
		(layer "In7.Cu")
		(net "SVID_CPU_DATA")
	)
	(segment
		(start 44.849034 -70.466966)
		(end 45.066966 -70.466966)
		(width 0.0889)
		(layer "In7.Cu")
		(net "SVID_CPU_DATA")
	)
	(segment
		(start 45.517308 -70.21957)
		(end 45.401738 -70.104)
		(width 0.0889)
		(layer "In7.Cu")
		(net "SVID_CPU_DATA")
	)
	(segment
		(start 15.7988 -64.9732)
		(end 15.621 -65.151)
		(width 0.0889)
		(layer "In7.Cu")
		(net "SVID_CPU_DATA")
	)
	(segment
		(start 46.089062 -69.203316)
		(end 46.242478 -69.0499)
		(width 0.0889)
		(layer "In7.Cu")
		(net "SVID_CPU_DATA")
	)
	(segment
		(start 45.212 -70.612)
		(end 45.309282 -70.612)
		(width 0.0889)
		(layer "In7.Cu")
		(net "SVID_CPU_DATA")
	)
	(segment
		(start 46.242478 -69.0499)
		(end 66.07683 -69.0499)
		(width 0.0889)
		(layer "In7.Cu")
		(net "SVID_CPU_DATA")
	)
	(segment
		(start 15.7099 -65.69583)
		(end 15.7988 -65.78473)
		(width 0.0889)
		(layer "In7.Cu")
		(net "SVID_CPU_DATA")
	)
	(segment
		(start 66.80073 -68.326)
		(end 67.182238 -67.944492)
		(width 0.0889)
		(layer "In7.Cu")
		(net "SVID_CPU_DATA")
	)
	(segment
		(start 45.066966 -70.466966)
		(end 45.212 -70.612)
		(width 0.0889)
		(layer "In7.Cu")
		(net "SVID_CPU_DATA")
	)
	(segment
		(start 15.7988 -64.773302)
		(end 15.7988 -64.9732)
		(width 0.0889)
		(layer "In7.Cu")
		(net "SVID_CPU_DATA")
	)
	(segment
		(start 45.784262 -69.85)
		(end 45.950124 -69.85)
		(width 0.0889)
		(layer "In7.Cu")
		(net "SVID_CPU_DATA")
	)
	(segment
		(start 15.3289 -65.151)
		(end 15.24 -65.2399)
		(width 0.0889)
		(layer "In7.Cu")
		(net "SVID_CPU_DATA")
	)
	(segment
		(start 44.825412 -71.09587)
		(end 44.825412 -70.860412)
		(width 0.0889)
		(layer "In7.Cu")
		(net "SVID_CPU_DATA")
	)
	(segment
		(start 68.706238 -66.420492)
		(end 68.706238 -66.040762)
		(width 0.0889)
		(layer "In7.Cu")
		(net "SVID_CPU_DATA")
	)
	(segment
		(start 45.517308 -70.403974)
		(end 45.517308 -70.21957)
		(width 0.0889)
		(layer "In7.Cu")
		(net "SVID_CPU_DATA")
	)
	(segment
		(start 45.401738 -69.914262)
		(end 45.530262 -69.785738)
		(width 0.0889)
		(layer "In7.Cu")
		(net "SVID_CPU_DATA")
	)
	(segment
		(start 159.84982 -9.897364)
		(end 159.84982 -8.416798)
		(width 0.2413)
		(layer "F.Cu")
		(net "M_B_MA7")
	)
	(segment
		(start 158.84652 -7.413498)
		(end 158.84652 -5.494528)
		(width 0.2413)
		(layer "F.Cu")
		(net "M_B_MA7")
	)
	(segment
		(start 101.577648 -29.997654)
		(end 101.577648 -30.070806)
		(width 0.1016)
		(layer "F.Cu")
		(net "M_B_MA7")
	)
	(segment
		(start 159.84982 -8.416798)
		(end 158.84652 -7.413498)
		(width 0.2413)
		(layer "F.Cu")
		(net "M_B_MA7")
	)
	(segment
		(start 101.577648 -30.070806)
		(end 101.894386 -30.387544)
		(width 0.1016)
		(layer "F.Cu")
		(net "M_B_MA7")
	)
	(segment
		(start 158.84652 -5.494528)
		(end 159.23387 -5.107178)
		(width 0.2413)
		(layer "F.Cu")
		(net "M_B_MA7")
	)
	(segment
		(start 159.23387 -5.107178)
		(end 159.265874 -5.107178)
		(width 0.2413)
		(layer "F.Cu")
		(net "M_B_MA7")
	)
	(segment
		(start 159.265874 -5.107178)
		(end 159.316674 -5.056378)
		(width 0.2413)
		(layer "F.Cu")
		(net "M_B_MA7")
	)
	(via
		(at 159.316674 -5.056378)
		(size 0.4318)
		(drill 0.2032)
		(layers "F.Cu" "B.Cu")
		(net "M_B_MA7")
	)
	(via
		(at 101.894386 -30.387544)
		(size 0.4318)
		(drill 0.2032)
		(layers "F.Cu" "B.Cu")
		(net "M_B_MA7")
	)
	(segment
		(start 159.34055 -5.056378)
		(end 159.316674 -5.056378)
		(width 0.2413)
		(layer "B.Cu")
		(net "M_B_MA7")
	)
	(segment
		(start 159.84982 -4.547108)
		(end 159.34055 -5.056378)
		(width 0.2413)
		(layer "B.Cu")
		(net "M_B_MA7")
	)
	(segment
		(start 159.84982 -1.690624)
		(end 159.84982 -4.547108)
		(width 0.2413)
		(layer "B.Cu")
		(net "M_B_MA7")
	)
	(segment
		(start 159.316674 -5.060188)
		(end 158.87192 -5.504942)
		(width 0.1905)
		(layer "In7.Cu")
		(net "M_B_MA7")
	)
	(segment
		(start 146.05 -18.440146)
		(end 145.529046 -18.9611)
		(width 0.1905)
		(layer "In7.Cu")
		(net "M_B_MA7")
	)
	(segment
		(start 157.9753 -9.943846)
		(end 149.479254 -18.440146)
		(width 0.1905)
		(layer "In7.Cu")
		(net "M_B_MA7")
	)
	(segment
		(start 125.052328 -18.630646)
		(end 125.052328 -18.7706)
		(width 0.1905)
		(layer "In7.Cu")
		(net "M_B_MA7")
	)
	(segment
		(start 132.468112 -18.9611)
		(end 132.087112 -18.9611)
		(width 0.1905)
		(layer "In7.Cu")
		(net "M_B_MA7")
	)
	(segment
		(start 145.529046 -18.9611)
		(end 139.5349 -18.9611)
		(width 0.1905)
		(layer "In7.Cu")
		(net "M_B_MA7")
	)
	(segment
		(start 130.372612 -18.7706)
		(end 130.372612 -18.630646)
		(width 0.1905)
		(layer "In7.Cu")
		(net "M_B_MA7")
	)
	(segment
		(start 124.099828 -18.440146)
		(end 123.718828 -18.440146)
		(width 0.1905)
		(layer "In7.Cu")
		(net "M_B_MA7")
	)
	(segment
		(start 121.432828 -18.9611)
		(end 121.242328 -18.7706)
		(width 0.1905)
		(layer "In7.Cu")
		(net "M_B_MA7")
	)
	(segment
		(start 121.813828 -18.9611)
		(end 121.432828 -18.9611)
		(width 0.1905)
		(layer "In7.Cu")
		(net "M_B_MA7")
	)
	(segment
		(start 101.5746 -29.8958)
		(end 101.5746 -28.3972)
		(width 0.1016)
		(layer "In7.Cu")
		(net "M_B_MA7")
	)
	(segment
		(start 121.051828 -18.440146)
		(end 116.075714 -18.440146)
		(width 0.1905)
		(layer "In7.Cu")
		(net "M_B_MA7")
	)
	(segment
		(start 122.766328 -18.7706)
		(end 122.766328 -18.630646)
		(width 0.1905)
		(layer "In7.Cu")
		(net "M_B_MA7")
	)
	(segment
		(start 123.528328 -18.7706)
		(end 123.337828 -18.9611)
		(width 0.1905)
		(layer "In7.Cu")
		(net "M_B_MA7")
	)
	(segment
		(start 123.718828 -18.440146)
		(end 123.528328 -18.630646)
		(width 0.1905)
		(layer "In7.Cu")
		(net "M_B_MA7")
	)
	(segment
		(start 122.956828 -18.9611)
		(end 122.766328 -18.7706)
		(width 0.1905)
		(layer "In7.Cu")
		(net "M_B_MA7")
	)
	(segment
		(start 124.480828 -18.9611)
		(end 124.290328 -18.7706)
		(width 0.1905)
		(layer "In7.Cu")
		(net "M_B_MA7")
	)
	(segment
		(start 131.896612 -18.630646)
		(end 131.706112 -18.440146)
		(width 0.1905)
		(layer "In7.Cu")
		(net "M_B_MA7")
	)
	(segment
		(start 124.290328 -18.630646)
		(end 124.099828 -18.440146)
		(width 0.1905)
		(layer "In7.Cu")
		(net "M_B_MA7")
	)
	(segment
		(start 134.182612 -18.7706)
		(end 133.992112 -18.9611)
		(width 0.1905)
		(layer "In7.Cu")
		(net "M_B_MA7")
	)
	(segment
		(start 116.075714 -18.440146)
		(end 111.77143 -22.74443)
		(width 0.1905)
		(layer "In7.Cu")
		(net "M_B_MA7")
	)
	(segment
		(start 122.766328 -18.630646)
		(end 122.575828 -18.440146)
		(width 0.1905)
		(layer "In7.Cu")
		(net "M_B_MA7")
	)
	(segment
		(start 139.5349 -18.9611)
		(end 139.013946 -18.440146)
		(width 0.1905)
		(layer "In7.Cu")
		(net "M_B_MA7")
	)
	(segment
		(start 159.316674 -5.056378)
		(end 159.316674 -5.060188)
		(width 0.1905)
		(layer "In7.Cu")
		(net "M_B_MA7")
	)
	(segment
		(start 132.658612 -18.630646)
		(end 132.658612 -18.7706)
		(width 0.1905)
		(layer "In7.Cu")
		(net "M_B_MA7")
	)
	(segment
		(start 132.849112 -18.440146)
		(end 132.658612 -18.630646)
		(width 0.1905)
		(layer "In7.Cu")
		(net "M_B_MA7")
	)
	(segment
		(start 107.7722 -23.6728)
		(end 108.1024 -23.3426)
		(width 0.1016)
		(layer "In7.Cu")
		(net "M_B_MA7")
	)
	(segment
		(start 105.276904 -26.9748)
		(end 106.68 -25.571704)
		(width 0.1016)
		(layer "In7.Cu")
		(net "M_B_MA7")
	)
	(segment
		(start 133.420612 -18.7706)
		(end 133.420612 -18.630646)
		(width 0.1905)
		(layer "In7.Cu")
		(net "M_B_MA7")
	)
	(segment
		(start 102.997 -26.9748)
		(end 105.276904 -26.9748)
		(width 0.1016)
		(layer "In7.Cu")
		(net "M_B_MA7")
	)
	(segment
		(start 125.242828 -18.440146)
		(end 125.052328 -18.630646)
		(width 0.1905)
		(layer "In7.Cu")
		(net "M_B_MA7")
	)
	(segment
		(start 131.706112 -18.440146)
		(end 131.325112 -18.440146)
		(width 0.1905)
		(layer "In7.Cu")
		(net "M_B_MA7")
	)
	(segment
		(start 134.182612 -18.630646)
		(end 134.182612 -18.7706)
		(width 0.1905)
		(layer "In7.Cu")
		(net "M_B_MA7")
	)
	(segment
		(start 158.87192 -5.504942)
		(end 158.87192 -7.032498)
		(width 0.1905)
		(layer "In7.Cu")
		(net "M_B_MA7")
	)
	(segment
		(start 123.528328 -18.630646)
		(end 123.528328 -18.7706)
		(width 0.1905)
		(layer "In7.Cu")
		(net "M_B_MA7")
	)
	(segment
		(start 101.894386 -30.215586)
		(end 101.5746 -29.8958)
		(width 0.1016)
		(layer "In7.Cu")
		(net "M_B_MA7")
	)
	(segment
		(start 133.611112 -18.9611)
		(end 133.420612 -18.7706)
		(width 0.1905)
		(layer "In7.Cu")
		(net "M_B_MA7")
	)
	(segment
		(start 139.013946 -18.440146)
		(end 134.373112 -18.440146)
		(width 0.1905)
		(layer "In7.Cu")
		(net "M_B_MA7")
	)
	(segment
		(start 101.894386 -30.387544)
		(end 101.894386 -30.215586)
		(width 0.1016)
		(layer "In7.Cu")
		(net "M_B_MA7")
	)
	(segment
		(start 132.658612 -18.7706)
		(end 132.468112 -18.9611)
		(width 0.1905)
		(layer "In7.Cu")
		(net "M_B_MA7")
	)
	(segment
		(start 131.325112 -18.440146)
		(end 131.134612 -18.630646)
		(width 0.1905)
		(layer "In7.Cu")
		(net "M_B_MA7")
	)
	(segment
		(start 111.77143 -22.74697)
		(end 111.1758 -23.3426)
		(width 0.1905)
		(layer "In7.Cu")
		(net "M_B_MA7")
	)
	(segment
		(start 133.420612 -18.630646)
		(end 133.230112 -18.440146)
		(width 0.1905)
		(layer "In7.Cu")
		(net "M_B_MA7")
	)
	(segment
		(start 134.373112 -18.440146)
		(end 134.182612 -18.630646)
		(width 0.1905)
		(layer "In7.Cu")
		(net "M_B_MA7")
	)
	(segment
		(start 111.1758 -23.3426)
		(end 108.1024 -23.3426)
		(width 0.1905)
		(layer "In7.Cu")
		(net "M_B_MA7")
	)
	(segment
		(start 130.563112 -18.9611)
		(end 130.372612 -18.7706)
		(width 0.1905)
		(layer "In7.Cu")
		(net "M_B_MA7")
	)
	(segment
		(start 131.134612 -18.7706)
		(end 130.944112 -18.9611)
		(width 0.1905)
		(layer "In7.Cu")
		(net "M_B_MA7")
	)
	(segment
		(start 122.004328 -18.7706)
		(end 121.813828 -18.9611)
		(width 0.1905)
		(layer "In7.Cu")
		(net "M_B_MA7")
	)
	(segment
		(start 130.944112 -18.9611)
		(end 130.563112 -18.9611)
		(width 0.1905)
		(layer "In7.Cu")
		(net "M_B_MA7")
	)
	(segment
		(start 133.992112 -18.9611)
		(end 133.611112 -18.9611)
		(width 0.1905)
		(layer "In7.Cu")
		(net "M_B_MA7")
	)
	(segment
		(start 158.87192 -7.032498)
		(end 157.9753 -7.929118)
		(width 0.1905)
		(layer "In7.Cu")
		(net "M_B_MA7")
	)
	(segment
		(start 122.194828 -18.440146)
		(end 122.004328 -18.630646)
		(width 0.1905)
		(layer "In7.Cu")
		(net "M_B_MA7")
	)
	(segment
		(start 130.182112 -18.440146)
		(end 125.242828 -18.440146)
		(width 0.1905)
		(layer "In7.Cu")
		(net "M_B_MA7")
	)
	(segment
		(start 106.68 -24.078946)
		(end 107.086146 -23.6728)
		(width 0.1016)
		(layer "In7.Cu")
		(net "M_B_MA7")
	)
	(segment
		(start 124.290328 -18.7706)
		(end 124.290328 -18.630646)
		(width 0.1905)
		(layer "In7.Cu")
		(net "M_B_MA7")
	)
	(segment
		(start 122.575828 -18.440146)
		(end 122.194828 -18.440146)
		(width 0.1905)
		(layer "In7.Cu")
		(net "M_B_MA7")
	)
	(segment
		(start 106.68 -25.571704)
		(end 106.68 -24.078946)
		(width 0.1016)
		(layer "In7.Cu")
		(net "M_B_MA7")
	)
	(segment
		(start 107.086146 -23.6728)
		(end 107.7722 -23.6728)
		(width 0.1016)
		(layer "In7.Cu")
		(net "M_B_MA7")
	)
	(segment
		(start 157.9753 -7.929118)
		(end 157.9753 -9.943846)
		(width 0.1905)
		(layer "In7.Cu")
		(net "M_B_MA7")
	)
	(segment
		(start 149.479254 -18.440146)
		(end 146.05 -18.440146)
		(width 0.1905)
		(layer "In7.Cu")
		(net "M_B_MA7")
	)
	(segment
		(start 124.861828 -18.9611)
		(end 124.480828 -18.9611)
		(width 0.1905)
		(layer "In7.Cu")
		(net "M_B_MA7")
	)
	(segment
		(start 125.052328 -18.7706)
		(end 124.861828 -18.9611)
		(width 0.1905)
		(layer "In7.Cu")
		(net "M_B_MA7")
	)
	(segment
		(start 132.087112 -18.9611)
		(end 131.896612 -18.7706)
		(width 0.1905)
		(layer "In7.Cu")
		(net "M_B_MA7")
	)
	(segment
		(start 131.896612 -18.7706)
		(end 131.896612 -18.630646)
		(width 0.1905)
		(layer "In7.Cu")
		(net "M_B_MA7")
	)
	(segment
		(start 122.004328 -18.630646)
		(end 122.004328 -18.7706)
		(width 0.1905)
		(layer "In7.Cu")
		(net "M_B_MA7")
	)
	(segment
		(start 121.242328 -18.7706)
		(end 121.242328 -18.630646)
		(width 0.1905)
		(layer "In7.Cu")
		(net "M_B_MA7")
	)
	(segment
		(start 131.134612 -18.630646)
		(end 131.134612 -18.7706)
		(width 0.1905)
		(layer "In7.Cu")
		(net "M_B_MA7")
	)
	(segment
		(start 121.242328 -18.630646)
		(end 121.051828 -18.440146)
		(width 0.1905)
		(layer "In7.Cu")
		(net "M_B_MA7")
	)
	(segment
		(start 101.5746 -28.3972)
		(end 102.997 -26.9748)
		(width 0.1016)
		(layer "In7.Cu")
		(net "M_B_MA7")
	)
	(segment
		(start 133.230112 -18.440146)
		(end 132.849112 -18.440146)
		(width 0.1905)
		(layer "In7.Cu")
		(net "M_B_MA7")
	)
	(segment
		(start 130.372612 -18.630646)
		(end 130.182112 -18.440146)
		(width 0.1905)
		(layer "In7.Cu")
		(net "M_B_MA7")
	)
	(segment
		(start 111.77143 -22.74443)
		(end 111.77143 -22.74697)
		(width 0.1905)
		(layer "In7.Cu")
		(net "M_B_MA7")
	)
	(segment
		(start 123.337828 -18.9611)
		(end 122.956828 -18.9611)
		(width 0.1905)
		(layer "In7.Cu")
		(net "M_B_MA7")
	)
	(segment
		(start 200.1012 -46.5074)
		(end 201.1807 -46.5074)
		(width 0.2032)
		(layer "F.Cu")
		(net "VR_PVDDRA_R_ISUMN1")
	)
	(segment
		(start 201.1807 -46.5074)
		(end 201.3712 -46.6979)
		(width 0.2032)
		(layer "F.Cu")
		(net "VR_PVDDRA_R_ISUMN1")
	)
	(segment
		(start 200.0504 -46.5582)
		(end 200.1012 -46.5074)
		(width 0.2032)
		(layer "F.Cu")
		(net "VR_PVDDRA_R_ISUMN1")
	)
	(via
		(at 200.0504 -46.5582)
		(size 0.508)
		(drill 0.254)
		(layers "F.Cu" "B.Cu")
		(net "VR_PVDDRA_R_ISUMN1")
	)
	(via
		(at 187.96 -24.384)
		(size 0.7112)
		(drill 0.3556)
		(layers "F.Cu" "B.Cu")
		(net "VR_PVDDRA_R_ISUMN1")
	)
	(via
		(at 192.764664 -26.4795)
		(size 0.508)
		(drill 0.254)
		(layers "F.Cu" "B.Cu")
		(net "VR_PVDDRA_R_ISUMN1")
	)
	(segment
		(start 186.999626 -24.384)
		(end 187.96 -24.384)
		(width 0.2032)
		(layer "B.Cu")
		(net "VR_PVDDRA_R_ISUMN1")
	)
	(segment
		(start 186.4868 -24.896826)
		(end 186.999626 -24.384)
		(width 0.2032)
		(layer "B.Cu")
		(net "VR_PVDDRA_R_ISUMN1")
	)
	(segment
		(start 186.4868 -25.6794)
		(end 186.4868 -24.896826)
		(width 0.2032)
		(layer "B.Cu")
		(net "VR_PVDDRA_R_ISUMN1")
	)
	(segment
		(start 190.885572 -24.384)
		(end 192.764664 -26.263092)
		(width 0.2032)
		(layer "B.Cu")
		(net "VR_PVDDRA_R_ISUMN1")
	)
	(segment
		(start 186.1312 -26.035)
		(end 186.4868 -25.6794)
		(width 0.2032)
		(layer "B.Cu")
		(net "VR_PVDDRA_R_ISUMN1")
	)
	(segment
		(start 187.96 -24.384)
		(end 190.885572 -24.384)
		(width 0.2032)
		(layer "B.Cu")
		(net "VR_PVDDRA_R_ISUMN1")
	)
	(segment
		(start 192.764664 -26.263092)
		(end 192.764664 -26.4795)
		(width 0.2032)
		(layer "B.Cu")
		(net "VR_PVDDRA_R_ISUMN1")
	)
	(segment
		(start 197.7644 -46.355)
		(end 196.85 -45.4406)
		(width 0.2032)
		(layer "In7.Cu")
		(net "VR_PVDDRA_R_ISUMN1")
	)
	(segment
		(start 193.421 -27.135836)
		(end 192.764664 -26.4795)
		(width 0.2032)
		(layer "In7.Cu")
		(net "VR_PVDDRA_R_ISUMN1")
	)
	(segment
		(start 196.85 -32.925766)
		(end 193.421 -29.496766)
		(width 0.2032)
		(layer "In7.Cu")
		(net "VR_PVDDRA_R_ISUMN1")
	)
	(segment
		(start 199.8472 -46.355)
		(end 197.7644 -46.355)
		(width 0.2032)
		(layer "In7.Cu")
		(net "VR_PVDDRA_R_ISUMN1")
	)
	(segment
		(start 200.0504 -46.5582)
		(end 199.8472 -46.355)
		(width 0.2032)
		(layer "In7.Cu")
		(net "VR_PVDDRA_R_ISUMN1")
	)
	(segment
		(start 193.421 -29.496766)
		(end 193.421 -27.135836)
		(width 0.2032)
		(layer "In7.Cu")
		(net "VR_PVDDRA_R_ISUMN1")
	)
	(segment
		(start 196.85 -45.4406)
		(end 196.85 -32.925766)
		(width 0.2032)
		(layer "In7.Cu")
		(net "VR_PVDDRA_R_ISUMN1")
	)
	(segment
		(start 139.573 -8.586978)
		(end 139.573 -8.028178)
		(width 0.1778)
		(layer "F.Cu")
		(net "M_B_DQ16")
	)
	(segment
		(start 100.1014 -25.146)
		(end 100.379276 -25.146)
		(width 0.1016)
		(layer "F.Cu")
		(net "M_B_DQ16")
	)
	(segment
		(start 140.050012 -9.897364)
		(end 140.050012 -9.06399)
		(width 0.1778)
		(layer "F.Cu")
		(net "M_B_DQ16")
	)
	(segment
		(start 100.379276 -25.146)
		(end 101.011228 -25.777952)
		(width 0.1016)
		(layer "F.Cu")
		(net "M_B_DQ16")
	)
	(segment
		(start 101.135688 -26.745946)
		(end 101.135688 -27.447494)
		(width 0.1016)
		(layer "F.Cu")
		(net "M_B_DQ16")
	)
	(segment
		(start 100.909628 -26.519886)
		(end 101.135688 -26.745946)
		(width 0.1016)
		(layer "F.Cu")
		(net "M_B_DQ16")
	)
	(segment
		(start 101.011228 -25.777952)
		(end 101.011228 -26.165302)
		(width 0.1016)
		(layer "F.Cu")
		(net "M_B_DQ16")
	)
	(segment
		(start 100.909628 -26.266902)
		(end 100.909628 -26.519886)
		(width 0.1016)
		(layer "F.Cu")
		(net "M_B_DQ16")
	)
	(segment
		(start 101.011228 -26.165302)
		(end 100.909628 -26.266902)
		(width 0.1016)
		(layer "F.Cu")
		(net "M_B_DQ16")
	)
	(segment
		(start 140.050012 -9.06399)
		(end 139.573 -8.586978)
		(width 0.1778)
		(layer "F.Cu")
		(net "M_B_DQ16")
	)
	(via
		(at 100.1014 -25.146)
		(size 0.4318)
		(drill 0.2032)
		(layers "F.Cu" "B.Cu")
		(net "M_B_DQ16")
	)
	(via
		(at 139.573 -8.028178)
		(size 0.4318)
		(drill 0.2032)
		(layers "F.Cu" "B.Cu")
		(net "M_B_DQ16")
	)
	(segment
		(start 139.149836 -8.923528)
		(end 139.5476 -8.525764)
		(width 0.1778)
		(layer "B.Cu")
		(net "M_B_DQ16")
	)
	(segment
		(start 139.149836 -9.89076)
		(end 139.149836 -8.923528)
		(width 0.1778)
		(layer "B.Cu")
		(net "M_B_DQ16")
	)
	(segment
		(start 139.5476 -8.525764)
		(end 139.5476 -8.053578)
		(width 0.1778)
		(layer "B.Cu")
		(net "M_B_DQ16")
	)
	(segment
		(start 139.5476 -8.053578)
		(end 139.573 -8.028178)
		(width 0.1778)
		(layer "B.Cu")
		(net "M_B_DQ16")
	)
	(segment
		(start 133.6294 -11.2649)
		(end 133.477 -11.1125)
		(width 0.1524)
		(layer "In4.Cu")
		(net "M_B_DQ16")
	)
	(segment
		(start 114.841528 -10.4394)
		(end 109.228128 -16.0528)
		(width 0.1524)
		(layer "In4.Cu")
		(net "M_B_DQ16")
	)
	(segment
		(start 132.8674 -11.1125)
		(end 132.715 -11.2649)
		(width 0.1524)
		(layer "In4.Cu")
		(net "M_B_DQ16")
	)
	(segment
		(start 134.4676 -9.906)
		(end 134.3152 -10.0584)
		(width 0.1524)
		(layer "In4.Cu")
		(net "M_B_DQ16")
	)
	(segment
		(start 132.4102 -11.2649)
		(end 132.2578 -11.1125)
		(width 0.1524)
		(layer "In4.Cu")
		(net "M_B_DQ16")
	)
	(segment
		(start 132.715 -11.2649)
		(end 132.4102 -11.2649)
		(width 0.1524)
		(layer "In4.Cu")
		(net "M_B_DQ16")
	)
	(segment
		(start 134.3152 -11.1125)
		(end 134.1628 -11.2649)
		(width 0.1524)
		(layer "In4.Cu")
		(net "M_B_DQ16")
	)
	(segment
		(start 109.228128 -16.0528)
		(end 103.63327 -16.0528)
		(width 0.1524)
		(layer "In4.Cu")
		(net "M_B_DQ16")
	)
	(segment
		(start 124.4727 -11.2649)
		(end 123.6472 -10.4394)
		(width 0.1524)
		(layer "In4.Cu")
		(net "M_B_DQ16")
	)
	(segment
		(start 134.3152 -10.0584)
		(end 134.3152 -11.1125)
		(width 0.1524)
		(layer "In4.Cu")
		(net "M_B_DQ16")
	)
	(segment
		(start 103.63327 -16.0528)
		(end 100.0506 -19.63547)
		(width 0.1524)
		(layer "In4.Cu")
		(net "M_B_DQ16")
	)
	(segment
		(start 133.477 -11.1125)
		(end 133.477 -10.4394)
		(width 0.1524)
		(layer "In4.Cu")
		(net "M_B_DQ16")
	)
	(segment
		(start 131.8006 -10.2362)
		(end 131.6482 -10.3886)
		(width 0.1524)
		(layer "In4.Cu")
		(net "M_B_DQ16")
	)
	(segment
		(start 134.1628 -11.2649)
		(end 133.6294 -11.2649)
		(width 0.1524)
		(layer "In4.Cu")
		(net "M_B_DQ16")
	)
	(segment
		(start 131.4958 -11.2649)
		(end 124.4727 -11.2649)
		(width 0.1524)
		(layer "In4.Cu")
		(net "M_B_DQ16")
	)
	(segment
		(start 139.573 -8.028178)
		(end 139.5476 -8.053578)
		(width 0.1524)
		(layer "In4.Cu")
		(net "M_B_DQ16")
	)
	(segment
		(start 99.695 -24.7396)
		(end 100.1014 -25.146)
		(width 0.1016)
		(layer "In4.Cu")
		(net "M_B_DQ16")
	)
	(segment
		(start 139.5476 -9.3218)
		(end 138.9634 -9.906)
		(width 0.1524)
		(layer "In4.Cu")
		(net "M_B_DQ16")
	)
	(segment
		(start 99.695 -19.99107)
		(end 99.695 -24.7396)
		(width 0.1016)
		(layer "In4.Cu")
		(net "M_B_DQ16")
	)
	(segment
		(start 133.477 -10.4394)
		(end 133.3246 -10.287)
		(width 0.1524)
		(layer "In4.Cu")
		(net "M_B_DQ16")
	)
	(segment
		(start 132.2578 -10.3886)
		(end 132.1054 -10.2362)
		(width 0.1524)
		(layer "In4.Cu")
		(net "M_B_DQ16")
	)
	(segment
		(start 132.1054 -10.2362)
		(end 131.8006 -10.2362)
		(width 0.1524)
		(layer "In4.Cu")
		(net "M_B_DQ16")
	)
	(segment
		(start 123.6472 -10.4394)
		(end 114.841528 -10.4394)
		(width 0.1524)
		(layer "In4.Cu")
		(net "M_B_DQ16")
	)
	(segment
		(start 138.9634 -9.906)
		(end 134.4676 -9.906)
		(width 0.1524)
		(layer "In4.Cu")
		(net "M_B_DQ16")
	)
	(segment
		(start 133.3246 -10.287)
		(end 133.0198 -10.287)
		(width 0.1524)
		(layer "In4.Cu")
		(net "M_B_DQ16")
	)
	(segment
		(start 133.0198 -10.287)
		(end 132.8674 -10.4394)
		(width 0.1524)
		(layer "In4.Cu")
		(net "M_B_DQ16")
	)
	(segment
		(start 100.0506 -19.63547)
		(end 99.695 -19.99107)
		(width 0.1016)
		(layer "In4.Cu")
		(net "M_B_DQ16")
	)
	(segment
		(start 132.2578 -11.1125)
		(end 132.2578 -10.3886)
		(width 0.1524)
		(layer "In4.Cu")
		(net "M_B_DQ16")
	)
	(segment
		(start 132.8674 -10.4394)
		(end 132.8674 -11.1125)
		(width 0.1524)
		(layer "In4.Cu")
		(net "M_B_DQ16")
	)
	(segment
		(start 131.6482 -10.3886)
		(end 131.6482 -11.1125)
		(width 0.1524)
		(layer "In4.Cu")
		(net "M_B_DQ16")
	)
	(segment
		(start 139.5476 -8.053578)
		(end 139.5476 -9.3218)
		(width 0.1524)
		(layer "In4.Cu")
		(net "M_B_DQ16")
	)
	(segment
		(start 131.6482 -11.1125)
		(end 131.4958 -11.2649)
		(width 0.1524)
		(layer "In4.Cu")
		(net "M_B_DQ16")
	)
	(segment
		(start 88.265 -43.038522)
		(end 88.265 -43.053)
		(width 0.1143)
		(layer "F.Cu")
		(net "PD_USB_OBSP")
	)
	(segment
		(start 88.600788 -42.702734)
		(end 88.265 -43.038522)
		(width 0.1143)
		(layer "F.Cu")
		(net "PD_USB_OBSP")
	)
	(via
		(at 88.265 -43.053)
		(size 0.4318)
		(drill 0.2032)
		(layers "F.Cu" "B.Cu")
		(net "PD_USB_OBSP")
	)
	(via
		(at 87.043768 -45.093636)
		(size 0.7112)
		(drill 0.3556)
		(layers "F.Cu" "B.Cu")
		(net "PD_USB_OBSP")
	)
	(segment
		(start 87.043768 -45.620432)
		(end 86.6902 -45.974)
		(width 0.1143)
		(layer "B.Cu")
		(net "PD_USB_OBSP")
	)
	(segment
		(start 87.939372 -43.053)
		(end 88.265 -43.053)
		(width 0.1143)
		(layer "B.Cu")
		(net "PD_USB_OBSP")
	)
	(segment
		(start 86.98865 -45.038518)
		(end 86.98865 -43.73499)
		(width 0.1143)
		(layer "B.Cu")
		(net "PD_USB_OBSP")
	)
	(segment
		(start 87.043768 -45.093636)
		(end 86.98865 -45.038518)
		(width 0.1143)
		(layer "B.Cu")
		(net "PD_USB_OBSP")
	)
	(segment
		(start 86.98865 -43.73499)
		(end 87.304626 -43.419014)
		(width 0.1143)
		(layer "B.Cu")
		(net "PD_USB_OBSP")
	)
	(segment
		(start 87.573358 -43.419014)
		(end 87.939372 -43.053)
		(width 0.1143)
		(layer "B.Cu")
		(net "PD_USB_OBSP")
	)
	(segment
		(start 87.304626 -43.419014)
		(end 87.573358 -43.419014)
		(width 0.1143)
		(layer "B.Cu")
		(net "PD_USB_OBSP")
	)
	(segment
		(start 87.043768 -45.093636)
		(end 87.043768 -45.620432)
		(width 0.1143)
		(layer "B.Cu")
		(net "PD_USB_OBSP")
	)
	(segment
		(start 186.9186 -25.019)
		(end 187.1726 -25.019)
		(width 0.2032)
		(layer "F.Cu")
		(net "VR_PVDDRA_ISUMN1")
	)
	(segment
		(start 189.3824 -28.2194)
		(end 189.3824 -28.4226)
		(width 0.2032)
		(layer "F.Cu")
		(net "VR_PVDDRA_ISUMN1")
	)
	(segment
		(start 186.0042 -25.9334)
		(end 186.9186 -25.019)
		(width 0.2032)
		(layer "F.Cu")
		(net "VR_PVDDRA_ISUMN1")
	)
	(segment
		(start 189.3824 -28.4226)
		(end 190.1952 -29.2354)
		(width 0.2032)
		(layer "F.Cu")
		(net "VR_PVDDRA_ISUMN1")
	)
	(segment
		(start 190.1952 -29.2354)
		(end 190.1952 -29.4132)
		(width 0.2032)
		(layer "F.Cu")
		(net "VR_PVDDRA_ISUMN1")
	)
	(via
		(at 190.1952 -29.4132)
		(size 0.508)
		(drill 0.254)
		(layers "F.Cu" "B.Cu")
		(net "VR_PVDDRA_ISUMN1")
	)
	(via
		(at 187.9346 -25.7556)
		(size 0.7112)
		(drill 0.3556)
		(layers "F.Cu" "B.Cu")
		(net "VR_PVDDRA_ISUMN1")
	)
	(via
		(at 187.1726 -25.019)
		(size 0.508)
		(drill 0.254)
		(layers "F.Cu" "B.Cu")
		(net "VR_PVDDRA_ISUMN1")
	)
	(segment
		(start 189.357 -28.575)
		(end 190.1952 -29.4132)
		(width 0.2032)
		(layer "B.Cu")
		(net "VR_PVDDRA_ISUMN1")
	)
	(segment
		(start 187.9346 -25.7556)
		(end 187.9346 -25.4508)
		(width 0.2032)
		(layer "B.Cu")
		(net "VR_PVDDRA_ISUMN1")
	)
	(segment
		(start 189.357 -28.3718)
		(end 189.357 -28.575)
		(width 0.2032)
		(layer "B.Cu")
		(net "VR_PVDDRA_ISUMN1")
	)
	(segment
		(start 188.595 -28.3718)
		(end 189.357 -28.3718)
		(width 0.2032)
		(layer "B.Cu")
		(net "VR_PVDDRA_ISUMN1")
	)
	(segment
		(start 188.595 -28.3718)
		(end 187.833 -27.6098)
		(width 0.2032)
		(layer "B.Cu")
		(net "VR_PVDDRA_ISUMN1")
	)
	(segment
		(start 187.0964 -27.6098)
		(end 186.9948 -27.5082)
		(width 0.2032)
		(layer "B.Cu")
		(net "VR_PVDDRA_ISUMN1")
	)
	(segment
		(start 187.6552 -26.035)
		(end 186.9948 -26.035)
		(width 0.2032)
		(layer "B.Cu")
		(net "VR_PVDDRA_ISUMN1")
	)
	(segment
		(start 187.833 -27.6098)
		(end 187.7822 -27.6098)
		(width 0.2032)
		(layer "B.Cu")
		(net "VR_PVDDRA_ISUMN1")
	)
	(segment
		(start 187.0964 -27.6098)
		(end 187.7822 -27.6098)
		(width 0.2032)
		(layer "B.Cu")
		(net "VR_PVDDRA_ISUMN1")
	)
	(segment
		(start 186.9948 -27.5082)
		(end 186.9948 -26.797)
		(width 0.2032)
		(layer "B.Cu")
		(net "VR_PVDDRA_ISUMN1")
	)
	(segment
		(start 187.5028 -25.019)
		(end 187.1726 -25.019)
		(width 0.2032)
		(layer "B.Cu")
		(net "VR_PVDDRA_ISUMN1")
	)
	(segment
		(start 187.9346 -25.7556)
		(end 187.6552 -26.035)
		(width 0.2032)
		(layer "B.Cu")
		(net "VR_PVDDRA_ISUMN1")
	)
	(segment
		(start 187.0964 -27.6098)
		(end 187.071 -27.6352)
		(width 0.2032)
		(layer "B.Cu")
		(net "VR_PVDDRA_ISUMN1")
	)
	(segment
		(start 186.9948 -26.797)
		(end 186.9948 -26.035)
		(width 0.2032)
		(layer "B.Cu")
		(net "VR_PVDDRA_ISUMN1")
	)
	(segment
		(start 187.9346 -25.4508)
		(end 187.5028 -25.019)
		(width 0.2032)
		(layer "B.Cu")
		(net "VR_PVDDRA_ISUMN1")
	)
	(segment
		(start 187.071 -27.6352)
		(end 187.071 -28.4226)
		(width 0.2032)
		(layer "B.Cu")
		(net "VR_PVDDRA_ISUMN1")
	)
	(segment
		(start 177.249836 -9.897364)
		(end 177.249836 -9.154414)
		(width 0.1778)
		(layer "F.Cu")
		(net "M_B_DQS_DP5")
	)
	(segment
		(start 112.613694 -34.569908)
		(end 112.154462 -34.569908)
		(width 0.1016)
		(layer "F.Cu")
		(net "M_B_DQS_DP5")
	)
	(segment
		(start 177.249836 -9.154414)
		(end 177.102262 -9.00684)
		(width 0.1778)
		(layer "F.Cu")
		(net "M_B_DQS_DP5")
	)
	(segment
		(start 112.154462 -34.569908)
		(end 112.098328 -34.626042)
		(width 0.1016)
		(layer "F.Cu")
		(net "M_B_DQS_DP5")
	)
	(segment
		(start 117.6528 -32.0548)
		(end 117.2464 -32.4612)
		(width 0.1016)
		(layer "F.Cu")
		(net "M_B_DQS_DP5")
	)
	(segment
		(start 177.354992 -5.80517)
		(end 177.362358 -5.80517)
		(width 0.1778)
		(layer "F.Cu")
		(net "M_B_DQS_DP5")
	)
	(segment
		(start 177.102262 -9.00684)
		(end 177.102262 -6.0579)
		(width 0.1778)
		(layer "F.Cu")
		(net "M_B_DQS_DP5")
	)
	(segment
		(start 177.102262 -6.0579)
		(end 177.354992 -5.80517)
		(width 0.1778)
		(layer "F.Cu")
		(net "M_B_DQS_DP5")
	)
	(segment
		(start 117.2464 -32.4612)
		(end 114.722402 -32.4612)
		(width 0.1016)
		(layer "F.Cu")
		(net "M_B_DQS_DP5")
	)
	(segment
		(start 112.098328 -34.626042)
		(end 112.098328 -34.800794)
		(width 0.1016)
		(layer "F.Cu")
		(net "M_B_DQS_DP5")
	)
	(segment
		(start 114.722402 -32.4612)
		(end 112.613694 -34.569908)
		(width 0.1016)
		(layer "F.Cu")
		(net "M_B_DQS_DP5")
	)
	(via
		(at 117.6528 -32.0548)
		(size 0.4318)
		(drill 0.2032)
		(layers "F.Cu" "B.Cu")
		(net "M_B_DQS_DP5")
	)
	(via
		(at 177.362358 -5.80517)
		(size 0.4318)
		(drill 0.2032)
		(layers "F.Cu" "B.Cu")
		(net "M_B_DQS_DP5")
	)
	(segment
		(start 177.249836 -1.690624)
		(end 177.249836 -2.482342)
		(width 0.1778)
		(layer "B.Cu")
		(net "M_B_DQS_DP5")
	)
	(segment
		(start 177.249836 -2.482342)
		(end 177.102262 -2.629916)
		(width 0.1778)
		(layer "B.Cu")
		(net "M_B_DQS_DP5")
	)
	(segment
		(start 177.102262 -2.629916)
		(end 177.102262 -5.545074)
		(width 0.1778)
		(layer "B.Cu")
		(net "M_B_DQS_DP5")
	)
	(segment
		(start 177.102262 -5.545074)
		(end 177.362358 -5.80517)
		(width 0.1778)
		(layer "B.Cu")
		(net "M_B_DQS_DP5")
	)
	(segment
		(start 118.484142 -30.861)
		(end 117.6528 -31.692342)
		(width 0.1016)
		(layer "In2.Cu")
		(net "M_B_DQS_DP5")
	)
	(segment
		(start 165.3032 -18.2626)
		(end 165.3032 -17.8562)
		(width 0.1524)
		(layer "In2.Cu")
		(net "M_B_DQS_DP5")
	)
	(segment
		(start 127.236474 -28.76804)
		(end 127.360934 -28.64358)
		(width 0.1524)
		(layer "In2.Cu")
		(net "M_B_DQS_DP5")
	)
	(segment
		(start 129.105914 -28.76804)
		(end 129.563114 -28.76804)
		(width 0.1524)
		(layer "In2.Cu")
		(net "M_B_DQS_DP5")
	)
	(segment
		(start 176.911 -6.605778)
		(end 177.0634 -6.453378)
		(width 0.1524)
		(layer "In2.Cu")
		(net "M_B_DQS_DP5")
	)
	(segment
		(start 128.981454 -28.64358)
		(end 129.105914 -28.76804)
		(width 0.1524)
		(layer "In2.Cu")
		(net "M_B_DQS_DP5")
	)
	(segment
		(start 163.498276 -19.7612)
		(end 165.774624 -19.7612)
		(width 0.1524)
		(layer "In2.Cu")
		(net "M_B_DQS_DP5")
	)
	(segment
		(start 165.774624 -18.415)
		(end 165.4556 -18.415)
		(width 0.1524)
		(layer "In2.Cu")
		(net "M_B_DQS_DP5")
	)
	(segment
		(start 129.563114 -28.76804)
		(end 129.687574 -28.64358)
		(width 0.1524)
		(layer "In2.Cu")
		(net "M_B_DQS_DP5")
	)
	(segment
		(start 118.774972 -30.861)
		(end 118.484142 -30.861)
		(width 0.1016)
		(layer "In2.Cu")
		(net "M_B_DQS_DP5")
	)
	(segment
		(start 118.810786 -30.896814)
		(end 118.774972 -30.861)
		(width 0.1016)
		(layer "In2.Cu")
		(net "M_B_DQS_DP5")
	)
	(segment
		(start 165.3032 -17.8562)
		(end 165.4556 -17.7038)
		(width 0.1524)
		(layer "In2.Cu")
		(net "M_B_DQS_DP5")
	)
	(segment
		(start 127.360934 -28.64358)
		(end 127.818134 -28.64358)
		(width 0.1524)
		(layer "In2.Cu")
		(net "M_B_DQS_DP5")
	)
	(segment
		(start 123.94438 -30.896814)
		(end 126.197614 -28.64358)
		(width 0.1524)
		(layer "In2.Cu")
		(net "M_B_DQS_DP5")
	)
	(segment
		(start 127.942594 -28.76804)
		(end 128.399794 -28.76804)
		(width 0.1524)
		(layer "In2.Cu")
		(net "M_B_DQS_DP5")
	)
	(segment
		(start 126.197614 -28.64358)
		(end 126.654814 -28.64358)
		(width 0.1524)
		(layer "In2.Cu")
		(net "M_B_DQS_DP5")
	)
	(segment
		(start 126.654814 -28.64358)
		(end 126.779274 -28.76804)
		(width 0.1524)
		(layer "In2.Cu")
		(net "M_B_DQS_DP5")
	)
	(segment
		(start 128.399794 -28.76804)
		(end 128.524254 -28.64358)
		(width 0.1524)
		(layer "In2.Cu")
		(net "M_B_DQS_DP5")
	)
	(segment
		(start 165.774624 -19.7612)
		(end 166.0906 -19.445224)
		(width 0.1524)
		(layer "In2.Cu")
		(net "M_B_DQS_DP5")
	)
	(segment
		(start 126.779274 -28.76804)
		(end 127.236474 -28.76804)
		(width 0.1524)
		(layer "In2.Cu")
		(net "M_B_DQS_DP5")
	)
	(segment
		(start 166.0906 -18.730976)
		(end 165.774624 -18.415)
		(width 0.1524)
		(layer "In2.Cu")
		(net "M_B_DQS_DP5")
	)
	(segment
		(start 176.4284 -9.9314)
		(end 176.911 -9.4488)
		(width 0.1524)
		(layer "In2.Cu")
		(net "M_B_DQS_DP5")
	)
	(segment
		(start 117.6528 -31.692342)
		(end 117.6528 -32.0548)
		(width 0.1016)
		(layer "In2.Cu")
		(net "M_B_DQS_DP5")
	)
	(segment
		(start 175.791114 -9.9314)
		(end 176.4284 -9.9314)
		(width 0.1524)
		(layer "In2.Cu")
		(net "M_B_DQS_DP5")
	)
	(segment
		(start 165.4556 -17.7038)
		(end 168.018714 -17.7038)
		(width 0.1524)
		(layer "In2.Cu")
		(net "M_B_DQS_DP5")
	)
	(segment
		(start 168.018714 -17.7038)
		(end 175.791114 -9.9314)
		(width 0.1524)
		(layer "In2.Cu")
		(net "M_B_DQS_DP5")
	)
	(segment
		(start 165.4556 -18.415)
		(end 165.3032 -18.2626)
		(width 0.1524)
		(layer "In2.Cu")
		(net "M_B_DQS_DP5")
	)
	(segment
		(start 177.0634 -6.453378)
		(end 177.0634 -6.096762)
		(width 0.1524)
		(layer "In2.Cu")
		(net "M_B_DQS_DP5")
	)
	(segment
		(start 154.615896 -28.64358)
		(end 163.498276 -19.7612)
		(width 0.1524)
		(layer "In2.Cu")
		(net "M_B_DQS_DP5")
	)
	(segment
		(start 127.818134 -28.64358)
		(end 127.942594 -28.76804)
		(width 0.1524)
		(layer "In2.Cu")
		(net "M_B_DQS_DP5")
	)
	(segment
		(start 118.810786 -30.896814)
		(end 123.94438 -30.896814)
		(width 0.1524)
		(layer "In2.Cu")
		(net "M_B_DQS_DP5")
	)
	(segment
		(start 177.0634 -6.096762)
		(end 177.354992 -5.80517)
		(width 0.1524)
		(layer "In2.Cu")
		(net "M_B_DQS_DP5")
	)
	(segment
		(start 176.911 -9.4488)
		(end 176.911 -6.605778)
		(width 0.1524)
		(layer "In2.Cu")
		(net "M_B_DQS_DP5")
	)
	(segment
		(start 129.687574 -28.64358)
		(end 154.615896 -28.64358)
		(width 0.1524)
		(layer "In2.Cu")
		(net "M_B_DQS_DP5")
	)
	(segment
		(start 128.524254 -28.64358)
		(end 128.981454 -28.64358)
		(width 0.1524)
		(layer "In2.Cu")
		(net "M_B_DQS_DP5")
	)
	(segment
		(start 177.354992 -5.80517)
		(end 177.362358 -5.80517)
		(width 0.1524)
		(layer "In2.Cu")
		(net "M_B_DQS_DP5")
	)
	(segment
		(start 166.0906 -19.445224)
		(end 166.0906 -18.730976)
		(width 0.1524)
		(layer "In2.Cu")
		(net "M_B_DQS_DP5")
	)
	(segment
		(start 153.767536 -11.078464)
		(end 155.341066 -11.078464)
		(width 0.3048)
		(layer "F.Cu")
		(net "DDR3_M_B_VREF_CA")
	)
	(segment
		(start 155.3972 -4.472178)
		(end 155.448 -4.421378)
		(width 0.3048)
		(layer "F.Cu")
		(net "DDR3_M_B_VREF_CA")
	)
	(segment
		(start 153.4922 -11.3538)
		(end 153.767536 -11.078464)
		(width 0.3048)
		(layer "F.Cu")
		(net "DDR3_M_B_VREF_CA")
	)
	(segment
		(start 155.6766 -7.164578)
		(end 155.3972 -6.885178)
		(width 0.3048)
		(layer "F.Cu")
		(net "DDR3_M_B_VREF_CA")
	)
	(segment
		(start 155.3972 -6.885178)
		(end 155.3972 -4.472178)
		(width 0.3048)
		(layer "F.Cu")
		(net "DDR3_M_B_VREF_CA")
	)
	(segment
		(start 153.4668 -11.7094)
		(end 153.4922 -11.684)
		(width 0.3048)
		(layer "F.Cu")
		(net "DDR3_M_B_VREF_CA")
	)
	(segment
		(start 155.64993 -9.897364)
		(end 155.64993 -8.68299)
		(width 0.3048)
		(layer "F.Cu")
		(net "DDR3_M_B_VREF_CA")
	)
	(segment
		(start 155.64993 -8.68299)
		(end 155.6766 -8.65632)
		(width 0.3048)
		(layer "F.Cu")
		(net "DDR3_M_B_VREF_CA")
	)
	(segment
		(start 155.6766 -8.65632)
		(end 155.6766 -7.164578)
		(width 0.3048)
		(layer "F.Cu")
		(net "DDR3_M_B_VREF_CA")
	)
	(segment
		(start 154.5082 -11.684)
		(end 153.4922 -11.684)
		(width 0.3048)
		(layer "F.Cu")
		(net "DDR3_M_B_VREF_CA")
	)
	(segment
		(start 153.4922 -11.684)
		(end 153.4922 -11.3538)
		(width 0.3048)
		(layer "F.Cu")
		(net "DDR3_M_B_VREF_CA")
	)
	(segment
		(start 153.4668 -12.446)
		(end 153.4668 -11.7094)
		(width 0.3048)
		(layer "F.Cu")
		(net "DDR3_M_B_VREF_CA")
	)
	(segment
		(start 155.64993 -10.7696)
		(end 155.64993 -9.897364)
		(width 0.3048)
		(layer "F.Cu")
		(net "DDR3_M_B_VREF_CA")
	)
	(segment
		(start 155.341066 -11.078464)
		(end 155.64993 -10.7696)
		(width 0.3048)
		(layer "F.Cu")
		(net "DDR3_M_B_VREF_CA")
	)
	(via
		(at 155.448 -4.421378)
		(size 0.4318)
		(drill 0.2032)
		(layers "F.Cu" "B.Cu")
		(net "DDR3_M_B_VREF_CA")
	)
	(segment
		(start 155.6385 -4.230878)
		(end 155.6385 -3.369818)
		(width 0.3048)
		(layer "B.Cu")
		(net "DDR3_M_B_VREF_CA")
	)
	(segment
		(start 155.448 -4.421378)
		(end 155.6385 -4.230878)
		(width 0.3048)
		(layer "B.Cu")
		(net "DDR3_M_B_VREF_CA")
	)
	(segment
		(start 155.6385 -3.369818)
		(end 155.677108 -3.33121)
		(width 0.3048)
		(layer "B.Cu")
		(net "DDR3_M_B_VREF_CA")
	)
	(segment
		(start 155.677108 -2.920746)
		(end 155.64993 -2.893568)
		(width 0.3048)
		(layer "B.Cu")
		(net "DDR3_M_B_VREF_CA")
	)
	(segment
		(start 155.64993 -2.893568)
		(end 155.64993 -1.690624)
		(width 0.3048)
		(layer "B.Cu")
		(net "DDR3_M_B_VREF_CA")
	)
	(segment
		(start 155.677108 -3.33121)
		(end 155.677108 -2.920746)
		(width 0.3048)
		(layer "B.Cu")
		(net "DDR3_M_B_VREF_CA")
	)
	(segment
		(start 87.076788 -39.431214)
		(end 86.7156 -39.792402)
		(width 0.1143)
		(layer "F.Cu")
		(net "BD_ID_1")
	)
	(segment
		(start 86.7156 -39.792402)
		(end 86.7156 -39.8018)
		(width 0.1143)
		(layer "F.Cu")
		(net "BD_ID_1")
	)
	(via
		(at 86.7156 -39.8018)
		(size 0.4318)
		(drill 0.2032)
		(layers "F.Cu" "B.Cu")
		(net "BD_ID_1")
	)
	(via
		(at 78.8162 -41.4782)
		(size 0.7112)
		(drill 0.3556)
		(layers "F.Cu" "B.Cu")
		(net "BD_ID_1")
	)
	(segment
		(start 78.20787 -41.258236)
		(end 77.865478 -41.258236)
		(width 0.1143)
		(layer "B.Cu")
		(net "BD_ID_1")
	)
	(segment
		(start 86.6394 -39.7256)
		(end 85.030056 -39.7256)
		(width 0.1143)
		(layer "B.Cu")
		(net "BD_ID_1")
	)
	(segment
		(start 78.8162 -41.4782)
		(end 78.79461 -41.49979)
		(width 0.1143)
		(layer "B.Cu")
		(net "BD_ID_1")
	)
	(segment
		(start 83.23199 -39.451534)
		(end 82.983324 -39.7002)
		(width 0.1143)
		(layer "B.Cu")
		(net "BD_ID_1")
	)
	(segment
		(start 74.93 -40.767)
		(end 74.5998 -40.767)
		(width 0.1143)
		(layer "B.Cu")
		(net "BD_ID_1")
	)
	(segment
		(start 77.865478 -41.258236)
		(end 77.340714 -41.783)
		(width 0.1143)
		(layer "B.Cu")
		(net "BD_ID_1")
	)
	(segment
		(start 78.449424 -41.49979)
		(end 78.20787 -41.258236)
		(width 0.1143)
		(layer "B.Cu")
		(net "BD_ID_1")
	)
	(segment
		(start 84.75599 -39.451534)
		(end 83.23199 -39.451534)
		(width 0.1143)
		(layer "B.Cu")
		(net "BD_ID_1")
	)
	(segment
		(start 73.7362 -41.656)
		(end 73.7362 -41.6306)
		(width 0.1143)
		(layer "B.Cu")
		(net "BD_ID_1")
	)
	(segment
		(start 85.030056 -39.7256)
		(end 84.75599 -39.451534)
		(width 0.1143)
		(layer "B.Cu")
		(net "BD_ID_1")
	)
	(segment
		(start 78.79461 -41.49979)
		(end 78.449424 -41.49979)
		(width 0.1143)
		(layer "B.Cu")
		(net "BD_ID_1")
	)
	(segment
		(start 79.2988 -41.4782)
		(end 78.8162 -41.4782)
		(width 0.1143)
		(layer "B.Cu")
		(net "BD_ID_1")
	)
	(segment
		(start 79.947516 -40.829484)
		(end 79.2988 -41.4782)
		(width 0.1143)
		(layer "B.Cu")
		(net "BD_ID_1")
	)
	(segment
		(start 73.7362 -41.6306)
		(end 74.5998 -40.767)
		(width 0.1143)
		(layer "B.Cu")
		(net "BD_ID_1")
	)
	(segment
		(start 80.874108 -40.829484)
		(end 79.947516 -40.829484)
		(width 0.1143)
		(layer "B.Cu")
		(net "BD_ID_1")
	)
	(segment
		(start 75.33005 -41.16705)
		(end 74.93 -40.767)
		(width 0.1143)
		(layer "B.Cu")
		(net "BD_ID_1")
	)
	(segment
		(start 82.983324 -39.7002)
		(end 82.003392 -39.7002)
		(width 0.1143)
		(layer "B.Cu")
		(net "BD_ID_1")
	)
	(segment
		(start 77.340714 -41.783)
		(end 76.288646 -41.783)
		(width 0.1143)
		(layer "B.Cu")
		(net "BD_ID_1")
	)
	(segment
		(start 76.288646 -41.783)
		(end 75.672696 -41.16705)
		(width 0.1143)
		(layer "B.Cu")
		(net "BD_ID_1")
	)
	(segment
		(start 82.003392 -39.7002)
		(end 80.874108 -40.829484)
		(width 0.1143)
		(layer "B.Cu")
		(net "BD_ID_1")
	)
	(segment
		(start 75.672696 -41.16705)
		(end 75.33005 -41.16705)
		(width 0.1143)
		(layer "B.Cu")
		(net "BD_ID_1")
	)
	(segment
		(start 86.7156 -39.8018)
		(end 86.6394 -39.7256)
		(width 0.1143)
		(layer "B.Cu")
		(net "BD_ID_1")
	)
	(segment
		(start 159.799528 -3.820414)
		(end 159.799528 -5.888736)
		(width 0.2413)
		(layer "F.Cu")
		(net "M_B_MA8")
	)
	(segment
		(start 102.278688 -29.235654)
		(end 102.044246 -29.001212)
		(width 0.1016)
		(layer "F.Cu")
		(net "M_B_MA8")
	)
	(segment
		(start 159.799528 -5.888736)
		(end 159.32277 -6.365494)
		(width 0.2413)
		(layer "F.Cu")
		(net "M_B_MA8")
	)
	(segment
		(start 159.549846 -1.68402)
		(end 159.549846 -3.570732)
		(width 0.2413)
		(layer "F.Cu")
		(net "M_B_MA8")
	)
	(segment
		(start 102.044246 -29.001212)
		(end 102.044246 -28.554172)
		(width 0.1016)
		(layer "F.Cu")
		(net "M_B_MA8")
	)
	(segment
		(start 159.549846 -3.570732)
		(end 159.799528 -3.820414)
		(width 0.2413)
		(layer "F.Cu")
		(net "M_B_MA8")
	)
	(segment
		(start 159.32277 -6.365494)
		(end 159.32277 -6.377178)
		(width 0.2413)
		(layer "F.Cu")
		(net "M_B_MA8")
	)
	(via
		(at 102.044246 -28.554172)
		(size 0.4318)
		(drill 0.2032)
		(layers "F.Cu" "B.Cu")
		(net "M_B_MA8")
	)
	(via
		(at 159.32277 -6.377178)
		(size 0.4318)
		(drill 0.2032)
		(layers "F.Cu" "B.Cu")
		(net "M_B_MA8")
	)
	(segment
		(start 159.549846 -7.761224)
		(end 159.426148 -7.637526)
		(width 0.2413)
		(layer "B.Cu")
		(net "M_B_MA8")
	)
	(segment
		(start 159.426148 -6.480556)
		(end 159.32277 -6.377178)
		(width 0.2413)
		(layer "B.Cu")
		(net "M_B_MA8")
	)
	(segment
		(start 159.426148 -7.637526)
		(end 159.426148 -6.480556)
		(width 0.2413)
		(layer "B.Cu")
		(net "M_B_MA8")
	)
	(segment
		(start 159.549846 -9.89076)
		(end 159.549846 -7.761224)
		(width 0.2413)
		(layer "B.Cu")
		(net "M_B_MA8")
	)
	(segment
		(start 111.72317 -23.6982)
		(end 109.9312 -23.6982)
		(width 0.1905)
		(layer "In7.Cu")
		(net "M_B_MA8")
	)
	(segment
		(start 146.30781 -19.062446)
		(end 146.11731 -19.252946)
		(width 0.1905)
		(layer "In7.Cu")
		(net "M_B_MA8")
	)
	(segment
		(start 117.41277 -19.3929)
		(end 117.41277 -19.252946)
		(width 0.1905)
		(layer "In7.Cu")
		(net "M_B_MA8")
	)
	(segment
		(start 129.632456 -19.3929)
		(end 129.632456 -19.252946)
		(width 0.1905)
		(layer "In7.Cu")
		(net "M_B_MA8")
	)
	(segment
		(start 135.297164 -19.062446)
		(end 135.106664 -19.252946)
		(width 0.1905)
		(layer "In7.Cu")
		(net "M_B_MA8")
	)
	(segment
		(start 154.559254 -14.509496)
		(end 154.290014 -14.509496)
		(width 0.1905)
		(layer "In7.Cu")
		(net "M_B_MA8")
	)
	(segment
		(start 135.678164 -19.062446)
		(end 135.297164 -19.062446)
		(width 0.1905)
		(layer "In7.Cu")
		(net "M_B_MA8")
	)
	(segment
		(start 136.059164 -19.5834)
		(end 135.868664 -19.3929)
		(width 0.1905)
		(layer "In7.Cu")
		(net "M_B_MA8")
	)
	(segment
		(start 146.87931 -19.252946)
		(end 146.68881 -19.062446)
		(width 0.1905)
		(layer "In7.Cu")
		(net "M_B_MA8")
	)
	(segment
		(start 147.64131 -19.3929)
		(end 147.45081 -19.5834)
		(width 0.1905)
		(layer "In7.Cu")
		(net "M_B_MA8")
	)
	(segment
		(start 116.46027 -19.5834)
		(end 115.83797 -19.5834)
		(width 0.1905)
		(layer "In7.Cu")
		(net "M_B_MA8")
	)
	(segment
		(start 117.41277 -19.252946)
		(end 117.22227 -19.062446)
		(width 0.1905)
		(layer "In7.Cu")
		(net "M_B_MA8")
	)
	(segment
		(start 118.17477 -19.3929)
		(end 117.98427 -19.5834)
		(width 0.1905)
		(layer "In7.Cu")
		(net "M_B_MA8")
	)
	(segment
		(start 157.107128 -11.692128)
		(end 156.176218 -12.623038)
		(width 0.1905)
		(layer "In7.Cu")
		(net "M_B_MA8")
	)
	(segment
		(start 154.764486 -14.714474)
		(end 154.559254 -14.509496)
		(width 0.1905)
		(layer "In7.Cu")
		(net "M_B_MA8")
	)
	(segment
		(start 148.21281 -19.062446)
		(end 147.83181 -19.062446)
		(width 0.1905)
		(layer "In7.Cu")
		(net "M_B_MA8")
	)
	(segment
		(start 126.584456 -19.3929)
		(end 126.584456 -19.252946)
		(width 0.1905)
		(layer "In7.Cu")
		(net "M_B_MA8")
	)
	(segment
		(start 155.033726 -14.714474)
		(end 154.764486 -14.714474)
		(width 0.1905)
		(layer "In7.Cu")
		(net "M_B_MA8")
	)
	(segment
		(start 116.84127 -19.062446)
		(end 116.65077 -19.252946)
		(width 0.1905)
		(layer "In7.Cu")
		(net "M_B_MA8")
	)
	(segment
		(start 149.21611 -19.5834)
		(end 148.59381 -19.5834)
		(width 0.1905)
		(layer "In7.Cu")
		(net "M_B_MA8")
	)
	(segment
		(start 127.536956 -19.062446)
		(end 127.346456 -19.252946)
		(width 0.1905)
		(layer "In7.Cu")
		(net "M_B_MA8")
	)
	(segment
		(start 128.870456 -19.3929)
		(end 128.679956 -19.5834)
		(width 0.1905)
		(layer "In7.Cu")
		(net "M_B_MA8")
	)
	(segment
		(start 137.202164 -19.062446)
		(end 136.821164 -19.062446)
		(width 0.1905)
		(layer "In7.Cu")
		(net "M_B_MA8")
	)
	(segment
		(start 159.1818 -6.518148)
		(end 159.1818 -9.186418)
		(width 0.1905)
		(layer "In7.Cu")
		(net "M_B_MA8")
	)
	(segment
		(start 129.060956 -19.062446)
		(end 128.870456 -19.252946)
		(width 0.1905)
		(layer "In7.Cu")
		(net "M_B_MA8")
	)
	(segment
		(start 128.870456 -19.252946)
		(end 128.870456 -19.3929)
		(width 0.1905)
		(layer "In7.Cu")
		(net "M_B_MA8")
	)
	(segment
		(start 145.92681 -19.5834)
		(end 139.107164 -19.5834)
		(width 0.1905)
		(layer "In7.Cu")
		(net "M_B_MA8")
	)
	(segment
		(start 108.066332 -24.4729)
		(end 109.1565 -24.4729)
		(width 0.1016)
		(layer "In7.Cu")
		(net "M_B_MA8")
	)
	(segment
		(start 159.1818 -9.186418)
		(end 157.107128 -11.26109)
		(width 0.1905)
		(layer "In7.Cu")
		(net "M_B_MA8")
	)
	(segment
		(start 120.46077 -19.3929)
		(end 120.46077 -19.252946)
		(width 0.1905)
		(layer "In7.Cu")
		(net "M_B_MA8")
	)
	(segment
		(start 119.12727 -19.5834)
		(end 118.93677 -19.3929)
		(width 0.1905)
		(layer "In7.Cu")
		(net "M_B_MA8")
	)
	(segment
		(start 118.93677 -19.252946)
		(end 118.74627 -19.062446)
		(width 0.1905)
		(layer "In7.Cu")
		(net "M_B_MA8")
	)
	(segment
		(start 117.98427 -19.5834)
		(end 117.60327 -19.5834)
		(width 0.1905)
		(layer "In7.Cu")
		(net "M_B_MA8")
	)
	(segment
		(start 135.868664 -19.3929)
		(end 135.868664 -19.252946)
		(width 0.1905)
		(layer "In7.Cu")
		(net "M_B_MA8")
	)
	(segment
		(start 120.46077 -19.252946)
		(end 120.27027 -19.062446)
		(width 0.1905)
		(layer "In7.Cu")
		(net "M_B_MA8")
	)
	(segment
		(start 155.098242 -13.970508)
		(end 155.303474 -14.175486)
		(width 0.1905)
		(layer "In7.Cu")
		(net "M_B_MA8")
	)
	(segment
		(start 138.154664 -19.252946)
		(end 138.154664 -19.3929)
		(width 0.1905)
		(layer "In7.Cu")
		(net "M_B_MA8")
	)
	(segment
		(start 126.012956 -19.062446)
		(end 125.822456 -19.252946)
		(width 0.1905)
		(layer "In7.Cu")
		(net "M_B_MA8")
	)
	(segment
		(start 156.176218 -12.892532)
		(end 156.38145 -13.09751)
		(width 0.1905)
		(layer "In7.Cu")
		(net "M_B_MA8")
	)
	(segment
		(start 119.69877 -19.252946)
		(end 119.69877 -19.3929)
		(width 0.1905)
		(layer "In7.Cu")
		(net "M_B_MA8")
	)
	(segment
		(start 118.93677 -19.3929)
		(end 118.93677 -19.252946)
		(width 0.1905)
		(layer "In7.Cu")
		(net "M_B_MA8")
	)
	(segment
		(start 146.11731 -19.3929)
		(end 145.92681 -19.5834)
		(width 0.1905)
		(layer "In7.Cu")
		(net "M_B_MA8")
	)
	(segment
		(start 156.176218 -12.623038)
		(end 156.176218 -12.892532)
		(width 0.1905)
		(layer "In7.Cu")
		(net "M_B_MA8")
	)
	(segment
		(start 155.303474 -14.175486)
		(end 155.303474 -14.444726)
		(width 0.1905)
		(layer "In7.Cu")
		(net "M_B_MA8")
	)
	(segment
		(start 155.63723 -13.43152)
		(end 155.36799 -13.43152)
		(width 0.1905)
		(layer "In7.Cu")
		(net "M_B_MA8")
	)
	(segment
		(start 126.393956 -19.062446)
		(end 126.012956 -19.062446)
		(width 0.1905)
		(layer "In7.Cu")
		(net "M_B_MA8")
	)
	(segment
		(start 148.40331 -19.252946)
		(end 148.21281 -19.062446)
		(width 0.1905)
		(layer "In7.Cu")
		(net "M_B_MA8")
	)
	(segment
		(start 120.65127 -19.5834)
		(end 120.46077 -19.3929)
		(width 0.1905)
		(layer "In7.Cu")
		(net "M_B_MA8")
	)
	(segment
		(start 117.60327 -19.5834)
		(end 117.41277 -19.3929)
		(width 0.1905)
		(layer "In7.Cu")
		(net "M_B_MA8")
	)
	(segment
		(start 125.631956 -19.5834)
		(end 120.65127 -19.5834)
		(width 0.1905)
		(layer "In7.Cu")
		(net "M_B_MA8")
	)
	(segment
		(start 146.11731 -19.252946)
		(end 146.11731 -19.3929)
		(width 0.1905)
		(layer "In7.Cu")
		(net "M_B_MA8")
	)
	(segment
		(start 127.917956 -19.062446)
		(end 127.536956 -19.062446)
		(width 0.1905)
		(layer "In7.Cu")
		(net "M_B_MA8")
	)
	(segment
		(start 118.74627 -19.062446)
		(end 118.36527 -19.062446)
		(width 0.1905)
		(layer "In7.Cu")
		(net "M_B_MA8")
	)
	(segment
		(start 139.107164 -19.5834)
		(end 138.916664 -19.3929)
		(width 0.1905)
		(layer "In7.Cu")
		(net "M_B_MA8")
	)
	(segment
		(start 118.36527 -19.062446)
		(end 118.17477 -19.252946)
		(width 0.1905)
		(layer "In7.Cu")
		(net "M_B_MA8")
	)
	(segment
		(start 136.821164 -19.062446)
		(end 136.630664 -19.252946)
		(width 0.1905)
		(layer "In7.Cu")
		(net "M_B_MA8")
	)
	(segment
		(start 128.108456 -19.252946)
		(end 127.917956 -19.062446)
		(width 0.1905)
		(layer "In7.Cu")
		(net "M_B_MA8")
	)
	(segment
		(start 102.044246 -28.554172)
		(end 103.318818 -27.2796)
		(width 0.1016)
		(layer "In7.Cu")
		(net "M_B_MA8")
	)
	(segment
		(start 116.65077 -19.252946)
		(end 116.65077 -19.3929)
		(width 0.1905)
		(layer "In7.Cu")
		(net "M_B_MA8")
	)
	(segment
		(start 128.679956 -19.5834)
		(end 128.298956 -19.5834)
		(width 0.1905)
		(layer "In7.Cu")
		(net "M_B_MA8")
	)
	(segment
		(start 157.107128 -11.26109)
		(end 157.107128 -11.692128)
		(width 0.1905)
		(layer "In7.Cu")
		(net "M_B_MA8")
	)
	(segment
		(start 154.290014 -14.509496)
		(end 149.21611 -19.5834)
		(width 0.1905)
		(layer "In7.Cu")
		(net "M_B_MA8")
	)
	(segment
		(start 128.298956 -19.5834)
		(end 128.108456 -19.3929)
		(width 0.1905)
		(layer "In7.Cu")
		(net "M_B_MA8")
	)
	(segment
		(start 125.822456 -19.3929)
		(end 125.631956 -19.5834)
		(width 0.1905)
		(layer "In7.Cu")
		(net "M_B_MA8")
	)
	(segment
		(start 137.583164 -19.5834)
		(end 137.392664 -19.3929)
		(width 0.1905)
		(layer "In7.Cu")
		(net "M_B_MA8")
	)
	(segment
		(start 129.441956 -19.062446)
		(end 129.060956 -19.062446)
		(width 0.1905)
		(layer "In7.Cu")
		(net "M_B_MA8")
	)
	(segment
		(start 137.964164 -19.5834)
		(end 137.583164 -19.5834)
		(width 0.1905)
		(layer "In7.Cu")
		(net "M_B_MA8")
	)
	(segment
		(start 128.108456 -19.3929)
		(end 128.108456 -19.252946)
		(width 0.1905)
		(layer "In7.Cu")
		(net "M_B_MA8")
	)
	(segment
		(start 156.111702 -13.636498)
		(end 155.842462 -13.636498)
		(width 0.1905)
		(layer "In7.Cu")
		(net "M_B_MA8")
	)
	(segment
		(start 138.345164 -19.062446)
		(end 138.154664 -19.252946)
		(width 0.1905)
		(layer "In7.Cu")
		(net "M_B_MA8")
	)
	(segment
		(start 129.632456 -19.252946)
		(end 129.441956 -19.062446)
		(width 0.1905)
		(layer "In7.Cu")
		(net "M_B_MA8")
	)
	(segment
		(start 155.098242 -13.701268)
		(end 155.098242 -13.970508)
		(width 0.1905)
		(layer "In7.Cu")
		(net "M_B_MA8")
	)
	(segment
		(start 137.392664 -19.252946)
		(end 137.202164 -19.062446)
		(width 0.1905)
		(layer "In7.Cu")
		(net "M_B_MA8")
	)
	(segment
		(start 119.88927 -19.062446)
		(end 119.69877 -19.252946)
		(width 0.1905)
		(layer "In7.Cu")
		(net "M_B_MA8")
	)
	(segment
		(start 105.259632 -27.2796)
		(end 108.066332 -24.4729)
		(width 0.1016)
		(layer "In7.Cu")
		(net "M_B_MA8")
	)
	(segment
		(start 135.106664 -19.3929)
		(end 134.916164 -19.5834)
		(width 0.1905)
		(layer "In7.Cu")
		(net "M_B_MA8")
	)
	(segment
		(start 116.65077 -19.3929)
		(end 116.46027 -19.5834)
		(width 0.1905)
		(layer "In7.Cu")
		(net "M_B_MA8")
	)
	(segment
		(start 156.38145 -13.09751)
		(end 156.38145 -13.36675)
		(width 0.1905)
		(layer "In7.Cu")
		(net "M_B_MA8")
	)
	(segment
		(start 120.27027 -19.062446)
		(end 119.88927 -19.062446)
		(width 0.1905)
		(layer "In7.Cu")
		(net "M_B_MA8")
	)
	(segment
		(start 136.440164 -19.5834)
		(end 136.059164 -19.5834)
		(width 0.1905)
		(layer "In7.Cu")
		(net "M_B_MA8")
	)
	(segment
		(start 147.06981 -19.5834)
		(end 146.87931 -19.3929)
		(width 0.1905)
		(layer "In7.Cu")
		(net "M_B_MA8")
	)
	(segment
		(start 148.40331 -19.3929)
		(end 148.40331 -19.252946)
		(width 0.1905)
		(layer "In7.Cu")
		(net "M_B_MA8")
	)
	(segment
		(start 129.822956 -19.5834)
		(end 129.632456 -19.3929)
		(width 0.1905)
		(layer "In7.Cu")
		(net "M_B_MA8")
	)
	(segment
		(start 156.38145 -13.36675)
		(end 156.111702 -13.636498)
		(width 0.1905)
		(layer "In7.Cu")
		(net "M_B_MA8")
	)
	(segment
		(start 119.50827 -19.5834)
		(end 119.12727 -19.5834)
		(width 0.1905)
		(layer "In7.Cu")
		(net "M_B_MA8")
	)
	(segment
		(start 127.346456 -19.3929)
		(end 127.155956 -19.5834)
		(width 0.1905)
		(layer "In7.Cu")
		(net "M_B_MA8")
	)
	(segment
		(start 138.916664 -19.252946)
		(end 138.726164 -19.062446)
		(width 0.1905)
		(layer "In7.Cu")
		(net "M_B_MA8")
	)
	(segment
		(start 136.630664 -19.252946)
		(end 136.630664 -19.3929)
		(width 0.1905)
		(layer "In7.Cu")
		(net "M_B_MA8")
	)
	(segment
		(start 118.17477 -19.252946)
		(end 118.17477 -19.3929)
		(width 0.1905)
		(layer "In7.Cu")
		(net "M_B_MA8")
	)
	(segment
		(start 103.318818 -27.2796)
		(end 105.259632 -27.2796)
		(width 0.1016)
		(layer "In7.Cu")
		(net "M_B_MA8")
	)
	(segment
		(start 138.916664 -19.3929)
		(end 138.916664 -19.252946)
		(width 0.1905)
		(layer "In7.Cu")
		(net "M_B_MA8")
	)
	(segment
		(start 134.916164 -19.5834)
		(end 129.822956 -19.5834)
		(width 0.1905)
		(layer "In7.Cu")
		(net "M_B_MA8")
	)
	(segment
		(start 159.32277 -6.377178)
		(end 159.1818 -6.518148)
		(width 0.1905)
		(layer "In7.Cu")
		(net "M_B_MA8")
	)
	(segment
		(start 126.774956 -19.5834)
		(end 126.584456 -19.3929)
		(width 0.1905)
		(layer "In7.Cu")
		(net "M_B_MA8")
	)
	(segment
		(start 109.9312 -23.6982)
		(end 109.1565 -24.4729)
		(width 0.1905)
		(layer "In7.Cu")
		(net "M_B_MA8")
	)
	(segment
		(start 147.45081 -19.5834)
		(end 147.06981 -19.5834)
		(width 0.1905)
		(layer "In7.Cu")
		(net "M_B_MA8")
	)
	(segment
		(start 155.36799 -13.43152)
		(end 155.098242 -13.701268)
		(width 0.1905)
		(layer "In7.Cu")
		(net "M_B_MA8")
	)
	(segment
		(start 155.842462 -13.636498)
		(end 155.63723 -13.43152)
		(width 0.1905)
		(layer "In7.Cu")
		(net "M_B_MA8")
	)
	(segment
		(start 147.83181 -19.062446)
		(end 147.64131 -19.252946)
		(width 0.1905)
		(layer "In7.Cu")
		(net "M_B_MA8")
	)
	(segment
		(start 136.630664 -19.3929)
		(end 136.440164 -19.5834)
		(width 0.1905)
		(layer "In7.Cu")
		(net "M_B_MA8")
	)
	(segment
		(start 127.155956 -19.5834)
		(end 126.774956 -19.5834)
		(width 0.1905)
		(layer "In7.Cu")
		(net "M_B_MA8")
	)
	(segment
		(start 155.303474 -14.444726)
		(end 155.033726 -14.714474)
		(width 0.1905)
		(layer "In7.Cu")
		(net "M_B_MA8")
	)
	(segment
		(start 115.83797 -19.5834)
		(end 111.72317 -23.6982)
		(width 0.1905)
		(layer "In7.Cu")
		(net "M_B_MA8")
	)
	(segment
		(start 137.392664 -19.3929)
		(end 137.392664 -19.252946)
		(width 0.1905)
		(layer "In7.Cu")
		(net "M_B_MA8")
	)
	(segment
		(start 135.106664 -19.252946)
		(end 135.106664 -19.3929)
		(width 0.1905)
		(layer "In7.Cu")
		(net "M_B_MA8")
	)
	(segment
		(start 117.22227 -19.062446)
		(end 116.84127 -19.062446)
		(width 0.1905)
		(layer "In7.Cu")
		(net "M_B_MA8")
	)
	(segment
		(start 146.68881 -19.062446)
		(end 146.30781 -19.062446)
		(width 0.1905)
		(layer "In7.Cu")
		(net "M_B_MA8")
	)
	(segment
		(start 119.69877 -19.3929)
		(end 119.50827 -19.5834)
		(width 0.1905)
		(layer "In7.Cu")
		(net "M_B_MA8")
	)
	(segment
		(start 147.64131 -19.252946)
		(end 147.64131 -19.3929)
		(width 0.1905)
		(layer "In7.Cu")
		(net "M_B_MA8")
	)
	(segment
		(start 135.868664 -19.252946)
		(end 135.678164 -19.062446)
		(width 0.1905)
		(layer "In7.Cu")
		(net "M_B_MA8")
	)
	(segment
		(start 146.87931 -19.3929)
		(end 146.87931 -19.252946)
		(width 0.1905)
		(layer "In7.Cu")
		(net "M_B_MA8")
	)
	(segment
		(start 126.584456 -19.252946)
		(end 126.393956 -19.062446)
		(width 0.1905)
		(layer "In7.Cu")
		(net "M_B_MA8")
	)
	(segment
		(start 127.346456 -19.252946)
		(end 127.346456 -19.3929)
		(width 0.1905)
		(layer "In7.Cu")
		(net "M_B_MA8")
	)
	(segment
		(start 138.726164 -19.062446)
		(end 138.345164 -19.062446)
		(width 0.1905)
		(layer "In7.Cu")
		(net "M_B_MA8")
	)
	(segment
		(start 125.822456 -19.252946)
		(end 125.822456 -19.3929)
		(width 0.1905)
		(layer "In7.Cu")
		(net "M_B_MA8")
	)
	(segment
		(start 138.154664 -19.3929)
		(end 137.964164 -19.5834)
		(width 0.1905)
		(layer "In7.Cu")
		(net "M_B_MA8")
	)
	(segment
		(start 148.59381 -19.5834)
		(end 148.40331 -19.3929)
		(width 0.1905)
		(layer "In7.Cu")
		(net "M_B_MA8")
	)
	(segment
		(start 81.141316 -31.308294)
		(end 81.132172 -31.29915)
		(width 0.1397)
		(layer "F.Cu")
		(net "SATA3_RX_DP0")
	)
	(segment
		(start 81.768188 -31.308294)
		(end 81.141316 -31.308294)
		(width 0.1397)
		(layer "F.Cu")
		(net "SATA3_RX_DP0")
	)
	(via
		(at 81.132172 -31.29915)
		(size 0.4318)
		(drill 0.2032)
		(layers "F.Cu" "B.Cu")
		(net "SATA3_RX_DP0")
	)
	(segment
		(start 76.962 -30.970728)
		(end 76.962 -29.53385)
		(width 0.1016)
		(layer "B.Cu")
		(net "SATA3_RX_DP0")
	)
	(segment
		(start 80.330802 -32.2072)
		(end 79.6544 -32.2072)
		(width 0.1016)
		(layer "B.Cu")
		(net "SATA3_RX_DP0")
	)
	(segment
		(start 68.89369 -30.32125)
		(end 67.84975 -30.32125)
		(width 0.1397)
		(layer "B.Cu")
		(net "SATA3_RX_DP0")
	)
	(segment
		(start 79.3496 -31.9024)
		(end 77.893672 -31.9024)
		(width 0.1016)
		(layer "B.Cu")
		(net "SATA3_RX_DP0")
	)
	(segment
		(start 71.610982 -29.1084)
		(end 70.10654 -29.1084)
		(width 0.1397)
		(layer "B.Cu")
		(net "SATA3_RX_DP0")
	)
	(segment
		(start 76.89215 -29.4386)
		(end 76.89215 -29.06776)
		(width 0.1397)
		(layer "B.Cu")
		(net "SATA3_RX_DP0")
	)
	(segment
		(start 73.312528 -27.406854)
		(end 71.610982 -29.1084)
		(width 0.1397)
		(layer "B.Cu")
		(net "SATA3_RX_DP0")
	)
	(segment
		(start 67.84975 -30.32125)
		(end 67.6402 -30.5308)
		(width 0.1397)
		(layer "B.Cu")
		(net "SATA3_RX_DP0")
	)
	(segment
		(start 80.867504 -31.29915)
		(end 80.729074 -31.43758)
		(width 0.1016)
		(layer "B.Cu")
		(net "SATA3_RX_DP0")
	)
	(segment
		(start 70.10654 -29.1084)
		(end 68.89369 -30.32125)
		(width 0.1397)
		(layer "B.Cu")
		(net "SATA3_RX_DP0")
	)
	(segment
		(start 79.6544 -32.2072)
		(end 79.3496 -31.9024)
		(width 0.1016)
		(layer "B.Cu")
		(net "SATA3_RX_DP0")
	)
	(segment
		(start 76.962 -29.53385)
		(end 76.89215 -29.464)
		(width 0.1016)
		(layer "B.Cu")
		(net "SATA3_RX_DP0")
	)
	(segment
		(start 77.893672 -31.9024)
		(end 76.962 -30.970728)
		(width 0.1016)
		(layer "B.Cu")
		(net "SATA3_RX_DP0")
	)
	(segment
		(start 76.89215 -29.464)
		(end 76.89215 -29.4386)
		(width 0.1016)
		(layer "B.Cu")
		(net "SATA3_RX_DP0")
	)
	(segment
		(start 81.132172 -31.29915)
		(end 80.867504 -31.29915)
		(width 0.1016)
		(layer "B.Cu")
		(net "SATA3_RX_DP0")
	)
	(segment
		(start 76.89215 -29.06776)
		(end 75.231244 -27.406854)
		(width 0.1397)
		(layer "B.Cu")
		(net "SATA3_RX_DP0")
	)
	(segment
		(start 80.729074 -31.808928)
		(end 80.330802 -32.2072)
		(width 0.1016)
		(layer "B.Cu")
		(net "SATA3_RX_DP0")
	)
	(segment
		(start 75.231244 -27.406854)
		(end 73.312528 -27.406854)
		(width 0.1397)
		(layer "B.Cu")
		(net "SATA3_RX_DP0")
	)
	(segment
		(start 80.729074 -31.43758)
		(end 80.729074 -31.808928)
		(width 0.1016)
		(layer "B.Cu")
		(net "SATA3_RX_DP0")
	)
	(segment
		(start 38.862 -24.745696)
		(end 38.37432 -25.233376)
		(width 0.1143)
		(layer "F.Cu")
		(net "XDP_DFX_PORT0")
	)
	(segment
		(start 79.438754 -46.948344)
		(end 80.07477 -46.948344)
		(width 0.1143)
		(layer "F.Cu")
		(net "XDP_DFX_PORT0")
	)
	(segment
		(start 78.0288 -46.396656)
		(end 78.505558 -46.873668)
		(width 0.1143)
		(layer "F.Cu")
		(net "XDP_DFX_PORT0")
	)
	(segment
		(start 80.07477 -46.948344)
		(end 80.10398 -46.919134)
		(width 0.1143)
		(layer "F.Cu")
		(net "XDP_DFX_PORT0")
	)
	(segment
		(start 38.862 -23.114)
		(end 38.862 -24.745696)
		(width 0.1143)
		(layer "F.Cu")
		(net "XDP_DFX_PORT0")
	)
	(segment
		(start 78.505558 -46.873668)
		(end 79.364078 -46.873668)
		(width 0.1143)
		(layer "F.Cu")
		(net "XDP_DFX_PORT0")
	)
	(segment
		(start 80.10398 -46.919134)
		(end 80.602328 -46.919134)
		(width 0.1143)
		(layer "F.Cu")
		(net "XDP_DFX_PORT0")
	)
	(segment
		(start 79.364078 -46.873668)
		(end 79.438754 -46.948344)
		(width 0.1143)
		(layer "F.Cu")
		(net "XDP_DFX_PORT0")
	)
	(segment
		(start 42.10177 -22.05482)
		(end 39.92118 -22.05482)
		(width 0.1143)
		(layer "F.Cu")
		(net "XDP_DFX_PORT0")
	)
	(segment
		(start 39.92118 -22.05482)
		(end 38.862 -23.114)
		(width 0.1143)
		(layer "F.Cu")
		(net "XDP_DFX_PORT0")
	)
	(segment
		(start 78.0288 -46.228)
		(end 78.0288 -46.396656)
		(width 0.1143)
		(layer "F.Cu")
		(net "XDP_DFX_PORT0")
	)
	(via
		(at 37.421566 -25.630378)
		(size 0.7112)
		(drill 0.3556)
		(layers "F.Cu" "B.Cu")
		(net "XDP_DFX_PORT0")
	)
	(via
		(at 38.37432 -25.233376)
		(size 0.508)
		(drill 0.254)
		(layers "F.Cu" "B.Cu")
		(net "XDP_DFX_PORT0")
	)
	(via
		(at 78.0288 -46.228)
		(size 0.508)
		(drill 0.254)
		(layers "F.Cu" "B.Cu")
		(net "XDP_DFX_PORT0")
	)
	(segment
		(start 37.818568 -25.233376)
		(end 37.421566 -25.630378)
		(width 0.1143)
		(layer "B.Cu")
		(net "XDP_DFX_PORT0")
	)
	(segment
		(start 38.37432 -25.233376)
		(end 37.818568 -25.233376)
		(width 0.1143)
		(layer "B.Cu")
		(net "XDP_DFX_PORT0")
	)
	(segment
		(start 61.862462 -42.799)
		(end 60.179712 -41.11625)
		(width 0.0889)
		(layer "In7.Cu")
		(net "XDP_DFX_PORT0")
	)
	(segment
		(start 37.5285 -30.960314)
		(end 37.5285 -26.079196)
		(width 0.0889)
		(layer "In7.Cu")
		(net "XDP_DFX_PORT0")
	)
	(segment
		(start 39.632128 -32.3088)
		(end 38.876986 -32.3088)
		(width 0.0889)
		(layer "In7.Cu")
		(net "XDP_DFX_PORT0")
	)
	(segment
		(start 60.179712 -41.11625)
		(end 57.440322 -41.11625)
		(width 0.0889)
		(layer "In7.Cu")
		(net "XDP_DFX_PORT0")
	)
	(segment
		(start 78.0288 -46.228)
		(end 77.562202 -45.761402)
		(width 0.0889)
		(layer "In7.Cu")
		(net "XDP_DFX_PORT0")
	)
	(segment
		(start 43.156378 -35.83305)
		(end 39.632128 -32.3088)
		(width 0.0889)
		(layer "In7.Cu")
		(net "XDP_DFX_PORT0")
	)
	(segment
		(start 74.428604 -45.761402)
		(end 73.504552 -44.83735)
		(width 0.0889)
		(layer "In7.Cu")
		(net "XDP_DFX_PORT0")
	)
	(segment
		(start 64.096392 -42.799)
		(end 61.862462 -42.799)
		(width 0.0889)
		(layer "In7.Cu")
		(net "XDP_DFX_PORT0")
	)
	(segment
		(start 52.8701 -41.6941)
		(end 51.16195 -39.98595)
		(width 0.0889)
		(layer "In7.Cu")
		(net "XDP_DFX_PORT0")
	)
	(segment
		(start 56.862472 -41.6941)
		(end 52.8701 -41.6941)
		(width 0.0889)
		(layer "In7.Cu")
		(net "XDP_DFX_PORT0")
	)
	(segment
		(start 77.562202 -45.761402)
		(end 74.428604 -45.761402)
		(width 0.0889)
		(layer "In7.Cu")
		(net "XDP_DFX_PORT0")
	)
	(segment
		(start 73.504552 -44.83735)
		(end 66.134742 -44.83735)
		(width 0.0889)
		(layer "In7.Cu")
		(net "XDP_DFX_PORT0")
	)
	(segment
		(start 57.440322 -41.11625)
		(end 56.862472 -41.6941)
		(width 0.0889)
		(layer "In7.Cu")
		(net "XDP_DFX_PORT0")
	)
	(segment
		(start 49.688242 -39.98595)
		(end 45.535342 -35.83305)
		(width 0.0889)
		(layer "In7.Cu")
		(net "XDP_DFX_PORT0")
	)
	(segment
		(start 45.535342 -35.83305)
		(end 43.156378 -35.83305)
		(width 0.0889)
		(layer "In7.Cu")
		(net "XDP_DFX_PORT0")
	)
	(segment
		(start 38.876986 -32.3088)
		(end 37.5285 -30.960314)
		(width 0.0889)
		(layer "In7.Cu")
		(net "XDP_DFX_PORT0")
	)
	(segment
		(start 37.5285 -26.079196)
		(end 38.37432 -25.233376)
		(width 0.0889)
		(layer "In7.Cu")
		(net "XDP_DFX_PORT0")
	)
	(segment
		(start 51.16195 -39.98595)
		(end 49.688242 -39.98595)
		(width 0.0889)
		(layer "In7.Cu")
		(net "XDP_DFX_PORT0")
	)
	(segment
		(start 66.134742 -44.83735)
		(end 64.096392 -42.799)
		(width 0.0889)
		(layer "In7.Cu")
		(net "XDP_DFX_PORT0")
	)
	(segment
		(start 185.9788 -32.1818)
		(end 186.372754 -32.575754)
		(width 0.2032)
		(layer "F.Cu")
		(net "VR_PVDDR_A_VW")
	)
	(segment
		(start 185.398664 -32.1818)
		(end 185.9788 -32.1818)
		(width 0.2032)
		(layer "F.Cu")
		(net "VR_PVDDR_A_VW")
	)
	(segment
		(start 186.372754 -32.575754)
		(end 186.856116 -32.575754)
		(width 0.2032)
		(layer "F.Cu")
		(net "VR_PVDDR_A_VW")
	)
	(segment
		(start 184.94502 -31.78302)
		(end 184.968896 -31.806896)
		(width 0.2032)
		(layer "F.Cu")
		(net "VR_PVDDR_A_VW")
	)
	(segment
		(start 183.3372 -32.1818)
		(end 184.0738 -32.1818)
		(width 0.2032)
		(layer "F.Cu")
		(net "VR_PVDDR_A_VW")
	)
	(segment
		(start 185.02376 -31.806896)
		(end 185.398664 -32.1818)
		(width 0.2032)
		(layer "F.Cu")
		(net "VR_PVDDR_A_VW")
	)
	(segment
		(start 184.968896 -31.806896)
		(end 185.02376 -31.806896)
		(width 0.2032)
		(layer "F.Cu")
		(net "VR_PVDDR_A_VW")
	)
	(segment
		(start 183.3118 -32.1564)
		(end 183.3372 -32.1818)
		(width 0.2032)
		(layer "F.Cu")
		(net "VR_PVDDR_A_VW")
	)
	(segment
		(start 184.0738 -32.1818)
		(end 184.1246 -32.1818)
		(width 0.2032)
		(layer "F.Cu")
		(net "VR_PVDDR_A_VW")
	)
	(segment
		(start 184.52338 -31.78302)
		(end 184.94502 -31.78302)
		(width 0.2032)
		(layer "F.Cu")
		(net "VR_PVDDR_A_VW")
	)
	(segment
		(start 184.1246 -32.1818)
		(end 184.52338 -31.78302)
		(width 0.2032)
		(layer "F.Cu")
		(net "VR_PVDDR_A_VW")
	)
	(via
		(at 185.02376 -31.806896)
		(size 0.7112)
		(drill 0.3556)
		(layers "F.Cu" "B.Cu")
		(net "VR_PVDDR_A_VW")
	)
	(segment
		(start 79.400654 -34.954464)
		(end 80.67548 -34.954464)
		(width 0.1143)
		(layer "F.Cu")
		(net "GBE_WOL")
	)
	(segment
		(start 76.074016 -33.02)
		(end 76.677266 -33.62325)
		(width 0.1143)
		(layer "F.Cu")
		(net "GBE_WOL")
	)
	(segment
		(start 77.471524 -34.417)
		(end 78.86319 -34.417)
		(width 0.1143)
		(layer "F.Cu")
		(net "GBE_WOL")
	)
	(segment
		(start 76.677774 -33.62325)
		(end 77.471524 -34.417)
		(width 0.1143)
		(layer "F.Cu")
		(net "GBE_WOL")
	)
	(segment
		(start 80.67548 -34.954464)
		(end 81.03743 -34.592514)
		(width 0.1143)
		(layer "F.Cu")
		(net "GBE_WOL")
	)
	(segment
		(start 78.86319 -34.417)
		(end 79.400654 -34.954464)
		(width 0.1143)
		(layer "F.Cu")
		(net "GBE_WOL")
	)
	(segment
		(start 74.4728 -32.131)
		(end 75.073256 -32.131)
		(width 0.1143)
		(layer "F.Cu")
		(net "GBE_WOL")
	)
	(segment
		(start 75.327256 -32.385)
		(end 75.327256 -32.528256)
		(width 0.1143)
		(layer "F.Cu")
		(net "GBE_WOL")
	)
	(segment
		(start 75.327256 -32.528256)
		(end 75.819 -33.02)
		(width 0.1143)
		(layer "F.Cu")
		(net "GBE_WOL")
	)
	(segment
		(start 75.819 -33.02)
		(end 76.074016 -33.02)
		(width 0.1143)
		(layer "F.Cu")
		(net "GBE_WOL")
	)
	(segment
		(start 81.03743 -34.592514)
		(end 81.308448 -34.592514)
		(width 0.1143)
		(layer "F.Cu")
		(net "GBE_WOL")
	)
	(segment
		(start 76.677266 -33.62325)
		(end 76.677774 -33.62325)
		(width 0.1143)
		(layer "F.Cu")
		(net "GBE_WOL")
	)
	(segment
		(start 75.073256 -32.131)
		(end 75.327256 -32.385)
		(width 0.1143)
		(layer "F.Cu")
		(net "GBE_WOL")
	)
	(via
		(at 75.327256 -32.385)
		(size 0.508)
		(drill 0.254)
		(layers "F.Cu" "B.Cu")
		(net "GBE_WOL")
	)
	(via
		(at 75.819 -33.02)
		(size 0.7112)
		(drill 0.3556)
		(layers "F.Cu" "B.Cu")
		(net "GBE_WOL")
	)
	(segment
		(start 75.200256 -32.512)
		(end 75.327256 -32.385)
		(width 0.1143)
		(layer "B.Cu")
		(net "GBE_WOL")
	)
	(segment
		(start 74.4728 -32.512)
		(end 75.200256 -32.512)
		(width 0.1143)
		(layer "B.Cu")
		(net "GBE_WOL")
	)
	(segment
		(start 36.068 -38.1)
		(end 35.687 -37.719)
		(width 0.1143)
		(layer "F.Cu")
		(net "XDP_PWRGD_IN")
	)
	(segment
		(start 38.2016 -33.289494)
		(end 40.435784 -31.05531)
		(width 0.1143)
		(layer "F.Cu")
		(net "XDP_PWRGD_IN")
	)
	(segment
		(start 35.687 -36.83)
		(end 36.7284 -35.7886)
		(width 0.1143)
		(layer "F.Cu")
		(net "XDP_PWRGD_IN")
	)
	(segment
		(start 35.687 -37.719)
		(end 35.687 -36.83)
		(width 0.1143)
		(layer "F.Cu")
		(net "XDP_PWRGD_IN")
	)
	(segment
		(start 36.068 -38.6842)
		(end 36.068 -38.1)
		(width 0.1143)
		(layer "F.Cu")
		(net "XDP_PWRGD_IN")
	)
	(segment
		(start 37.7952 -35.7886)
		(end 38.2016 -35.3822)
		(width 0.1143)
		(layer "F.Cu")
		(net "XDP_PWRGD_IN")
	)
	(segment
		(start 40.435784 -31.05531)
		(end 42.10177 -31.05531)
		(width 0.1143)
		(layer "F.Cu")
		(net "XDP_PWRGD_IN")
	)
	(segment
		(start 38.2016 -35.3822)
		(end 38.2016 -33.289494)
		(width 0.1143)
		(layer "F.Cu")
		(net "XDP_PWRGD_IN")
	)
	(segment
		(start 36.7284 -35.7886)
		(end 37.7952 -35.7886)
		(width 0.1143)
		(layer "F.Cu")
		(net "XDP_PWRGD_IN")
	)
	(via
		(at 69.977 -25.7048)
		(size 0.7112)
		(drill 0.3556)
		(layers "F.Cu" "B.Cu")
		(net "AGND_P1V8_STBY")
	)
	(segment
		(start 68.7832 -23.241)
		(end 68.961 -23.4188)
		(width 0.254)
		(layer "B.Cu")
		(net "AGND_P1V8_STBY")
	)
	(segment
		(start 68.2244 -24.257)
		(end 68.2244 -21.7424)
		(width 0.254)
		(layer "B.Cu")
		(net "AGND_P1V8_STBY")
	)
	(segment
		(start 69.108066 -21.38807)
		(end 69.108066 -21.820886)
		(width 0.254)
		(layer "B.Cu")
		(net "AGND_P1V8_STBY")
	)
	(segment
		(start 68.9864 -24.2062)
		(end 68.58 -24.6126)
		(width 0.254)
		(layer "B.Cu")
		(net "AGND_P1V8_STBY")
	)
	(segment
		(start 68.9864 -23.4442)
		(end 68.9864 -24.2062)
		(width 0.254)
		(layer "B.Cu")
		(net "AGND_P1V8_STBY")
	)
	(segment
		(start 68.961 -23.4188)
		(end 68.9864 -23.4442)
		(width 0.254)
		(layer "B.Cu")
		(net "AGND_P1V8_STBY")
	)
	(segment
		(start 68.2244 -21.7424)
		(end 67.7164 -21.2344)
		(width 0.254)
		(layer "B.Cu")
		(net "AGND_P1V8_STBY")
	)
	(segment
		(start 68.58 -24.6126)
		(end 68.8848 -24.6126)
		(width 0.254)
		(layer "B.Cu")
		(net "AGND_P1V8_STBY")
	)
	(segment
		(start 68.58 -24.6126)
		(end 68.2244 -24.257)
		(width 0.254)
		(layer "B.Cu")
		(net "AGND_P1V8_STBY")
	)
	(segment
		(start 67.7164 -21.2344)
		(end 67.7164 -21.082)
		(width 0.254)
		(layer "B.Cu")
		(net "AGND_P1V8_STBY")
	)
	(segment
		(start 69.108066 -21.820886)
		(end 68.7832 -22.145752)
		(width 0.254)
		(layer "B.Cu")
		(net "AGND_P1V8_STBY")
	)
	(segment
		(start 68.8848 -24.6126)
		(end 69.977 -25.7048)
		(width 0.254)
		(layer "B.Cu")
		(net "AGND_P1V8_STBY")
	)
	(segment
		(start 68.7832 -22.145752)
		(end 68.7832 -23.241)
		(width 0.254)
		(layer "B.Cu")
		(net "AGND_P1V8_STBY")
	)
	(segment
		(start 200.406 -45.9994)
		(end 201.1807 -45.9994)
		(width 0.2032)
		(layer "F.Cu")
		(net "VR_PVDDRA_R_IS")
	)
	(segment
		(start 200.1012 -45.6946)
		(end 200.406 -45.9994)
		(width 0.2032)
		(layer "F.Cu")
		(net "VR_PVDDRA_R_IS")
	)
	(segment
		(start 201.1807 -45.9994)
		(end 201.3966 -45.7835)
		(width 0.2032)
		(layer "F.Cu")
		(net "VR_PVDDRA_R_IS")
	)
	(via
		(at 185.801 -25.0444)
		(size 0.7112)
		(drill 0.3556)
		(layers "F.Cu" "B.Cu")
		(net "VR_PVDDRA_R_IS")
	)
	(via
		(at 200.1012 -45.6946)
		(size 0.508)
		(drill 0.254)
		(layers "F.Cu" "B.Cu")
		(net "VR_PVDDRA_R_IS")
	)
	(via
		(at 193.625216 -26.405078)
		(size 0.508)
		(drill 0.254)
		(layers "F.Cu" "B.Cu")
		(net "VR_PVDDRA_R_IS")
	)
	(segment
		(start 185.801 -25.0444)
		(end 185.801 -24.86406)
		(width 0.2032)
		(layer "B.Cu")
		(net "VR_PVDDRA_R_IS")
	)
	(segment
		(start 186.89066 -23.7744)
		(end 190.994538 -23.7744)
		(width 0.2032)
		(layer "B.Cu")
		(net "VR_PVDDRA_R_IS")
	)
	(segment
		(start 185.801 -25.4)
		(end 185.2676 -25.9334)
		(width 0.2032)
		(layer "B.Cu")
		(net "VR_PVDDRA_R_IS")
	)
	(segment
		(start 190.994538 -23.7744)
		(end 193.625216 -26.405078)
		(width 0.2032)
		(layer "B.Cu")
		(net "VR_PVDDRA_R_IS")
	)
	(segment
		(start 185.801 -24.86406)
		(end 186.89066 -23.7744)
		(width 0.2032)
		(layer "B.Cu")
		(net "VR_PVDDRA_R_IS")
	)
	(segment
		(start 185.2676 -25.9334)
		(end 184.4548 -25.9334)
		(width 0.2032)
		(layer "B.Cu")
		(net "VR_PVDDRA_R_IS")
	)
	(segment
		(start 185.801 -25.0444)
		(end 185.801 -25.4)
		(width 0.2032)
		(layer "B.Cu")
		(net "VR_PVDDRA_R_IS")
	)
	(segment
		(start 193.929 -26.708862)
		(end 193.625216 -26.405078)
		(width 0.2032)
		(layer "In7.Cu")
		(net "VR_PVDDRA_R_IS")
	)
	(segment
		(start 193.929 -29.2862)
		(end 193.929 -26.708862)
		(width 0.2032)
		(layer "In7.Cu")
		(net "VR_PVDDRA_R_IS")
	)
	(segment
		(start 200.1012 -45.6946)
		(end 197.822566 -45.6946)
		(width 0.2032)
		(layer "In7.Cu")
		(net "VR_PVDDRA_R_IS")
	)
	(segment
		(start 197.358 -32.7152)
		(end 193.929 -29.2862)
		(width 0.2032)
		(layer "In7.Cu")
		(net "VR_PVDDRA_R_IS")
	)
	(segment
		(start 197.822566 -45.6946)
		(end 197.358 -45.230034)
		(width 0.2032)
		(layer "In7.Cu")
		(net "VR_PVDDRA_R_IS")
	)
	(segment
		(start 197.358 -45.230034)
		(end 197.358 -32.7152)
		(width 0.2032)
		(layer "In7.Cu")
		(net "VR_PVDDRA_R_IS")
	)
	(segment
		(start 108.935266 -33.711134)
		(end 109.2454 -33.401)
		(width 0.1778)
		(layer "F.Cu")
		(net "M_B_DQ39")
	)
	(segment
		(start 174.549816 -1.68402)
		(end 174.549816 -2.492248)
		(width 0.1778)
		(layer "F.Cu")
		(net "M_B_DQ39")
	)
	(segment
		(start 174.549816 -2.492248)
		(end 173.92904 -3.113024)
		(width 0.1778)
		(layer "F.Cu")
		(net "M_B_DQ39")
	)
	(segment
		(start 108.814108 -33.711134)
		(end 108.935266 -33.711134)
		(width 0.1778)
		(layer "F.Cu")
		(net "M_B_DQ39")
	)
	(via
		(at 109.2454 -33.401)
		(size 0.4318)
		(drill 0.2032)
		(layers "F.Cu" "B.Cu")
		(net "M_B_DQ39")
	)
	(via
		(at 173.92904 -3.113024)
		(size 0.4318)
		(drill 0.2032)
		(layers "F.Cu" "B.Cu")
		(net "M_B_DQ39")
	)
	(segment
		(start 173.649894 -2.486914)
		(end 173.59503 -2.541778)
		(width 0.1778)
		(layer "B.Cu")
		(net "M_B_DQ39")
	)
	(segment
		(start 173.59503 -2.541778)
		(end 173.59503 -2.707894)
		(width 0.1778)
		(layer "B.Cu")
		(net "M_B_DQ39")
	)
	(segment
		(start 173.59503 -2.707894)
		(end 173.92904 -3.041904)
		(width 0.1778)
		(layer "B.Cu")
		(net "M_B_DQ39")
	)
	(segment
		(start 173.649894 -1.690624)
		(end 173.649894 -2.486914)
		(width 0.1778)
		(layer "B.Cu")
		(net "M_B_DQ39")
	)
	(segment
		(start 173.92904 -3.041904)
		(end 173.92904 -3.113024)
		(width 0.1778)
		(layer "B.Cu")
		(net "M_B_DQ39")
	)
	(segment
		(start 114.5032 -30.6578)
		(end 112.0902 -33.0708)
		(width 0.1524)
		(layer "In4.Cu")
		(net "M_B_DQ39")
	)
	(segment
		(start 176.657 -7.799578)
		(end 176.657 -8.764778)
		(width 0.1524)
		(layer "In4.Cu")
		(net "M_B_DQ39")
	)
	(segment
		(start 175.9204 -11.864086)
		(end 175.9204 -12.6238)
		(width 0.1524)
		(layer "In4.Cu")
		(net "M_B_DQ39")
	)
	(segment
		(start 109.5756 -33.0708)
		(end 109.2454 -33.401)
		(width 0.1524)
		(layer "In4.Cu")
		(net "M_B_DQ39")
	)
	(segment
		(start 158.242 -30.3022)
		(end 153.035 -30.3022)
		(width 0.1524)
		(layer "In4.Cu")
		(net "M_B_DQ39")
	)
	(segment
		(start 176.12614 -6.36143)
		(end 176.657 -7.799578)
		(width 0.1524)
		(layer "In4.Cu")
		(net "M_B_DQ39")
	)
	(segment
		(start 173.92904 -3.113024)
		(end 176.12614 -6.36143)
		(width 0.1524)
		(layer "In4.Cu")
		(net "M_B_DQ39")
	)
	(segment
		(start 152.3492 -30.988)
		(end 117.7544 -30.988)
		(width 0.1524)
		(layer "In4.Cu")
		(net "M_B_DQ39")
	)
	(segment
		(start 175.9204 -12.6238)
		(end 158.242 -30.3022)
		(width 0.1524)
		(layer "In4.Cu")
		(net "M_B_DQ39")
	)
	(segment
		(start 176.657 -8.764778)
		(end 175.9204 -11.864086)
		(width 0.1524)
		(layer "In4.Cu")
		(net "M_B_DQ39")
	)
	(segment
		(start 117.4242 -30.6578)
		(end 114.5032 -30.6578)
		(width 0.1524)
		(layer "In4.Cu")
		(net "M_B_DQ39")
	)
	(segment
		(start 153.035 -30.3022)
		(end 152.3492 -30.988)
		(width 0.1524)
		(layer "In4.Cu")
		(net "M_B_DQ39")
	)
	(segment
		(start 117.7544 -30.988)
		(end 117.4242 -30.6578)
		(width 0.1524)
		(layer "In4.Cu")
		(net "M_B_DQ39")
	)
	(segment
		(start 112.0902 -33.0708)
		(end 109.5756 -33.0708)
		(width 0.1524)
		(layer "In4.Cu")
		(net "M_B_DQ39")
	)
	(segment
		(start 89.702894 -43.053)
		(end 89.3318 -43.053)
		(width 0.1143)
		(layer "F.Cu")
		(net "PD_USB_RCOMP")
	)
	(segment
		(start 88.926162 -43.0784)
		(end 89.3064 -43.0784)
		(width 0.1143)
		(layer "F.Cu")
		(net "PD_USB_RCOMP")
	)
	(segment
		(start 88.600788 -43.403774)
		(end 88.926162 -43.0784)
		(width 0.1143)
		(layer "F.Cu")
		(net "PD_USB_RCOMP")
	)
	(segment
		(start 89.3318 -43.053)
		(end 89.3064 -43.0784)
		(width 0.1143)
		(layer "F.Cu")
		(net "PD_USB_RCOMP")
	)
	(segment
		(start 89.850468 -43.200574)
		(end 89.702894 -43.053)
		(width 0.1143)
		(layer "F.Cu")
		(net "PD_USB_RCOMP")
	)
	(via
		(at 87.5284 -43.958764)
		(size 0.7112)
		(drill 0.3556)
		(layers "F.Cu" "B.Cu")
		(net "PD_USB_RCOMP")
	)
	(via
		(at 89.3064 -43.0784)
		(size 0.4318)
		(drill 0.2032)
		(layers "F.Cu" "B.Cu")
		(net "PD_USB_RCOMP")
	)
	(segment
		(start 88.773 -43.6118)
		(end 89.3064 -43.0784)
		(width 0.1143)
		(layer "B.Cu")
		(net "PD_USB_RCOMP")
	)
	(segment
		(start 87.5284 -43.958764)
		(end 87.849964 -43.6372)
		(width 0.1143)
		(layer "B.Cu")
		(net "PD_USB_RCOMP")
	)
	(segment
		(start 87.849964 -43.6372)
		(end 88.773 -43.6372)
		(width 0.1143)
		(layer "B.Cu")
		(net "PD_USB_RCOMP")
	)
	(segment
		(start 88.773 -43.6372)
		(end 88.773 -43.6118)
		(width 0.1143)
		(layer "B.Cu")
		(net "PD_USB_RCOMP")
	)
	(segment
		(start 185.2676 -30.5308)
		(end 185.4454 -30.353)
		(width 0.2032)
		(layer "F.Cu")
		(net "VR_PVDDR_A_FB")
	)
	(segment
		(start 185.901076 -30.353)
		(end 187.126626 -31.575502)
		(width 0.2032)
		(layer "F.Cu")
		(net "VR_PVDDR_A_FB")
	)
	(segment
		(start 185.4454 -30.353)
		(end 185.901076 -30.353)
		(width 0.2032)
		(layer "F.Cu")
		(net "VR_PVDDR_A_FB")
	)
	(segment
		(start 184.15 -30.4038)
		(end 184.2008 -30.4546)
		(width 0.2032)
		(layer "F.Cu")
		(net "VR_PVDDR_A_FB")
	)
	(segment
		(start 183.388 -30.4038)
		(end 184.15 -30.4038)
		(width 0.2032)
		(layer "F.Cu")
		(net "VR_PVDDR_A_FB")
	)
	(segment
		(start 184.2008 -30.4546)
		(end 185.1914 -30.4546)
		(width 0.2032)
		(layer "F.Cu")
		(net "VR_PVDDR_A_FB")
	)
	(segment
		(start 185.1914 -30.4546)
		(end 185.2676 -30.5308)
		(width 0.2032)
		(layer "F.Cu")
		(net "VR_PVDDR_A_FB")
	)
	(segment
		(start 187.126626 -31.575502)
		(end 187.456318 -31.575502)
		(width 0.2032)
		(layer "F.Cu")
		(net "VR_PVDDR_A_FB")
	)
	(via
		(at 185.2676 -30.5308)
		(size 0.508)
		(drill 0.254)
		(layers "F.Cu" "B.Cu")
		(net "VR_PVDDR_A_FB")
	)
	(via
		(at 184.6834 -31.369)
		(size 0.7112)
		(drill 0.3556)
		(layers "F.Cu" "B.Cu")
		(net "VR_PVDDR_A_FB")
	)
	(segment
		(start 183.408828 -30.39999)
		(end 184.14619 -30.39999)
		(width 0.2032)
		(layer "B.Cu")
		(net "VR_PVDDR_A_FB")
	)
	(segment
		(start 184.2008 -31.0896)
		(end 184.2008 -30.4546)
		(width 0.2032)
		(layer "B.Cu")
		(net "VR_PVDDR_A_FB")
	)
	(segment
		(start 184.6834 -31.3436)
		(end 184.4548 -31.3436)
		(width 0.2032)
		(layer "B.Cu")
		(net "VR_PVDDR_A_FB")
	)
	(segment
		(start 184.6834 -31.3436)
		(end 184.6834 -31.369)
		(width 0.2032)
		(layer "B.Cu")
		(net "VR_PVDDR_A_FB")
	)
	(segment
		(start 185.2676 -30.7594)
		(end 184.6834 -31.3436)
		(width 0.2032)
		(layer "B.Cu")
		(net "VR_PVDDR_A_FB")
	)
	(segment
		(start 185.2676 -30.5308)
		(end 185.2676 -30.7594)
		(width 0.2032)
		(layer "B.Cu")
		(net "VR_PVDDR_A_FB")
	)
	(segment
		(start 184.4548 -31.3436)
		(end 184.2008 -31.0896)
		(width 0.2032)
		(layer "B.Cu")
		(net "VR_PVDDR_A_FB")
	)
	(segment
		(start 184.14619 -30.39999)
		(end 184.2008 -30.4546)
		(width 0.2032)
		(layer "B.Cu")
		(net "VR_PVDDR_A_FB")
	)
	(segment
		(start 157.529276 -7.01421)
		(end 157.436566 -7.01421)
		(width 0.2413)
		(layer "F.Cu")
		(net "M_B_MA9")
	)
	(segment
		(start 158.01975 -8.663686)
		(end 158.01975 -7.504684)
		(width 0.2413)
		(layer "F.Cu")
		(net "M_B_MA9")
	)
	(segment
		(start 156.9212 -6.498844)
		(end 156.9212 -5.488178)
		(width 0.2413)
		(layer "F.Cu")
		(net "M_B_MA9")
	)
	(segment
		(start 158.01975 -7.504684)
		(end 157.529276 -7.01421)
		(width 0.2413)
		(layer "F.Cu")
		(net "M_B_MA9")
	)
	(segment
		(start 158.049976 -9.897364)
		(end 158.049976 -8.693912)
		(width 0.2413)
		(layer "F.Cu")
		(net "M_B_MA9")
	)
	(segment
		(start 157.436566 -7.01421)
		(end 156.9212 -6.498844)
		(width 0.2413)
		(layer "F.Cu")
		(net "M_B_MA9")
	)
	(segment
		(start 157.3784 -5.030978)
		(end 157.380178 -5.030978)
		(width 0.2413)
		(layer "F.Cu")
		(net "M_B_MA9")
	)
	(segment
		(start 156.9212 -5.488178)
		(end 157.3784 -5.030978)
		(width 0.2413)
		(layer "F.Cu")
		(net "M_B_MA9")
	)
	(segment
		(start 101.548692 -31.521654)
		(end 101.222048 -31.19501)
		(width 0.1016)
		(layer "F.Cu")
		(net "M_B_MA9")
	)
	(segment
		(start 101.577648 -31.521654)
		(end 101.548692 -31.521654)
		(width 0.1016)
		(layer "F.Cu")
		(net "M_B_MA9")
	)
	(segment
		(start 158.049976 -8.693912)
		(end 158.01975 -8.663686)
		(width 0.2413)
		(layer "F.Cu")
		(net "M_B_MA9")
	)
	(via
		(at 101.222048 -31.19501)
		(size 0.4318)
		(drill 0.2032)
		(layers "F.Cu" "B.Cu")
		(net "M_B_MA9")
	)
	(via
		(at 157.380178 -5.030978)
		(size 0.4318)
		(drill 0.2032)
		(layers "F.Cu" "B.Cu")
		(net "M_B_MA9")
	)
	(segment
		(start 157.99435 -2.943098)
		(end 157.99435 -4.416806)
		(width 0.2413)
		(layer "B.Cu")
		(net "M_B_MA9")
	)
	(segment
		(start 157.99435 -4.416806)
		(end 157.380178 -5.030978)
		(width 0.2413)
		(layer "B.Cu")
		(net "M_B_MA9")
	)
	(segment
		(start 158.049976 -1.690624)
		(end 158.049976 -2.887472)
		(width 0.2413)
		(layer "B.Cu")
		(net "M_B_MA9")
	)
	(segment
		(start 158.049976 -2.887472)
		(end 157.99435 -2.943098)
		(width 0.2413)
		(layer "B.Cu")
		(net "M_B_MA9")
	)
	(segment
		(start 100.1649 -28.8163)
		(end 100.279454 -28.930854)
		(width 0.1016)
		(layer "In7.Cu")
		(net "M_B_MA9")
	)
	(segment
		(start 110.16742 -20.828)
		(end 103.1748 -20.828)
		(width 0.1905)
		(layer "In7.Cu")
		(net "M_B_MA9")
	)
	(segment
		(start 136.6139 -15.94485)
		(end 115.05057 -15.94485)
		(width 0.1905)
		(layer "In7.Cu")
		(net "M_B_MA9")
	)
	(segment
		(start 157.3276 -5.030978)
		(end 156.942028 -5.41655)
		(width 0.1905)
		(layer "In7.Cu")
		(net "M_B_MA9")
	)
	(segment
		(start 100.85832 -30.352492)
		(end 101.222048 -30.71622)
		(width 0.1016)
		(layer "In7.Cu")
		(net "M_B_MA9")
	)
	(segment
		(start 101.222048 -30.71622)
		(end 101.222048 -31.19501)
		(width 0.1016)
		(layer "In7.Cu")
		(net "M_B_MA9")
	)
	(segment
		(start 102.997 -21.0058)
		(end 102.997 -24.3078)
		(width 0.1016)
		(layer "In7.Cu")
		(net "M_B_MA9")
	)
	(segment
		(start 103.1748 -20.828)
		(end 102.997 -21.0058)
		(width 0.1905)
		(layer "In7.Cu")
		(net "M_B_MA9")
	)
	(segment
		(start 156.942028 -6.449568)
		(end 156.557218 -6.834378)
		(width 0.1905)
		(layer "In7.Cu")
		(net "M_B_MA9")
	)
	(segment
		(start 148.310854 -15.950946)
		(end 145.669 -15.950946)
		(width 0.1905)
		(layer "In7.Cu")
		(net "M_B_MA9")
	)
	(segment
		(start 145.669 -15.950946)
		(end 145.4658 -15.747746)
		(width 0.1905)
		(layer "In7.Cu")
		(net "M_B_MA9")
	)
	(segment
		(start 153.7716 -10.4902)
		(end 148.310854 -15.950946)
		(width 0.1905)
		(layer "In7.Cu")
		(net "M_B_MA9")
	)
	(segment
		(start 115.05057 -15.94485)
		(end 110.16742 -20.828)
		(width 0.1905)
		(layer "In7.Cu")
		(net "M_B_MA9")
	)
	(segment
		(start 100.279454 -28.930854)
		(end 100.279454 -30.175454)
		(width 0.1016)
		(layer "In7.Cu")
		(net "M_B_MA9")
	)
	(segment
		(start 157.380178 -5.030978)
		(end 157.3276 -5.030978)
		(width 0.1905)
		(layer "In7.Cu")
		(net "M_B_MA9")
	)
	(segment
		(start 137.0076 -13.589)
		(end 136.8044 -13.7922)
		(width 0.1905)
		(layer "In7.Cu")
		(net "M_B_MA9")
	)
	(segment
		(start 153.7716 -7.647178)
		(end 153.7716 -10.4902)
		(width 0.1905)
		(layer "In7.Cu")
		(net "M_B_MA9")
	)
	(segment
		(start 102.997 -24.3078)
		(end 100.1649 -27.1399)
		(width 0.1016)
		(layer "In7.Cu")
		(net "M_B_MA9")
	)
	(segment
		(start 100.279454 -30.175454)
		(end 100.456492 -30.352492)
		(width 0.1016)
		(layer "In7.Cu")
		(net "M_B_MA9")
	)
	(segment
		(start 136.8044 -15.75435)
		(end 136.6139 -15.94485)
		(width 0.1905)
		(layer "In7.Cu")
		(net "M_B_MA9")
	)
	(segment
		(start 156.557218 -6.834378)
		(end 154.5844 -6.834378)
		(width 0.1905)
		(layer "In7.Cu")
		(net "M_B_MA9")
	)
	(segment
		(start 145.4658 -15.747746)
		(end 145.4658 -13.7922)
		(width 0.1905)
		(layer "In7.Cu")
		(net "M_B_MA9")
	)
	(segment
		(start 100.456492 -30.352492)
		(end 100.85832 -30.352492)
		(width 0.1016)
		(layer "In7.Cu")
		(net "M_B_MA9")
	)
	(segment
		(start 156.942028 -5.41655)
		(end 156.942028 -6.449568)
		(width 0.1905)
		(layer "In7.Cu")
		(net "M_B_MA9")
	)
	(segment
		(start 154.5844 -6.834378)
		(end 153.7716 -7.647178)
		(width 0.1905)
		(layer "In7.Cu")
		(net "M_B_MA9")
	)
	(segment
		(start 145.2626 -13.589)
		(end 137.0076 -13.589)
		(width 0.1905)
		(layer "In7.Cu")
		(net "M_B_MA9")
	)
	(segment
		(start 100.1649 -27.1399)
		(end 100.1649 -28.8163)
		(width 0.1016)
		(layer "In7.Cu")
		(net "M_B_MA9")
	)
	(segment
		(start 145.4658 -13.7922)
		(end 145.2626 -13.589)
		(width 0.1905)
		(layer "In7.Cu")
		(net "M_B_MA9")
	)
	(segment
		(start 136.8044 -13.7922)
		(end 136.8044 -15.75435)
		(width 0.1905)
		(layer "In7.Cu")
		(net "M_B_MA9")
	)
	(segment
		(start 60.452 -42.3418)
		(end 60.452 -42.7228)
		(width 0.1143)
		(layer "F.Cu")
		(net "SMBUS_HOST_DATA")
	)
	(segment
		(start 34.325306 -40.92575)
		(end 33.315402 -41.935654)
		(width 0.1143)
		(layer "F.Cu")
		(net "SMBUS_HOST_DATA")
	)
	(segment
		(start 37.2364 -40.482774)
		(end 36.793424 -40.92575)
		(width 0.1143)
		(layer "F.Cu")
		(net "SMBUS_HOST_DATA")
	)
	(segment
		(start 82.296 -42.263568)
		(end 82.298032 -42.261536)
		(width 0.1143)
		(layer "F.Cu")
		(net "SMBUS_HOST_DATA")
	)
	(segment
		(start 65.786 -47.899574)
		(end 66.527426 -48.641)
		(width 0.1143)
		(layer "F.Cu")
		(net "SMBUS_HOST_DATA")
	)
	(segment
		(start 33.315402 -41.935654)
		(end 33.315402 -49.266602)
		(width 0.1143)
		(layer "F.Cu")
		(net "SMBUS_HOST_DATA")
	)
	(segment
		(start 81.836768 -42.385234)
		(end 81.958434 -42.263568)
		(width 0.1143)
		(layer "F.Cu")
		(net "SMBUS_HOST_DATA")
	)
	(segment
		(start 62.9793 -43.61815)
		(end 64.29375 -44.9326)
		(width 0.1143)
		(layer "F.Cu")
		(net "SMBUS_HOST_DATA")
	)
	(segment
		(start 65.30975 -45.418756)
		(end 65.30975 -46.706282)
		(width 0.1143)
		(layer "F.Cu")
		(net "SMBUS_HOST_DATA")
	)
	(segment
		(start 36.32835 -52.27955)
		(end 34.990278 -50.941478)
		(width 0.1143)
		(layer "F.Cu")
		(net "SMBUS_HOST_DATA")
	)
	(segment
		(start 64.823594 -44.9326)
		(end 65.30975 -45.418756)
		(width 0.1143)
		(layer "F.Cu")
		(net "SMBUS_HOST_DATA")
	)
	(segment
		(start 36.793424 -40.92575)
		(end 34.325306 -40.92575)
		(width 0.1143)
		(layer "F.Cu")
		(net "SMBUS_HOST_DATA")
	)
	(segment
		(start 66.527426 -48.641)
		(end 66.7258 -48.641)
		(width 0.1143)
		(layer "F.Cu")
		(net "SMBUS_HOST_DATA")
	)
	(segment
		(start 36.321238 -52.804314)
		(end 36.32835 -52.797202)
		(width 0.1143)
		(layer "F.Cu")
		(net "SMBUS_HOST_DATA")
	)
	(segment
		(start 81.958434 -42.263568)
		(end 82.296 -42.263568)
		(width 0.1143)
		(layer "F.Cu")
		(net "SMBUS_HOST_DATA")
	)
	(segment
		(start 65.786 -47.182532)
		(end 65.786 -47.899574)
		(width 0.1143)
		(layer "F.Cu")
		(net "SMBUS_HOST_DATA")
	)
	(segment
		(start 61.34735 -43.61815)
		(end 62.9793 -43.61815)
		(width 0.1143)
		(layer "F.Cu")
		(net "SMBUS_HOST_DATA")
	)
	(segment
		(start 82.298032 -42.261536)
		(end 82.303366 -42.261536)
		(width 0.1143)
		(layer "F.Cu")
		(net "SMBUS_HOST_DATA")
	)
	(segment
		(start 64.29375 -44.9326)
		(end 64.823594 -44.9326)
		(width 0.1143)
		(layer "F.Cu")
		(net "SMBUS_HOST_DATA")
	)
	(segment
		(start 65.30975 -46.706282)
		(end 65.786 -47.182532)
		(width 0.1143)
		(layer "F.Cu")
		(net "SMBUS_HOST_DATA")
	)
	(segment
		(start 37.592 -39.5478)
		(end 37.2364 -39.9034)
		(width 0.1143)
		(layer "F.Cu")
		(net "SMBUS_HOST_DATA")
	)
	(segment
		(start 37.2364 -39.9034)
		(end 37.2364 -40.482774)
		(width 0.1143)
		(layer "F.Cu")
		(net "SMBUS_HOST_DATA")
	)
	(segment
		(start 33.315402 -49.266602)
		(end 34.990278 -50.941478)
		(width 0.1143)
		(layer "F.Cu")
		(net "SMBUS_HOST_DATA")
	)
	(segment
		(start 60.452 -42.7228)
		(end 61.34735 -43.61815)
		(width 0.1143)
		(layer "F.Cu")
		(net "SMBUS_HOST_DATA")
	)
	(segment
		(start 36.32835 -52.797202)
		(end 36.32835 -52.27955)
		(width 0.1143)
		(layer "F.Cu")
		(net "SMBUS_HOST_DATA")
	)
	(via
		(at 66.7258 -48.641)
		(size 0.508)
		(drill 0.254)
		(layers "F.Cu" "B.Cu")
		(net "SMBUS_HOST_DATA")
	)
	(via
		(at 24.003 -19.3548)
		(size 0.508)
		(drill 0.254)
		(layers "F.Cu" "B.Cu")
		(net "SMBUS_HOST_DATA")
	)
	(via
		(at 36.321238 -52.804314)
		(size 0.508)
		(drill 0.254)
		(layers "F.Cu" "B.Cu")
		(net "SMBUS_HOST_DATA")
	)
	(via
		(at 75.3364 -48.0314)
		(size 0.508)
		(drill 0.254)
		(layers "F.Cu" "B.Cu")
		(net "SMBUS_HOST_DATA")
	)
	(via
		(at 82.303366 -42.261536)
		(size 0.4318)
		(drill 0.2032)
		(layers "F.Cu" "B.Cu")
		(net "SMBUS_HOST_DATA")
	)
	(via
		(at 34.990278 -50.941478)
		(size 0.7112)
		(drill 0.3556)
		(layers "F.Cu" "B.Cu")
		(net "SMBUS_HOST_DATA")
	)
	(segment
		(start 31.0261 -16.5227)
		(end 33.9725 -16.5227)
		(width 0.1143)
		(layer "B.Cu")
		(net "SMBUS_HOST_DATA")
	)
	(segment
		(start 29.5783 -17.9705)
		(end 31.0261 -16.5227)
		(width 0.1143)
		(layer "B.Cu")
		(net "SMBUS_HOST_DATA")
	)
	(segment
		(start 75.86218 -46.84522)
		(end 75.3364 -47.371)
		(width 0.1143)
		(layer "B.Cu")
		(net "SMBUS_HOST_DATA")
	)
	(segment
		(start 75.3618 -48.0568)
		(end 75.3364 -48.0314)
		(width 0.1143)
		(layer "B.Cu")
		(net "SMBUS_HOST_DATA")
	)
	(segment
		(start 75.3618 -49.149)
		(end 75.3618 -48.0568)
		(width 0.1143)
		(layer "B.Cu")
		(net "SMBUS_HOST_DATA")
	)
	(segment
		(start 24.003 -19.3548)
		(end 25.3873 -17.9705)
		(width 0.1143)
		(layer "B.Cu")
		(net "SMBUS_HOST_DATA")
	)
	(segment
		(start 25.3873 -17.9705)
		(end 29.5783 -17.9705)
		(width 0.1143)
		(layer "B.Cu")
		(net "SMBUS_HOST_DATA")
	)
	(segment
		(start 33.9725 -16.5227)
		(end 34.2392 -16.256)
		(width 0.1143)
		(layer "B.Cu")
		(net "SMBUS_HOST_DATA")
	)
	(segment
		(start 82.303366 -42.261536)
		(end 79.978758 -44.586144)
		(width 0.1143)
		(layer "B.Cu")
		(net "SMBUS_HOST_DATA")
	)
	(segment
		(start 75.3364 -47.371)
		(end 75.3364 -48.0314)
		(width 0.1143)
		(layer "B.Cu")
		(net "SMBUS_HOST_DATA")
	)
	(segment
		(start 79.978758 -46.46168)
		(end 79.595218 -46.84522)
		(width 0.1143)
		(layer "B.Cu")
		(net "SMBUS_HOST_DATA")
	)
	(segment
		(start 79.978758 -44.586144)
		(end 79.978758 -46.46168)
		(width 0.1143)
		(layer "B.Cu")
		(net "SMBUS_HOST_DATA")
	)
	(segment
		(start 79.595218 -46.84522)
		(end 75.86218 -46.84522)
		(width 0.1143)
		(layer "B.Cu")
		(net "SMBUS_HOST_DATA")
	)
	(segment
		(start 28.956 -24.13)
		(end 28.956 -31.877)
		(width 0.0889)
		(layer "In2.Cu")
		(net "SMBUS_HOST_DATA")
	)
	(segment
		(start 36.044886 -52.804314)
		(end 36.321238 -52.804314)
		(width 0.0889)
		(layer "In2.Cu")
		(net "SMBUS_HOST_DATA")
	)
	(segment
		(start 32.23895 -48.998378)
		(end 36.044886 -52.804314)
		(width 0.0889)
		(layer "In2.Cu")
		(net "SMBUS_HOST_DATA")
	)
	(segment
		(start 28.956 -31.877)
		(end 31.21025 -34.13125)
		(width 0.0889)
		(layer "In2.Cu")
		(net "SMBUS_HOST_DATA")
	)
	(segment
		(start 30.8102 -42.777918)
		(end 32.23895 -44.206668)
		(width 0.0889)
		(layer "In2.Cu")
		(net "SMBUS_HOST_DATA")
	)
	(segment
		(start 24.1808 -19.3548)
		(end 28.956 -24.13)
		(width 0.0889)
		(layer "In2.Cu")
		(net "SMBUS_HOST_DATA")
	)
	(segment
		(start 30.8102 -38.4302)
		(end 30.8102 -42.777918)
		(width 0.0889)
		(layer "In2.Cu")
		(net "SMBUS_HOST_DATA")
	)
	(segment
		(start 31.21025 -34.13125)
		(end 31.21025 -38.03015)
		(width 0.0889)
		(layer "In2.Cu")
		(net "SMBUS_HOST_DATA")
	)
	(segment
		(start 31.21025 -38.03015)
		(end 30.8102 -38.4302)
		(width 0.0889)
		(layer "In2.Cu")
		(net "SMBUS_HOST_DATA")
	)
	(segment
		(start 24.003 -19.3548)
		(end 24.1808 -19.3548)
		(width 0.0889)
		(layer "In2.Cu")
		(net "SMBUS_HOST_DATA")
	)
	(segment
		(start 32.23895 -44.206668)
		(end 32.23895 -48.998378)
		(width 0.0889)
		(layer "In2.Cu")
		(net "SMBUS_HOST_DATA")
	)
	(segment
		(start 47.82058 -54.85765)
		(end 48.08728 -54.59095)
		(width 0.0889)
		(layer "In4.Cu")
		(net "SMBUS_HOST_DATA")
	)
	(segment
		(start 36.321238 -52.916074)
		(end 38.262814 -54.85765)
		(width 0.0889)
		(layer "In4.Cu")
		(net "SMBUS_HOST_DATA")
	)
	(segment
		(start 38.262814 -54.85765)
		(end 47.82058 -54.85765)
		(width 0.0889)
		(layer "In4.Cu")
		(net "SMBUS_HOST_DATA")
	)
	(segment
		(start 62.52591 -49.4538)
		(end 65.913 -49.4538)
		(width 0.0889)
		(layer "In4.Cu")
		(net "SMBUS_HOST_DATA")
	)
	(segment
		(start 61.332618 -50.9651)
		(end 62.208156 -50.089562)
		(width 0.0889)
		(layer "In4.Cu")
		(net "SMBUS_HOST_DATA")
	)
	(segment
		(start 54.714902 -54.59095)
		(end 58.569352 -50.7365)
		(width 0.0889)
		(layer "In4.Cu")
		(net "SMBUS_HOST_DATA")
	)
	(segment
		(start 65.913 -49.4538)
		(end 66.7258 -48.641)
		(width 0.0889)
		(layer "In4.Cu")
		(net "SMBUS_HOST_DATA")
	)
	(segment
		(start 48.08728 -54.59095)
		(end 54.714902 -54.59095)
		(width 0.0889)
		(layer "In4.Cu")
		(net "SMBUS_HOST_DATA")
	)
	(segment
		(start 62.208156 -49.771554)
		(end 62.52591 -49.4538)
		(width 0.0889)
		(layer "In4.Cu")
		(net "SMBUS_HOST_DATA")
	)
	(segment
		(start 59.926982 -50.9651)
		(end 61.332618 -50.9651)
		(width 0.0889)
		(layer "In4.Cu")
		(net "SMBUS_HOST_DATA")
	)
	(segment
		(start 36.321238 -52.804314)
		(end 36.321238 -52.916074)
		(width 0.0889)
		(layer "In4.Cu")
		(net "SMBUS_HOST_DATA")
	)
	(segment
		(start 62.208156 -50.089562)
		(end 62.208156 -49.771554)
		(width 0.0889)
		(layer "In4.Cu")
		(net "SMBUS_HOST_DATA")
	)
	(segment
		(start 59.698382 -50.7365)
		(end 59.926982 -50.9651)
		(width 0.0889)
		(layer "In4.Cu")
		(net "SMBUS_HOST_DATA")
	)
	(segment
		(start 58.569352 -50.7365)
		(end 59.698382 -50.7365)
		(width 0.0889)
		(layer "In4.Cu")
		(net "SMBUS_HOST_DATA")
	)
	(segment
		(start 73.4314 -48.5394)
		(end 74.8284 -48.5394)
		(width 0.0889)
		(layer "In7.Cu")
		(net "SMBUS_HOST_DATA")
	)
	(segment
		(start 68.17614 -48.59274)
		(end 72.228456 -48.59274)
		(width 0.0889)
		(layer "In7.Cu")
		(net "SMBUS_HOST_DATA")
	)
	(segment
		(start 74.8284 -48.5394)
		(end 75.3364 -48.0314)
		(width 0.0889)
		(layer "In7.Cu")
		(net "SMBUS_HOST_DATA")
	)
	(segment
		(start 66.7258 -48.641)
		(end 67.08775 -48.27905)
		(width 0.0889)
		(layer "In7.Cu")
		(net "SMBUS_HOST_DATA")
	)
	(segment
		(start 73.17994 -48.28794)
		(end 73.4314 -48.5394)
		(width 0.0889)
		(layer "In7.Cu")
		(net "SMBUS_HOST_DATA")
	)
	(segment
		(start 67.08775 -48.27905)
		(end 67.86245 -48.27905)
		(width 0.0889)
		(layer "In7.Cu")
		(net "SMBUS_HOST_DATA")
	)
	(segment
		(start 72.533256 -48.28794)
		(end 73.17994 -48.28794)
		(width 0.0889)
		(layer "In7.Cu")
		(net "SMBUS_HOST_DATA")
	)
	(segment
		(start 67.86245 -48.27905)
		(end 68.17614 -48.59274)
		(width 0.0889)
		(layer "In7.Cu")
		(net "SMBUS_HOST_DATA")
	)
	(segment
		(start 72.228456 -48.59274)
		(end 72.533256 -48.28794)
		(width 0.0889)
		(layer "In7.Cu")
		(net "SMBUS_HOST_DATA")
	)
	(segment
		(start 115.951 -32.0294)
		(end 115.7224 -32.258)
		(width 0.1016)
		(layer "F.Cu")
		(net "M_B_DQS_DN5")
	)
	(segment
		(start 111.686848 -34.749994)
		(end 111.153448 -34.749994)
		(width 0.1016)
		(layer "F.Cu")
		(net "M_B_DQS_DN5")
	)
	(segment
		(start 112.070134 -34.366708)
		(end 111.686848 -34.749994)
		(width 0.1016)
		(layer "F.Cu")
		(net "M_B_DQS_DN5")
	)
	(segment
		(start 176.544478 -5.804662)
		(end 176.537366 -5.804662)
		(width 0.1778)
		(layer "F.Cu")
		(net "M_B_DQS_DN5")
	)
	(segment
		(start 115.7224 -32.258)
		(end 114.638074 -32.258)
		(width 0.1016)
		(layer "F.Cu")
		(net "M_B_DQS_DN5")
	)
	(segment
		(start 176.797462 -6.057646)
		(end 176.544478 -5.804662)
		(width 0.1778)
		(layer "F.Cu")
		(net "M_B_DQS_DN5")
	)
	(segment
		(start 176.649888 -9.15289)
		(end 176.797462 -9.005316)
		(width 0.1778)
		(layer "F.Cu")
		(net "M_B_DQS_DN5")
	)
	(segment
		(start 112.529366 -34.366708)
		(end 112.070134 -34.366708)
		(width 0.1016)
		(layer "F.Cu")
		(net "M_B_DQS_DN5")
	)
	(segment
		(start 176.797462 -9.005316)
		(end 176.797462 -6.057646)
		(width 0.1778)
		(layer "F.Cu")
		(net "M_B_DQS_DN5")
	)
	(segment
		(start 176.649888 -9.897364)
		(end 176.649888 -9.15289)
		(width 0.1778)
		(layer "F.Cu")
		(net "M_B_DQS_DN5")
	)
	(segment
		(start 114.638074 -32.258)
		(end 112.529366 -34.366708)
		(width 0.1016)
		(layer "F.Cu")
		(net "M_B_DQS_DN5")
	)
	(via
		(at 115.951 -32.0294)
		(size 0.4318)
		(drill 0.2032)
		(layers "F.Cu" "B.Cu")
		(net "M_B_DQS_DN5")
	)
	(via
		(at 176.537366 -5.804662)
		(size 0.4318)
		(drill 0.2032)
		(layers "F.Cu" "B.Cu")
		(net "M_B_DQS_DN5")
	)
	(segment
		(start 176.649888 -1.690624)
		(end 176.649888 -2.470404)
		(width 0.1778)
		(layer "B.Cu")
		(net "M_B_DQS_DN5")
	)
	(segment
		(start 176.649888 -2.470404)
		(end 176.797462 -2.617978)
		(width 0.1778)
		(layer "B.Cu")
		(net "M_B_DQS_DN5")
	)
	(segment
		(start 176.797462 -5.544566)
		(end 176.537366 -5.804662)
		(width 0.1778)
		(layer "B.Cu")
		(net "M_B_DQS_DN5")
	)
	(segment
		(start 176.797462 -2.617978)
		(end 176.797462 -5.544566)
		(width 0.1778)
		(layer "B.Cu")
		(net "M_B_DQS_DN5")
	)
	(segment
		(start 165.339776 -18.6944)
		(end 165.0238 -18.378424)
		(width 0.1524)
		(layer "In2.Cu")
		(net "M_B_DQS_DN5")
	)
	(segment
		(start 165.6588 -19.4818)
		(end 165.8112 -19.3294)
		(width 0.1524)
		(layer "In2.Cu")
		(net "M_B_DQS_DN5")
	)
	(segment
		(start 165.339776 -17.4244)
		(end 167.90289 -17.4244)
		(width 0.1524)
		(layer "In2.Cu")
		(net "M_B_DQS_DN5")
	)
	(segment
		(start 163.382452 -19.4818)
		(end 165.6588 -19.4818)
		(width 0.1524)
		(layer "In2.Cu")
		(net "M_B_DQS_DN5")
	)
	(segment
		(start 176.6316 -9.332976)
		(end 176.6316 -6.489954)
		(width 0.1524)
		(layer "In2.Cu")
		(net "M_B_DQS_DN5")
	)
	(segment
		(start 165.6588 -18.6944)
		(end 165.339776 -18.6944)
		(width 0.1524)
		(layer "In2.Cu")
		(net "M_B_DQS_DN5")
	)
	(segment
		(start 118.4402 -30.617414)
		(end 117.371114 -31.6865)
		(width 0.1016)
		(layer "In2.Cu")
		(net "M_B_DQS_DN5")
	)
	(segment
		(start 118.4402 -30.617414)
		(end 123.828556 -30.617414)
		(width 0.1524)
		(layer "In2.Cu")
		(net "M_B_DQS_DN5")
	)
	(segment
		(start 176.6316 -6.489954)
		(end 176.784 -6.337554)
		(width 0.1524)
		(layer "In2.Cu")
		(net "M_B_DQS_DN5")
	)
	(segment
		(start 176.541684 -5.804662)
		(end 176.537366 -5.804662)
		(width 0.1524)
		(layer "In2.Cu")
		(net "M_B_DQS_DN5")
	)
	(segment
		(start 176.784 -6.337554)
		(end 176.784 -6.046978)
		(width 0.1524)
		(layer "In2.Cu")
		(net "M_B_DQS_DN5")
	)
	(segment
		(start 176.312576 -9.652)
		(end 176.6316 -9.332976)
		(width 0.1524)
		(layer "In2.Cu")
		(net "M_B_DQS_DN5")
	)
	(segment
		(start 165.8112 -19.3294)
		(end 165.8112 -18.8468)
		(width 0.1524)
		(layer "In2.Cu")
		(net "M_B_DQS_DN5")
	)
	(segment
		(start 126.08179 -28.36418)
		(end 154.500072 -28.36418)
		(width 0.1524)
		(layer "In2.Cu")
		(net "M_B_DQS_DN5")
	)
	(segment
		(start 175.67529 -9.652)
		(end 176.312576 -9.652)
		(width 0.1524)
		(layer "In2.Cu")
		(net "M_B_DQS_DN5")
	)
	(segment
		(start 165.0238 -18.378424)
		(end 165.0238 -17.740376)
		(width 0.1524)
		(layer "In2.Cu")
		(net "M_B_DQS_DN5")
	)
	(segment
		(start 165.8112 -18.8468)
		(end 165.6588 -18.6944)
		(width 0.1524)
		(layer "In2.Cu")
		(net "M_B_DQS_DN5")
	)
	(segment
		(start 117.371114 -31.6865)
		(end 116.2939 -31.6865)
		(width 0.1016)
		(layer "In2.Cu")
		(net "M_B_DQS_DN5")
	)
	(segment
		(start 154.500072 -28.36418)
		(end 163.382452 -19.4818)
		(width 0.1524)
		(layer "In2.Cu")
		(net "M_B_DQS_DN5")
	)
	(segment
		(start 176.784 -6.046978)
		(end 176.541684 -5.804662)
		(width 0.1524)
		(layer "In2.Cu")
		(net "M_B_DQS_DN5")
	)
	(segment
		(start 123.828556 -30.617414)
		(end 126.08179 -28.36418)
		(width 0.1524)
		(layer "In2.Cu")
		(net "M_B_DQS_DN5")
	)
	(segment
		(start 167.90289 -17.4244)
		(end 175.67529 -9.652)
		(width 0.1524)
		(layer "In2.Cu")
		(net "M_B_DQS_DN5")
	)
	(segment
		(start 116.2939 -31.6865)
		(end 115.951 -32.0294)
		(width 0.1016)
		(layer "In2.Cu")
		(net "M_B_DQS_DN5")
	)
	(segment
		(start 165.0238 -17.740376)
		(end 165.339776 -17.4244)
		(width 0.1524)
		(layer "In2.Cu")
		(net "M_B_DQS_DN5")
	)
	(segment
		(start 186.1185 -38.9255)
		(end 186.68873 -38.9255)
		(width 0.2032)
		(layer "F.Cu")
		(net "VR_PVDDR_A_OCP")
	)
	(segment
		(start 185.674 -39.37)
		(end 186.1185 -38.9255)
		(width 0.2032)
		(layer "F.Cu")
		(net "VR_PVDDR_A_OCP")
	)
	(segment
		(start 187.579 -38.03523)
		(end 187.579 -37.719)
		(width 0.2032)
		(layer "F.Cu")
		(net "VR_PVDDR_A_OCP")
	)
	(segment
		(start 185.674 -39.4462)
		(end 185.674 -39.37)
		(width 0.2032)
		(layer "F.Cu")
		(net "VR_PVDDR_A_OCP")
	)
	(segment
		(start 187.856368 -37.441632)
		(end 187.579 -37.719)
		(width 0.2032)
		(layer "F.Cu")
		(net "VR_PVDDR_A_OCP")
	)
	(segment
		(start 186.68873 -38.9255)
		(end 187.579 -38.03523)
		(width 0.2032)
		(layer "F.Cu")
		(net "VR_PVDDR_A_OCP")
	)
	(segment
		(start 187.856368 -36.376102)
		(end 187.856368 -37.441632)
		(width 0.2032)
		(layer "F.Cu")
		(net "VR_PVDDR_A_OCP")
	)
	(via
		(at 187.579 -37.719)
		(size 0.7112)
		(drill 0.3556)
		(layers "F.Cu" "B.Cu")
		(net "VR_PVDDR_A_OCP")
	)
	(segment
		(start 37.7317 -40.202104)
		(end 38.354 -39.579804)
		(width 0.1143)
		(layer "F.Cu")
		(net "SMBUS_HOST_CLK")
	)
	(segment
		(start 74.287126 -45.04055)
		(end 74.757026 -44.57065)
		(width 0.1143)
		(layer "F.Cu")
		(net "SMBUS_HOST_CLK")
	)
	(segment
		(start 71.82485 -43.618912)
		(end 71.82485 -43.713654)
		(width 0.1143)
		(layer "F.Cu")
		(net "SMBUS_HOST_CLK")
	)
	(segment
		(start 36.998656 -41.42105)
		(end 37.7317 -40.688006)
		(width 0.1143)
		(layer "F.Cu")
		(net "SMBUS_HOST_CLK")
	)
	(segment
		(start 79.385668 -41.500044)
		(end 80.33766 -41.500044)
		(width 0.1143)
		(layer "F.Cu")
		(net "SMBUS_HOST_CLK")
	)
	(segment
		(start 37.7317 -40.688006)
		(end 37.7317 -40.202104)
		(width 0.1143)
		(layer "F.Cu")
		(net "SMBUS_HOST_CLK")
	)
	(segment
		(start 80.519778 -41.815766)
		(end 80.821276 -42.117264)
		(width 0.1143)
		(layer "F.Cu")
		(net "SMBUS_HOST_CLK")
	)
	(segment
		(start 75.55865 -43.650408)
		(end 76.82738 -42.381678)
		(width 0.1143)
		(layer "F.Cu")
		(net "SMBUS_HOST_CLK")
	)
	(segment
		(start 33.810702 -42.140886)
		(end 34.530538 -41.42105)
		(width 0.1143)
		(layer "F.Cu")
		(net "SMBUS_HOST_CLK")
	)
	(segment
		(start 80.821276 -42.117264)
		(end 81.07934 -42.117264)
		(width 0.1143)
		(layer "F.Cu")
		(net "SMBUS_HOST_CLK")
	)
	(segment
		(start 81.48955 -41.707054)
		(end 81.646268 -41.707054)
		(width 0.1143)
		(layer "F.Cu")
		(net "SMBUS_HOST_CLK")
	)
	(segment
		(start 37.184584 -52.74945)
		(end 37.184584 -52.336446)
		(width 0.1143)
		(layer "F.Cu")
		(net "SMBUS_HOST_CLK")
	)
	(segment
		(start 33.810702 -48.962564)
		(end 33.810702 -42.140886)
		(width 0.1143)
		(layer "F.Cu")
		(net "SMBUS_HOST_CLK")
	)
	(segment
		(start 72.545956 -45.04055)
		(end 74.287126 -45.04055)
		(width 0.1143)
		(layer "F.Cu")
		(net "SMBUS_HOST_CLK")
	)
	(segment
		(start 81.07934 -42.117264)
		(end 81.48955 -41.707054)
		(width 0.1143)
		(layer "F.Cu")
		(net "SMBUS_HOST_CLK")
	)
	(segment
		(start 80.519778 -41.682162)
		(end 80.519778 -41.815766)
		(width 0.1143)
		(layer "F.Cu")
		(net "SMBUS_HOST_CLK")
	)
	(segment
		(start 68.8848 -41.6306)
		(end 68.707 -41.4528)
		(width 0.1143)
		(layer "F.Cu")
		(net "SMBUS_HOST_CLK")
	)
	(segment
		(start 74.757026 -44.57065)
		(end 74.950066 -44.57065)
		(width 0.1143)
		(layer "F.Cu")
		(net "SMBUS_HOST_CLK")
	)
	(segment
		(start 71.8312 -44.325794)
		(end 72.545956 -45.04055)
		(width 0.1143)
		(layer "F.Cu")
		(net "SMBUS_HOST_CLK")
	)
	(segment
		(start 68.8848 -42.2402)
		(end 69.3674 -42.7228)
		(width 0.1143)
		(layer "F.Cu")
		(net "SMBUS_HOST_CLK")
	)
	(segment
		(start 71.8312 -43.720004)
		(end 71.8312 -44.325794)
		(width 0.1143)
		(layer "F.Cu")
		(net "SMBUS_HOST_CLK")
	)
	(segment
		(start 75.536044 -43.650408)
		(end 75.55865 -43.650408)
		(width 0.1143)
		(layer "F.Cu")
		(net "SMBUS_HOST_CLK")
	)
	(segment
		(start 78.504034 -42.381678)
		(end 79.385668 -41.500044)
		(width 0.1143)
		(layer "F.Cu")
		(net "SMBUS_HOST_CLK")
	)
	(segment
		(start 38.354 -39.579804)
		(end 38.354 -39.5478)
		(width 0.1143)
		(layer "F.Cu")
		(net "SMBUS_HOST_CLK")
	)
	(segment
		(start 75.24369 -43.942762)
		(end 75.536044 -43.650408)
		(width 0.1143)
		(layer "F.Cu")
		(net "SMBUS_HOST_CLK")
	)
	(segment
		(start 71.82485 -43.713654)
		(end 71.8312 -43.720004)
		(width 0.1143)
		(layer "F.Cu")
		(net "SMBUS_HOST_CLK")
	)
	(segment
		(start 74.950066 -44.57065)
		(end 75.24369 -44.277026)
		(width 0.1143)
		(layer "F.Cu")
		(net "SMBUS_HOST_CLK")
	)
	(segment
		(start 68.8848 -42.2402)
		(end 68.8848 -41.6306)
		(width 0.1143)
		(layer "F.Cu")
		(net "SMBUS_HOST_CLK")
	)
	(segment
		(start 37.184584 -52.336446)
		(end 33.810702 -48.962564)
		(width 0.1143)
		(layer "F.Cu")
		(net "SMBUS_HOST_CLK")
	)
	(segment
		(start 68.072 -42.2402)
		(end 68.8848 -42.2402)
		(width 0.1143)
		(layer "F.Cu")
		(net "SMBUS_HOST_CLK")
	)
	(segment
		(start 76.82738 -42.381678)
		(end 78.504034 -42.381678)
		(width 0.1143)
		(layer "F.Cu")
		(net "SMBUS_HOST_CLK")
	)
	(segment
		(start 69.3674 -42.7228)
		(end 70.928738 -42.7228)
		(width 0.1143)
		(layer "F.Cu")
		(net "SMBUS_HOST_CLK")
	)
	(segment
		(start 34.530538 -41.42105)
		(end 36.998656 -41.42105)
		(width 0.1143)
		(layer "F.Cu")
		(net "SMBUS_HOST_CLK")
	)
	(segment
		(start 80.33766 -41.500044)
		(end 80.519778 -41.682162)
		(width 0.1143)
		(layer "F.Cu")
		(net "SMBUS_HOST_CLK")
	)
	(segment
		(start 70.928738 -42.7228)
		(end 71.82485 -43.618912)
		(width 0.1143)
		(layer "F.Cu")
		(net "SMBUS_HOST_CLK")
	)
	(segment
		(start 75.24369 -44.277026)
		(end 75.24369 -43.942762)
		(width 0.1143)
		(layer "F.Cu")
		(net "SMBUS_HOST_CLK")
	)
	(via
		(at 68.707 -41.4528)
		(size 0.508)
		(drill 0.254)
		(layers "F.Cu" "B.Cu")
		(net "SMBUS_HOST_CLK")
	)
	(via
		(at 37.184584 -52.74945)
		(size 0.508)
		(drill 0.254)
		(layers "F.Cu" "B.Cu")
		(net "SMBUS_HOST_CLK")
	)
	(via
		(at 24.8666 -19.3548)
		(size 0.508)
		(drill 0.254)
		(layers "F.Cu" "B.Cu")
		(net "SMBUS_HOST_CLK")
	)
	(via
		(at 67.64528 -41.70172)
		(size 0.7112)
		(drill 0.3556)
		(layers "F.Cu" "B.Cu")
		(net "SMBUS_HOST_CLK")
	)
	(via
		(at 66.3702 -47.8282)
		(size 0.508)
		(drill 0.254)
		(layers "F.Cu" "B.Cu")
		(net "SMBUS_HOST_CLK")
	)
	(segment
		(start 66.4718 -45.401992)
		(end 67.67195 -44.201842)
		(width 0.1143)
		(layer "B.Cu")
		(net "SMBUS_HOST_CLK")
	)
	(segment
		(start 67.437 -41.91)
		(end 67.64528 -41.70172)
		(width 0.1143)
		(layer "B.Cu")
		(net "SMBUS_HOST_CLK")
	)
	(segment
		(start 67.67195 -44.201842)
		(end 67.67195 -43.775122)
		(width 0.1143)
		(layer "B.Cu")
		(net "SMBUS_HOST_CLK")
	)
	(segment
		(start 67.8942 -41.4528)
		(end 67.64528 -41.70172)
		(width 0.1143)
		(layer "B.Cu")
		(net "SMBUS_HOST_CLK")
	)
	(segment
		(start 31.369 -17.018)
		(end 34.2392 -17.018)
		(width 0.1143)
		(layer "B.Cu")
		(net "SMBUS_HOST_CLK")
	)
	(segment
		(start 68.707 -41.4528)
		(end 67.8942 -41.4528)
		(width 0.1143)
		(layer "B.Cu")
		(net "SMBUS_HOST_CLK")
	)
	(segment
		(start 24.8666 -19.3548)
		(end 25.7556 -18.4658)
		(width 0.1143)
		(layer "B.Cu")
		(net "SMBUS_HOST_CLK")
	)
	(segment
		(start 29.9212 -18.4658)
		(end 31.369 -17.018)
		(width 0.1143)
		(layer "B.Cu")
		(net "SMBUS_HOST_CLK")
	)
	(segment
		(start 25.7556 -18.4658)
		(end 29.9212 -18.4658)
		(width 0.1143)
		(layer "B.Cu")
		(net "SMBUS_HOST_CLK")
	)
	(segment
		(start 66.3702 -47.8282)
		(end 66.4718 -47.7266)
		(width 0.1143)
		(layer "B.Cu")
		(net "SMBUS_HOST_CLK")
	)
	(segment
		(start 67.437 -43.540172)
		(end 67.437 -41.91)
		(width 0.1143)
		(layer "B.Cu")
		(net "SMBUS_HOST_CLK")
	)
	(segment
		(start 66.4718 -47.7266)
		(end 66.4718 -45.401992)
		(width 0.1143)
		(layer "B.Cu")
		(net "SMBUS_HOST_CLK")
	)
	(segment
		(start 67.67195 -43.775122)
		(end 67.437 -43.540172)
		(width 0.1143)
		(layer "B.Cu")
		(net "SMBUS_HOST_CLK")
	)
	(segment
		(start 36.333684 -51.89855)
		(end 37.184584 -52.74945)
		(width 0.0889)
		(layer "In2.Cu")
		(net "SMBUS_HOST_CLK")
	)
	(segment
		(start 32.70885 -43.977814)
		(end 32.70885 -48.749712)
		(width 0.0889)
		(layer "In2.Cu")
		(net "SMBUS_HOST_CLK")
	)
	(segment
		(start 31.2801 -38.625018)
		(end 31.2801 -42.549064)
		(width 0.0889)
		(layer "In2.Cu")
		(net "SMBUS_HOST_CLK")
	)
	(segment
		(start 31.68015 -32.636206)
		(end 31.68015 -38.224968)
		(width 0.0889)
		(layer "In2.Cu")
		(net "SMBUS_HOST_CLK")
	)
	(segment
		(start 31.2801 -42.549064)
		(end 32.70885 -43.977814)
		(width 0.0889)
		(layer "In2.Cu")
		(net "SMBUS_HOST_CLK")
	)
	(segment
		(start 29.4259 -30.381956)
		(end 31.68015 -32.636206)
		(width 0.0889)
		(layer "In2.Cu")
		(net "SMBUS_HOST_CLK")
	)
	(segment
		(start 31.68015 -38.224968)
		(end 31.2801 -38.625018)
		(width 0.0889)
		(layer "In2.Cu")
		(net "SMBUS_HOST_CLK")
	)
	(segment
		(start 29.4259 -23.935182)
		(end 29.4259 -30.381956)
		(width 0.0889)
		(layer "In2.Cu")
		(net "SMBUS_HOST_CLK")
	)
	(segment
		(start 24.8666 -19.3548)
		(end 24.8666 -19.375882)
		(width 0.0889)
		(layer "In2.Cu")
		(net "SMBUS_HOST_CLK")
	)
	(segment
		(start 35.857688 -51.89855)
		(end 36.333684 -51.89855)
		(width 0.0889)
		(layer "In2.Cu")
		(net "SMBUS_HOST_CLK")
	)
	(segment
		(start 24.8666 -19.375882)
		(end 29.4259 -23.935182)
		(width 0.0889)
		(layer "In2.Cu")
		(net "SMBUS_HOST_CLK")
	)
	(segment
		(start 32.70885 -48.749712)
		(end 35.857688 -51.89855)
		(width 0.0889)
		(layer "In2.Cu")
		(net "SMBUS_HOST_CLK")
	)
	(segment
		(start 61.738256 -49.576736)
		(end 62.331092 -48.9839)
		(width 0.0889)
		(layer "In4.Cu")
		(net "SMBUS_HOST_CLK")
	)
	(segment
		(start 40.894 -53.75275)
		(end 41.275 -54.13375)
		(width 0.0889)
		(layer "In4.Cu")
		(net "SMBUS_HOST_CLK")
	)
	(segment
		(start 39.905686 -53.75275)
		(end 40.894 -53.75275)
		(width 0.0889)
		(layer "In4.Cu")
		(net "SMBUS_HOST_CLK")
	)
	(segment
		(start 61.1378 -50.4952)
		(end 61.738256 -49.894744)
		(width 0.0889)
		(layer "In4.Cu")
		(net "SMBUS_HOST_CLK")
	)
	(segment
		(start 62.331092 -48.9839)
		(end 65.2145 -48.9839)
		(width 0.0889)
		(layer "In4.Cu")
		(net "SMBUS_HOST_CLK")
	)
	(segment
		(start 65.2145 -48.9839)
		(end 66.3702 -47.8282)
		(width 0.0889)
		(layer "In4.Cu")
		(net "SMBUS_HOST_CLK")
	)
	(segment
		(start 37.184584 -52.74945)
		(end 37.184584 -53.114702)
		(width 0.0889)
		(layer "In4.Cu")
		(net "SMBUS_HOST_CLK")
	)
	(segment
		(start 61.738256 -49.894744)
		(end 61.738256 -49.576736)
		(width 0.0889)
		(layer "In4.Cu")
		(net "SMBUS_HOST_CLK")
	)
	(segment
		(start 38.330632 -54.26075)
		(end 39.397686 -54.26075)
		(width 0.0889)
		(layer "In4.Cu")
		(net "SMBUS_HOST_CLK")
	)
	(segment
		(start 59.8932 -50.2666)
		(end 60.1218 -50.4952)
		(width 0.0889)
		(layer "In4.Cu")
		(net "SMBUS_HOST_CLK")
	)
	(segment
		(start 58.374534 -50.2666)
		(end 59.8932 -50.2666)
		(width 0.0889)
		(layer "In4.Cu")
		(net "SMBUS_HOST_CLK")
	)
	(segment
		(start 60.1218 -50.4952)
		(end 61.1378 -50.4952)
		(width 0.0889)
		(layer "In4.Cu")
		(net "SMBUS_HOST_CLK")
	)
	(segment
		(start 39.397686 -54.26075)
		(end 39.905686 -53.75275)
		(width 0.0889)
		(layer "In4.Cu")
		(net "SMBUS_HOST_CLK")
	)
	(segment
		(start 54.520084 -54.12105)
		(end 58.374534 -50.2666)
		(width 0.0889)
		(layer "In4.Cu")
		(net "SMBUS_HOST_CLK")
	)
	(segment
		(start 47.879762 -54.13375)
		(end 47.892462 -54.12105)
		(width 0.0889)
		(layer "In4.Cu")
		(net "SMBUS_HOST_CLK")
	)
	(segment
		(start 47.892462 -54.12105)
		(end 54.520084 -54.12105)
		(width 0.0889)
		(layer "In4.Cu")
		(net "SMBUS_HOST_CLK")
	)
	(segment
		(start 37.184584 -53.114702)
		(end 38.330632 -54.26075)
		(width 0.0889)
		(layer "In4.Cu")
		(net "SMBUS_HOST_CLK")
	)
	(segment
		(start 41.275 -54.13375)
		(end 47.879762 -54.13375)
		(width 0.0889)
		(layer "In4.Cu")
		(net "SMBUS_HOST_CLK")
	)
	(segment
		(start 193.796412 -4.605528)
		(end 194.710812 -5.519928)
		(width 0.1143)
		(layer "F.Cu")
		(net "CHB_1_SA1")
	)
	(segment
		(start 190.749936 -3.68046)
		(end 191.675004 -4.605528)
		(width 0.1143)
		(layer "F.Cu")
		(net "CHB_1_SA1")
	)
	(segment
		(start 196.596 -4.826)
		(end 197.6882 -4.826)
		(width 0.1143)
		(layer "F.Cu")
		(net "CHB_1_SA1")
	)
	(segment
		(start 197.6882 -5.588)
		(end 197.6882 -4.826)
		(width 0.1143)
		(layer "F.Cu")
		(net "CHB_1_SA1")
	)
	(segment
		(start 195.902072 -5.519928)
		(end 196.596 -4.826)
		(width 0.1143)
		(layer "F.Cu")
		(net "CHB_1_SA1")
	)
	(segment
		(start 191.675004 -4.605528)
		(end 193.796412 -4.605528)
		(width 0.1143)
		(layer "F.Cu")
		(net "CHB_1_SA1")
	)
	(segment
		(start 190.749936 -1.68402)
		(end 190.749936 -3.68046)
		(width 0.1143)
		(layer "F.Cu")
		(net "CHB_1_SA1")
	)
	(segment
		(start 194.710812 -5.519928)
		(end 195.902072 -5.519928)
		(width 0.1143)
		(layer "F.Cu")
		(net "CHB_1_SA1")
	)
	(segment
		(start 188.656468 -38.034468)
		(end 189.1538 -38.5318)
		(width 0.2032)
		(layer "F.Cu")
		(net "VR_PVDDR_A_VAUTO")
	)
	(segment
		(start 189.1792 -40.894)
		(end 189.1792 -40.259)
		(width 0.2032)
		(layer "F.Cu")
		(net "VR_PVDDR_A_VAUTO")
	)
	(segment
		(start 188.214 -40.259)
		(end 189.1792 -40.259)
		(width 0.2032)
		(layer "F.Cu")
		(net "VR_PVDDR_A_VAUTO")
	)
	(segment
		(start 189.1538 -40.2336)
		(end 189.1538 -39.497)
		(width 0.2032)
		(layer "F.Cu")
		(net "VR_PVDDR_A_VAUTO")
	)
	(segment
		(start 189.1792 -40.259)
		(end 189.1538 -40.2336)
		(width 0.2032)
		(layer "F.Cu")
		(net "VR_PVDDR_A_VAUTO")
	)
	(segment
		(start 188.656468 -36.376102)
		(end 188.656468 -38.034468)
		(width 0.2032)
		(layer "F.Cu")
		(net "VR_PVDDR_A_VAUTO")
	)
	(segment
		(start 189.1538 -38.5318)
		(end 189.1538 -39.497)
		(width 0.2032)
		(layer "F.Cu")
		(net "VR_PVDDR_A_VAUTO")
	)
	(segment
		(start 188.976 -41.0972)
		(end 189.1792 -40.894)
		(width 0.2032)
		(layer "F.Cu")
		(net "VR_PVDDR_A_VAUTO")
	)
	(via
		(at 188.214 -40.259)
		(size 0.7112)
		(drill 0.3556)
		(layers "F.Cu" "B.Cu")
		(net "VR_PVDDR_A_VAUTO")
	)
	(segment
		(start 85.933788 -32.771334)
		(end 85.592666 -32.430212)
		(width 0.1143)
		(layer "F.Cu")
		(net "SATA3_OBS_N")
	)
	(segment
		(start 85.592666 -32.430212)
		(end 85.592412 -32.430212)
		(width 0.1143)
		(layer "F.Cu")
		(net "SATA3_OBS_N")
	)
	(segment
		(start 85.592412 -32.430212)
		(end 85.5726 -32.4104)
		(width 0.1143)
		(layer "F.Cu")
		(net "SATA3_OBS_N")
	)
	(via
		(at 87.34806 -33.38322)
		(size 0.7112)
		(drill 0.3556)
		(layers "F.Cu" "B.Cu")
		(net "SATA3_OBS_N")
	)
	(via
		(at 85.5726 -32.4104)
		(size 0.4318)
		(drill 0.2032)
		(layers "F.Cu" "B.Cu")
		(net "SATA3_OBS_N")
	)
	(segment
		(start 85.5726 -32.4104)
		(end 85.5726 -32.5882)
		(width 0.1143)
		(layer "B.Cu")
		(net "SATA3_OBS_N")
	)
	(segment
		(start 85.6488 -32.3342)
		(end 85.5726 -32.4104)
		(width 0.1143)
		(layer "B.Cu")
		(net "SATA3_OBS_N")
	)
	(segment
		(start 87.34806 -33.38322)
		(end 86.36762 -33.38322)
		(width 0.1143)
		(layer "B.Cu")
		(net "SATA3_OBS_N")
	)
	(segment
		(start 86.36762 -33.38322)
		(end 86.2584 -33.274)
		(width 0.1143)
		(layer "B.Cu")
		(net "SATA3_OBS_N")
	)
	(segment
		(start 85.5726 -32.5882)
		(end 86.2584 -33.274)
		(width 0.1143)
		(layer "B.Cu")
		(net "SATA3_OBS_N")
	)
	(segment
		(start 85.6488 -31.75)
		(end 85.6488 -32.3342)
		(width 0.1143)
		(layer "B.Cu")
		(net "SATA3_OBS_N")
	)
	(segment
		(start 106.299 -32.5628)
		(end 105.851706 -33.010094)
		(width 0.1016)
		(layer "F.Cu")
		(net "M_B_DQ33")
	)
	(segment
		(start 171.1198 -8.536178)
		(end 171.1198 -8.129778)
		(width 0.1778)
		(layer "F.Cu")
		(net "M_B_DQ33")
	)
	(segment
		(start 105.851706 -33.010094)
		(end 105.766108 -33.010094)
		(width 0.1016)
		(layer "F.Cu")
		(net "M_B_DQ33")
	)
	(segment
		(start 171.249848 -9.897364)
		(end 171.249848 -8.666226)
		(width 0.1778)
		(layer "F.Cu")
		(net "M_B_DQ33")
	)
	(segment
		(start 171.249848 -8.666226)
		(end 171.1198 -8.536178)
		(width 0.1778)
		(layer "F.Cu")
		(net "M_B_DQ33")
	)
	(segment
		(start 171.1198 -8.129778)
		(end 171.2976 -7.951978)
		(width 0.1778)
		(layer "F.Cu")
		(net "M_B_DQ33")
	)
	(via
		(at 106.299 -32.5628)
		(size 0.4318)
		(drill 0.2032)
		(layers "F.Cu" "B.Cu")
		(net "M_B_DQ33")
	)
	(via
		(at 171.2976 -7.951978)
		(size 0.4318)
		(drill 0.2032)
		(layers "F.Cu" "B.Cu")
		(net "M_B_DQ33")
	)
	(segment
		(start 170.949874 -8.299704)
		(end 171.2976 -7.951978)
		(width 0.1778)
		(layer "B.Cu")
		(net "M_B_DQ33")
	)
	(segment
		(start 170.949874 -9.89076)
		(end 170.949874 -8.299704)
		(width 0.1778)
		(layer "B.Cu")
		(net "M_B_DQ33")
	)
	(segment
		(start 110.940596 -27.3812)
		(end 109.1184 -29.203396)
		(width 0.1016)
		(layer "In4.Cu")
		(net "M_B_DQ33")
	)
	(segment
		(start 109.1184 -29.845)
		(end 108.9152 -30.0482)
		(width 0.1016)
		(layer "In4.Cu")
		(net "M_B_DQ33")
	)
	(segment
		(start 158.118048 -24.822404)
		(end 157.918404 -24.822404)
		(width 0.1524)
		(layer "In4.Cu")
		(net "M_B_DQ33")
	)
	(segment
		(start 156.965142 -25.469596)
		(end 155.383738 -27.051)
		(width 0.1524)
		(layer "In4.Cu")
		(net "M_B_DQ33")
	)
	(segment
		(start 113.3094 -27.3812)
		(end 111.444532 -27.3812)
		(width 0.1524)
		(layer "In4.Cu")
		(net "M_B_DQ33")
	)
	(segment
		(start 108.5342 -30.0482)
		(end 108.204 -29.718)
		(width 0.1016)
		(layer "In4.Cu")
		(net "M_B_DQ33")
	)
	(segment
		(start 158.66491 -23.541482)
		(end 158.449518 -23.541482)
		(width 0.1524)
		(layer "In4.Cu")
		(net "M_B_DQ33")
	)
	(segment
		(start 158.500826 -24.439626)
		(end 158.118048 -24.822404)
		(width 0.1524)
		(layer "In4.Cu")
		(net "M_B_DQ33")
	)
	(segment
		(start 158.233618 -23.972774)
		(end 158.500826 -24.239982)
		(width 0.1524)
		(layer "In4.Cu")
		(net "M_B_DQ33")
	)
	(segment
		(start 164.692838 -18.247614)
		(end 164.477446 -18.247614)
		(width 0.1524)
		(layer "In4.Cu")
		(net "M_B_DQ33")
	)
	(segment
		(start 159.185102 -22.551898)
		(end 158.969202 -22.767798)
		(width 0.1524)
		(layer "In4.Cu")
		(net "M_B_DQ33")
	)
	(segment
		(start 111.444532 -27.3812)
		(end 110.940596 -27.3812)
		(width 0.1016)
		(layer "In4.Cu")
		(net "M_B_DQ33")
	)
	(segment
		(start 157.283404 -24.402796)
		(end 156.965142 -24.721058)
		(width 0.1524)
		(layer "In4.Cu")
		(net "M_B_DQ33")
	)
	(segment
		(start 164.046154 -18.678906)
		(end 164.046154 -18.894298)
		(width 0.1524)
		(layer "In4.Cu")
		(net "M_B_DQ33")
	)
	(segment
		(start 157.918404 -24.822404)
		(end 157.498796 -24.402796)
		(width 0.1524)
		(layer "In4.Cu")
		(net "M_B_DQ33")
	)
	(segment
		(start 164.669216 -16.929608)
		(end 164.453316 -17.145508)
		(width 0.1524)
		(layer "In4.Cu")
		(net "M_B_DQ33")
	)
	(segment
		(start 107.3658 -30.1498)
		(end 107.3658 -30.835092)
		(width 0.1016)
		(layer "In4.Cu")
		(net "M_B_DQ33")
	)
	(segment
		(start 165.555422 -17.38503)
		(end 165.34003 -17.38503)
		(width 0.1524)
		(layer "In4.Cu")
		(net "M_B_DQ33")
	)
	(segment
		(start 158.924244 -23.800816)
		(end 158.66491 -23.541482)
		(width 0.1524)
		(layer "In4.Cu")
		(net "M_B_DQ33")
	)
	(segment
		(start 106.4768 -31.724092)
		(end 106.4768 -32.385)
		(width 0.1016)
		(layer "In4.Cu")
		(net "M_B_DQ33")
	)
	(segment
		(start 165.34003 -17.38503)
		(end 164.884608 -16.929608)
		(width 0.1524)
		(layer "In4.Cu")
		(net "M_B_DQ33")
	)
	(segment
		(start 164.453316 -17.3609)
		(end 164.908738 -17.816322)
		(width 0.1524)
		(layer "In4.Cu")
		(net "M_B_DQ33")
	)
	(segment
		(start 158.969202 -22.767798)
		(end 158.969202 -22.98319)
		(width 0.1524)
		(layer "In4.Cu")
		(net "M_B_DQ33")
	)
	(segment
		(start 164.046154 -18.894298)
		(end 160.00222 -22.938232)
		(width 0.1524)
		(layer "In4.Cu")
		(net "M_B_DQ33")
	)
	(segment
		(start 166.226998 -16.7132)
		(end 165.885114 -17.055084)
		(width 0.1524)
		(layer "In4.Cu")
		(net "M_B_DQ33")
	)
	(segment
		(start 158.233618 -23.757382)
		(end 158.233618 -23.972774)
		(width 0.1524)
		(layer "In4.Cu")
		(net "M_B_DQ33")
	)
	(segment
		(start 155.383738 -27.051)
		(end 113.6396 -27.051)
		(width 0.1524)
		(layer "In4.Cu")
		(net "M_B_DQ33")
	)
	(segment
		(start 171.1452 -8.104378)
		(end 171.1452 -12.745466)
		(width 0.1524)
		(layer "In4.Cu")
		(net "M_B_DQ33")
	)
	(segment
		(start 113.6396 -27.051)
		(end 113.3094 -27.3812)
		(width 0.1524)
		(layer "In4.Cu")
		(net "M_B_DQ33")
	)
	(segment
		(start 171.2976 -7.951978)
		(end 171.1452 -8.104378)
		(width 0.1524)
		(layer "In4.Cu")
		(net "M_B_DQ33")
	)
	(segment
		(start 164.908738 -18.031714)
		(end 164.692838 -18.247614)
		(width 0.1524)
		(layer "In4.Cu")
		(net "M_B_DQ33")
	)
	(segment
		(start 159.355536 -23.584916)
		(end 159.139636 -23.800816)
		(width 0.1524)
		(layer "In4.Cu")
		(net "M_B_DQ33")
	)
	(segment
		(start 164.477446 -18.247614)
		(end 164.022024 -17.792192)
		(width 0.1524)
		(layer "In4.Cu")
		(net "M_B_DQ33")
	)
	(segment
		(start 158.969202 -22.98319)
		(end 159.355536 -23.369524)
		(width 0.1524)
		(layer "In4.Cu")
		(net "M_B_DQ33")
	)
	(segment
		(start 165.885114 -17.055338)
		(end 165.555422 -17.38503)
		(width 0.1524)
		(layer "In4.Cu")
		(net "M_B_DQ33")
	)
	(segment
		(start 109.1184 -29.203396)
		(end 109.1184 -29.845)
		(width 0.1016)
		(layer "In4.Cu")
		(net "M_B_DQ33")
	)
	(segment
		(start 163.590732 -18.223484)
		(end 164.046154 -18.678906)
		(width 0.1524)
		(layer "In4.Cu")
		(net "M_B_DQ33")
	)
	(segment
		(start 158.449518 -23.541482)
		(end 158.233618 -23.757382)
		(width 0.1524)
		(layer "In4.Cu")
		(net "M_B_DQ33")
	)
	(segment
		(start 163.806632 -17.792192)
		(end 163.590732 -18.008092)
		(width 0.1524)
		(layer "In4.Cu")
		(net "M_B_DQ33")
	)
	(segment
		(start 164.908738 -17.816322)
		(end 164.908738 -18.031714)
		(width 0.1524)
		(layer "In4.Cu")
		(net "M_B_DQ33")
	)
	(segment
		(start 167.177466 -16.7132)
		(end 166.226998 -16.7132)
		(width 0.1524)
		(layer "In4.Cu")
		(net "M_B_DQ33")
	)
	(segment
		(start 159.400494 -22.551898)
		(end 159.185102 -22.551898)
		(width 0.1524)
		(layer "In4.Cu")
		(net "M_B_DQ33")
	)
	(segment
		(start 108.9152 -30.0482)
		(end 108.5342 -30.0482)
		(width 0.1016)
		(layer "In4.Cu")
		(net "M_B_DQ33")
	)
	(segment
		(start 164.453316 -17.145508)
		(end 164.453316 -17.3609)
		(width 0.1524)
		(layer "In4.Cu")
		(net "M_B_DQ33")
	)
	(segment
		(start 106.4768 -32.385)
		(end 106.299 -32.5628)
		(width 0.1016)
		(layer "In4.Cu")
		(net "M_B_DQ33")
	)
	(segment
		(start 159.355536 -23.369524)
		(end 159.355536 -23.584916)
		(width 0.1524)
		(layer "In4.Cu")
		(net "M_B_DQ33")
	)
	(segment
		(start 165.885114 -17.055084)
		(end 165.885114 -17.055338)
		(width 0.1524)
		(layer "In4.Cu")
		(net "M_B_DQ33")
	)
	(segment
		(start 164.022024 -17.792192)
		(end 163.806632 -17.792192)
		(width 0.1524)
		(layer "In4.Cu")
		(net "M_B_DQ33")
	)
	(segment
		(start 171.1452 -12.745466)
		(end 167.177466 -16.7132)
		(width 0.1524)
		(layer "In4.Cu")
		(net "M_B_DQ33")
	)
	(segment
		(start 156.965142 -24.721058)
		(end 156.965142 -25.469596)
		(width 0.1524)
		(layer "In4.Cu")
		(net "M_B_DQ33")
	)
	(segment
		(start 107.7976 -29.718)
		(end 107.3658 -30.1498)
		(width 0.1016)
		(layer "In4.Cu")
		(net "M_B_DQ33")
	)
	(segment
		(start 159.139636 -23.800816)
		(end 158.924244 -23.800816)
		(width 0.1524)
		(layer "In4.Cu")
		(net "M_B_DQ33")
	)
	(segment
		(start 164.884608 -16.929608)
		(end 164.669216 -16.929608)
		(width 0.1524)
		(layer "In4.Cu")
		(net "M_B_DQ33")
	)
	(segment
		(start 160.00222 -22.938232)
		(end 159.786828 -22.938232)
		(width 0.1524)
		(layer "In4.Cu")
		(net "M_B_DQ33")
	)
	(segment
		(start 157.498796 -24.402796)
		(end 157.283404 -24.402796)
		(width 0.1524)
		(layer "In4.Cu")
		(net "M_B_DQ33")
	)
	(segment
		(start 163.590732 -18.008092)
		(end 163.590732 -18.223484)
		(width 0.1524)
		(layer "In4.Cu")
		(net "M_B_DQ33")
	)
	(segment
		(start 159.786828 -22.938232)
		(end 159.400494 -22.551898)
		(width 0.1524)
		(layer "In4.Cu")
		(net "M_B_DQ33")
	)
	(segment
		(start 107.3658 -30.835092)
		(end 106.4768 -31.724092)
		(width 0.1016)
		(layer "In4.Cu")
		(net "M_B_DQ33")
	)
	(segment
		(start 158.500826 -24.239982)
		(end 158.500826 -24.439626)
		(width 0.1524)
		(layer "In4.Cu")
		(net "M_B_DQ33")
	)
	(segment
		(start 108.204 -29.718)
		(end 107.7976 -29.718)
		(width 0.1016)
		(layer "In4.Cu")
		(net "M_B_DQ33")
	)
	(segment
		(start 40.311324 -22.5552)
		(end 39.3192 -23.547324)
		(width 0.1143)
		(layer "F.Cu")
		(net "XDP_DFX_PORT1")
	)
	(segment
		(start 83.89112 -45.695362)
		(end 83.647788 -45.45203)
		(width 0.1143)
		(layer "F.Cu")
		(net "XDP_DFX_PORT1")
	)
	(segment
		(start 42.10177 -22.5552)
		(end 40.311324 -22.5552)
		(width 0.1143)
		(layer "F.Cu")
		(net "XDP_DFX_PORT1")
	)
	(segment
		(start 39.3192 -25.04186)
		(end 38.27018 -26.09088)
		(width 0.1143)
		(layer "F.Cu")
		(net "XDP_DFX_PORT1")
	)
	(segment
		(start 39.3192 -23.547324)
		(end 39.3192 -25.04186)
		(width 0.1143)
		(layer "F.Cu")
		(net "XDP_DFX_PORT1")
	)
	(segment
		(start 83.647788 -45.45203)
		(end 83.647788 -45.390054)
		(width 0.1143)
		(layer "F.Cu")
		(net "XDP_DFX_PORT1")
	)
	(segment
		(start 83.89112 -45.9486)
		(end 83.89112 -45.695362)
		(width 0.1143)
		(layer "F.Cu")
		(net "XDP_DFX_PORT1")
	)
	(via
		(at 38.27018 -26.09088)
		(size 0.508)
		(drill 0.254)
		(layers "F.Cu" "B.Cu")
		(net "XDP_DFX_PORT1")
	)
	(via
		(at 83.89112 -45.9486)
		(size 0.4318)
		(drill 0.2032)
		(layers "F.Cu" "B.Cu")
		(net "XDP_DFX_PORT1")
	)
	(via
		(at 83.85937 -46.64837)
		(size 0.7112)
		(drill 0.3556)
		(layers "F.Cu" "B.Cu")
		(net "XDP_DFX_PORT1")
	)
	(segment
		(start 83.8962 -45.95368)
		(end 83.8962 -46.61154)
		(width 0.1143)
		(layer "B.Cu")
		(net "XDP_DFX_PORT1")
	)
	(segment
		(start 83.89112 -45.9486)
		(end 83.8962 -45.95368)
		(width 0.1143)
		(layer "B.Cu")
		(net "XDP_DFX_PORT1")
	)
	(segment
		(start 83.8962 -46.61154)
		(end 83.85937 -46.64837)
		(width 0.1143)
		(layer "B.Cu")
		(net "XDP_DFX_PORT1")
	)
	(segment
		(start 61.00699 -39.54145)
		(end 61.58103 -40.11549)
		(width 0.0889)
		(layer "In7.Cu")
		(net "XDP_DFX_PORT1")
	)
	(segment
		(start 43.592496 -35.09645)
		(end 45.84065 -35.09645)
		(width 0.0889)
		(layer "In7.Cu")
		(net "XDP_DFX_PORT1")
	)
	(segment
		(start 61.58103 -40.11549)
		(end 65.64249 -40.11549)
		(width 0.0889)
		(layer "In7.Cu")
		(net "XDP_DFX_PORT1")
	)
	(segment
		(start 81.614518 -46.405546)
		(end 81.922366 -46.097952)
		(width 0.0889)
		(layer "In7.Cu")
		(net "XDP_DFX_PORT1")
	)
	(segment
		(start 49.82845 -39.08425)
		(end 50.219356 -39.08425)
		(width 0.0889)
		(layer "In7.Cu")
		(net "XDP_DFX_PORT1")
	)
	(segment
		(start 83.242404 -45.940218)
		(end 83.250786 -45.9486)
		(width 0.0889)
		(layer "In7.Cu")
		(net "XDP_DFX_PORT1")
	)
	(segment
		(start 65.64249 -40.11549)
		(end 69.057266 -43.530266)
		(width 0.0889)
		(layer "In7.Cu")
		(net "XDP_DFX_PORT1")
	)
	(segment
		(start 38.27018 -27.835606)
		(end 38.735 -28.300426)
		(width 0.0889)
		(layer "In7.Cu")
		(net "XDP_DFX_PORT1")
	)
	(segment
		(start 38.27018 -26.09088)
		(end 38.27018 -27.835606)
		(width 0.0889)
		(layer "In7.Cu")
		(net "XDP_DFX_PORT1")
	)
	(segment
		(start 45.84065 -35.09645)
		(end 49.82845 -39.08425)
		(width 0.0889)
		(layer "In7.Cu")
		(net "XDP_DFX_PORT1")
	)
	(segment
		(start 38.735 -28.300426)
		(end 38.735 -30.238954)
		(width 0.0889)
		(layer "In7.Cu")
		(net "XDP_DFX_PORT1")
	)
	(segment
		(start 75.216512 -45.024802)
		(end 78.782672 -45.024802)
		(width 0.0889)
		(layer "In7.Cu")
		(net "XDP_DFX_PORT1")
	)
	(segment
		(start 78.782672 -45.024802)
		(end 80.163416 -46.405546)
		(width 0.0889)
		(layer "In7.Cu")
		(net "XDP_DFX_PORT1")
	)
	(segment
		(start 38.735 -30.238954)
		(end 43.592496 -35.09645)
		(width 0.0889)
		(layer "In7.Cu")
		(net "XDP_DFX_PORT1")
	)
	(segment
		(start 50.587656 -38.71595)
		(end 56.05653 -38.71595)
		(width 0.0889)
		(layer "In7.Cu")
		(net "XDP_DFX_PORT1")
	)
	(segment
		(start 56.05653 -38.71595)
		(end 56.88203 -39.54145)
		(width 0.0889)
		(layer "In7.Cu")
		(net "XDP_DFX_PORT1")
	)
	(segment
		(start 69.057266 -43.530266)
		(end 73.721976 -43.530266)
		(width 0.0889)
		(layer "In7.Cu")
		(net "XDP_DFX_PORT1")
	)
	(segment
		(start 80.163416 -46.405546)
		(end 81.614518 -46.405546)
		(width 0.0889)
		(layer "In7.Cu")
		(net "XDP_DFX_PORT1")
	)
	(segment
		(start 56.88203 -39.54145)
		(end 61.00699 -39.54145)
		(width 0.0889)
		(layer "In7.Cu")
		(net "XDP_DFX_PORT1")
	)
	(segment
		(start 73.721976 -43.530266)
		(end 75.216512 -45.024802)
		(width 0.0889)
		(layer "In7.Cu")
		(net "XDP_DFX_PORT1")
	)
	(segment
		(start 82.476848 -45.940218)
		(end 83.242404 -45.940218)
		(width 0.0889)
		(layer "In7.Cu")
		(net "XDP_DFX_PORT1")
	)
	(segment
		(start 83.250786 -45.9486)
		(end 83.89112 -45.9486)
		(width 0.0889)
		(layer "In7.Cu")
		(net "XDP_DFX_PORT1")
	)
	(segment
		(start 82.319114 -46.097952)
		(end 82.476848 -45.940218)
		(width 0.0889)
		(layer "In7.Cu")
		(net "XDP_DFX_PORT1")
	)
	(segment
		(start 81.922366 -46.097952)
		(end 82.319114 -46.097952)
		(width 0.0889)
		(layer "In7.Cu")
		(net "XDP_DFX_PORT1")
	)
	(segment
		(start 50.219356 -39.08425)
		(end 50.587656 -38.71595)
		(width 0.0889)
		(layer "In7.Cu")
		(net "XDP_DFX_PORT1")
	)
	(segment
		(start 185.664602 -34.57575)
		(end 186.856116 -34.57575)
		(width 0.2032)
		(layer "F.Cu")
		(net "VR_PWREN_PVDDR_A")
	)
	(segment
		(start 185.213498 -35.770566)
		(end 185.213498 -35.026854)
		(width 0.2032)
		(layer "F.Cu")
		(net "VR_PWREN_PVDDR_A")
	)
	(segment
		(start 185.213498 -35.026854)
		(end 185.664602 -34.57575)
		(width 0.2032)
		(layer "F.Cu")
		(net "VR_PWREN_PVDDR_A")
	)
	(segment
		(start 184.712864 -36.2712)
		(end 185.213498 -35.770566)
		(width 0.2032)
		(layer "F.Cu")
		(net "VR_PWREN_PVDDR_A")
	)
	(segment
		(start 184.0484 -36.2712)
		(end 184.712864 -36.2712)
		(width 0.2032)
		(layer "F.Cu")
		(net "VR_PWREN_PVDDR_A")
	)
	(segment
		(start 182.372 -36.4998)
		(end 183.1086 -36.4998)
		(width 0.2032)
		(layer "F.Cu")
		(net "VR_PWREN_PVDDR_A")
	)
	(segment
		(start 183.388 -36.2712)
		(end 184.0484 -36.2712)
		(width 0.2032)
		(layer "F.Cu")
		(net "VR_PWREN_PVDDR_A")
	)
	(segment
		(start 181.61 -36.4998)
		(end 182.372 -36.4998)
		(width 0.2032)
		(layer "F.Cu")
		(net "VR_PWREN_PVDDR_A")
	)
	(segment
		(start 183.134 -36.5252)
		(end 183.388 -36.2712)
		(width 0.2032)
		(layer "F.Cu")
		(net "VR_PWREN_PVDDR_A")
	)
	(segment
		(start 183.1086 -36.4998)
		(end 183.134 -36.5252)
		(width 0.2032)
		(layer "F.Cu")
		(net "VR_PWREN_PVDDR_A")
	)
	(via
		(at 184.0484 -36.2712)
		(size 0.7112)
		(drill 0.3556)
		(layers "F.Cu" "B.Cu")
		(net "VR_PWREN_PVDDR_A")
	)
	(segment
		(start 165.549834 -1.68402)
		(end 165.549834 -2.581402)
		(width 0.2413)
		(layer "F.Cu")
		(net "M_B_MA10")
	)
	(segment
		(start 165.6588 -5.894578)
		(end 166.0652 -6.300978)
		(width 0.2413)
		(layer "F.Cu")
		(net "M_B_MA10")
	)
	(segment
		(start 165.549834 -2.581402)
		(end 165.910514 -2.942082)
		(width 0.2413)
		(layer "F.Cu")
		(net "M_B_MA10")
	)
	(segment
		(start 166.5224 -6.406642)
		(end 166.522908 -6.406642)
		(width 0.2413)
		(layer "F.Cu")
		(net "M_B_MA10")
	)
	(segment
		(start 165.910514 -2.942082)
		(end 165.910514 -3.336798)
		(width 0.2413)
		(layer "F.Cu")
		(net "M_B_MA10")
	)
	(segment
		(start 166.416736 -6.300978)
		(end 166.5224 -6.406642)
		(width 0.2413)
		(layer "F.Cu")
		(net "M_B_MA10")
	)
	(segment
		(start 102.8446 -31.6484)
		(end 103.056182 -31.6484)
		(width 0.1016)
		(layer "F.Cu")
		(net "M_B_MA10")
	)
	(segment
		(start 166.0652 -6.300978)
		(end 166.416736 -6.300978)
		(width 0.2413)
		(layer "F.Cu")
		(net "M_B_MA10")
	)
	(segment
		(start 103.056182 -31.6484)
		(end 103.563928 -31.140654)
		(width 0.1016)
		(layer "F.Cu")
		(net "M_B_MA10")
	)
	(segment
		(start 165.6588 -3.588512)
		(end 165.6588 -5.894578)
		(width 0.2413)
		(layer "F.Cu")
		(net "M_B_MA10")
	)
	(segment
		(start 165.910514 -3.336798)
		(end 165.6588 -3.588512)
		(width 0.2413)
		(layer "F.Cu")
		(net "M_B_MA10")
	)
	(via
		(at 102.8446 -31.6484)
		(size 0.4318)
		(drill 0.2032)
		(layers "F.Cu" "B.Cu")
		(net "M_B_MA10")
	)
	(via
		(at 166.522908 -6.406642)
		(size 0.4318)
		(drill 0.2032)
		(layers "F.Cu" "B.Cu")
		(net "M_B_MA10")
	)
	(segment
		(start 165.549834 -9.89076)
		(end 165.549834 -8.949436)
		(width 0.2413)
		(layer "B.Cu")
		(net "M_B_MA10")
	)
	(segment
		(start 166.516304 -6.406642)
		(end 166.522908 -6.406642)
		(width 0.2413)
		(layer "B.Cu")
		(net "M_B_MA10")
	)
	(segment
		(start 165.67785 -8.82142)
		(end 165.67785 -7.245096)
		(width 0.2413)
		(layer "B.Cu")
		(net "M_B_MA10")
	)
	(segment
		(start 165.67785 -7.245096)
		(end 166.516304 -6.406642)
		(width 0.2413)
		(layer "B.Cu")
		(net "M_B_MA10")
	)
	(segment
		(start 165.549834 -8.949436)
		(end 165.67785 -8.82142)
		(width 0.2413)
		(layer "B.Cu")
		(net "M_B_MA10")
	)
	(segment
		(start 109.900212 -28.102814)
		(end 110.240826 -27.7622)
		(width 0.1016)
		(layer "In7.Cu")
		(net "M_B_MA10")
	)
	(segment
		(start 161.664904 -18.311622)
		(end 161.934144 -18.311622)
		(width 0.1905)
		(layer "In7.Cu")
		(net "M_B_MA10")
	)
	(segment
		(start 164.090096 -16.15567)
		(end 164.359844 -15.885922)
		(width 0.1905)
		(layer "In7.Cu")
		(net "M_B_MA10")
	)
	(segment
		(start 163.820856 -16.15567)
		(end 164.090096 -16.15567)
		(width 0.1905)
		(layer "In7.Cu")
		(net "M_B_MA10")
	)
	(segment
		(start 103.705406 -31.07944)
		(end 104.066594 -31.07944)
		(width 0.1016)
		(layer "In7.Cu")
		(net "M_B_MA10")
	)
	(segment
		(start 163.678616 -16.01343)
		(end 163.820856 -16.15567)
		(width 0.1905)
		(layer "In7.Cu")
		(net "M_B_MA10")
	)
	(segment
		(start 162.061652 -17.630394)
		(end 162.061652 -17.361154)
		(width 0.1905)
		(layer "In7.Cu")
		(net "M_B_MA10")
	)
	(segment
		(start 161.522664 -18.169382)
		(end 161.664904 -18.311622)
		(width 0.1905)
		(layer "In7.Cu")
		(net "M_B_MA10")
	)
	(segment
		(start 110.240826 -27.7622)
		(end 112.0648 -27.7622)
		(width 0.1016)
		(layer "In7.Cu")
		(net "M_B_MA10")
	)
	(segment
		(start 164.359844 -15.616682)
		(end 164.217604 -15.474442)
		(width 0.1905)
		(layer "In7.Cu")
		(net "M_B_MA10")
	)
	(segment
		(start 106.7054 -29.5656)
		(end 106.7054 -29.23921)
		(width 0.1016)
		(layer "In7.Cu")
		(net "M_B_MA10")
	)
	(segment
		(start 153.540206 -25.8826)
		(end 161.253424 -18.169382)
		(width 0.1905)
		(layer "In7.Cu")
		(net "M_B_MA10")
	)
	(segment
		(start 117.543834 -25.8826)
		(end 153.540206 -25.8826)
		(width 0.1905)
		(layer "In7.Cu")
		(net "M_B_MA10")
	)
	(segment
		(start 161.253424 -18.169382)
		(end 161.522664 -18.169382)
		(width 0.1905)
		(layer "In7.Cu")
		(net "M_B_MA10")
	)
	(segment
		(start 164.359844 -15.885922)
		(end 164.359844 -15.616682)
		(width 0.1905)
		(layer "In7.Cu")
		(net "M_B_MA10")
	)
	(segment
		(start 162.061652 -17.361154)
		(end 162.3314 -17.091406)
		(width 0.1905)
		(layer "In7.Cu")
		(net "M_B_MA10")
	)
	(segment
		(start 164.217604 -15.474442)
		(end 164.217604 -15.205202)
		(width 0.1905)
		(layer "In7.Cu")
		(net "M_B_MA10")
	)
	(segment
		(start 162.203892 -17.772634)
		(end 162.061652 -17.630394)
		(width 0.1905)
		(layer "In7.Cu")
		(net "M_B_MA10")
	)
	(segment
		(start 112.0648 -27.7622)
		(end 115.664488 -27.7622)
		(width 0.1905)
		(layer "In7.Cu")
		(net "M_B_MA10")
	)
	(segment
		(start 162.60064 -17.091406)
		(end 162.74288 -17.233646)
		(width 0.1905)
		(layer "In7.Cu")
		(net "M_B_MA10")
	)
	(segment
		(start 106.7054 -29.23921)
		(end 107.841796 -28.102814)
		(width 0.1016)
		(layer "In7.Cu")
		(net "M_B_MA10")
	)
	(segment
		(start 166.516304 -6.406642)
		(end 166.522908 -6.406642)
		(width 0.1905)
		(layer "In7.Cu")
		(net "M_B_MA10")
	)
	(segment
		(start 166.0906 -9.120378)
		(end 166.0906 -6.832346)
		(width 0.1905)
		(layer "In7.Cu")
		(net "M_B_MA10")
	)
	(segment
		(start 162.3314 -17.091406)
		(end 162.60064 -17.091406)
		(width 0.1905)
		(layer "In7.Cu")
		(net "M_B_MA10")
	)
	(segment
		(start 166.0906 -6.832346)
		(end 166.516304 -6.406642)
		(width 0.1905)
		(layer "In7.Cu")
		(net "M_B_MA10")
	)
	(segment
		(start 107.841796 -28.102814)
		(end 109.900212 -28.102814)
		(width 0.1016)
		(layer "In7.Cu")
		(net "M_B_MA10")
	)
	(segment
		(start 164.7444 -14.678406)
		(end 164.7444 -10.466578)
		(width 0.1905)
		(layer "In7.Cu")
		(net "M_B_MA10")
	)
	(segment
		(start 164.217604 -15.205202)
		(end 164.7444 -14.678406)
		(width 0.1905)
		(layer "In7.Cu")
		(net "M_B_MA10")
	)
	(segment
		(start 163.281868 -16.963898)
		(end 163.281868 -16.694658)
		(width 0.1905)
		(layer "In7.Cu")
		(net "M_B_MA10")
	)
	(segment
		(start 163.139628 -16.283178)
		(end 163.409376 -16.01343)
		(width 0.1905)
		(layer "In7.Cu")
		(net "M_B_MA10")
	)
	(segment
		(start 106.2736 -29.9974)
		(end 106.7054 -29.5656)
		(width 0.1016)
		(layer "In7.Cu")
		(net "M_B_MA10")
	)
	(segment
		(start 162.74288 -17.233646)
		(end 163.01212 -17.233646)
		(width 0.1905)
		(layer "In7.Cu")
		(net "M_B_MA10")
	)
	(segment
		(start 104.878632 -29.9974)
		(end 106.2736 -29.9974)
		(width 0.1016)
		(layer "In7.Cu")
		(net "M_B_MA10")
	)
	(segment
		(start 162.203892 -18.041874)
		(end 162.203892 -17.772634)
		(width 0.1905)
		(layer "In7.Cu")
		(net "M_B_MA10")
	)
	(segment
		(start 103.136446 -31.6484)
		(end 103.705406 -31.07944)
		(width 0.1016)
		(layer "In7.Cu")
		(net "M_B_MA10")
	)
	(segment
		(start 104.28224 -30.863794)
		(end 104.28224 -30.593792)
		(width 0.1016)
		(layer "In7.Cu")
		(net "M_B_MA10")
	)
	(segment
		(start 115.664488 -27.7622)
		(end 116.24183 -27.184604)
		(width 0.1905)
		(layer "In7.Cu")
		(net "M_B_MA10")
	)
	(segment
		(start 102.8446 -31.6484)
		(end 103.136446 -31.6484)
		(width 0.1016)
		(layer "In7.Cu")
		(net "M_B_MA10")
	)
	(segment
		(start 164.7444 -10.466578)
		(end 166.0906 -9.120378)
		(width 0.1905)
		(layer "In7.Cu")
		(net "M_B_MA10")
	)
	(segment
		(start 116.24183 -27.184604)
		(end 117.543834 -25.8826)
		(width 0.1905)
		(layer "In7.Cu")
		(net "M_B_MA10")
	)
	(segment
		(start 163.281868 -16.694658)
		(end 163.139628 -16.552418)
		(width 0.1905)
		(layer "In7.Cu")
		(net "M_B_MA10")
	)
	(segment
		(start 161.934144 -18.311622)
		(end 162.203892 -18.041874)
		(width 0.1905)
		(layer "In7.Cu")
		(net "M_B_MA10")
	)
	(segment
		(start 104.066594 -31.07944)
		(end 104.28224 -30.863794)
		(width 0.1016)
		(layer "In7.Cu")
		(net "M_B_MA10")
	)
	(segment
		(start 163.01212 -17.233646)
		(end 163.281868 -16.963898)
		(width 0.1905)
		(layer "In7.Cu")
		(net "M_B_MA10")
	)
	(segment
		(start 104.28224 -30.593792)
		(end 104.878632 -29.9974)
		(width 0.1016)
		(layer "In7.Cu")
		(net "M_B_MA10")
	)
	(segment
		(start 163.409376 -16.01343)
		(end 163.678616 -16.01343)
		(width 0.1905)
		(layer "In7.Cu")
		(net "M_B_MA10")
	)
	(segment
		(start 163.139628 -16.552418)
		(end 163.139628 -16.283178)
		(width 0.1905)
		(layer "In7.Cu")
		(net "M_B_MA10")
	)
	(segment
		(start 85.171788 -32.771334)
		(end 85.17128 -32.771334)
		(width 0.1143)
		(layer "F.Cu")
		(net "SATA3_OBS_P")
	)
	(segment
		(start 85.17128 -32.771334)
		(end 84.830158 -32.430212)
		(width 0.1143)
		(layer "F.Cu")
		(net "SATA3_OBS_P")
	)
	(via
		(at 84.830158 -32.430212)
		(size 0.4318)
		(drill 0.2032)
		(layers "F.Cu" "B.Cu")
		(net "SATA3_OBS_P")
	)
	(via
		(at 83.698842 -32.546036)
		(size 0.7112)
		(drill 0.3556)
		(layers "F.Cu" "B.Cu")
		(net "SATA3_OBS_P")
	)
	(segment
		(start 84.7852 -32.385254)
		(end 84.830158 -32.430212)
		(width 0.1143)
		(layer "B.Cu")
		(net "SATA3_OBS_P")
	)
	(segment
		(start 84.714334 -32.546036)
		(end 84.830158 -32.430212)
		(width 0.1143)
		(layer "B.Cu")
		(net "SATA3_OBS_P")
	)
	(segment
		(start 84.9376 -33.274)
		(end 84.9376 -32.537654)
		(width 0.1143)
		(layer "B.Cu")
		(net "SATA3_OBS_P")
	)
	(segment
		(start 84.9376 -32.537654)
		(end 84.830158 -32.430212)
		(width 0.1143)
		(layer "B.Cu")
		(net "SATA3_OBS_P")
	)
	(segment
		(start 84.7852 -31.75)
		(end 84.7852 -32.385254)
		(width 0.1143)
		(layer "B.Cu")
		(net "SATA3_OBS_P")
	)
	(segment
		(start 83.698842 -32.546036)
		(end 84.714334 -32.546036)
		(width 0.1143)
		(layer "B.Cu")
		(net "SATA3_OBS_P")
	)
	(segment
		(start 44.3738 -22.3774)
		(end 44.3738 -22.62886)
		(width 0.1143)
		(layer "F.Cu")
		(net "XDP_DFX_PORT2")
	)
	(segment
		(start 43.42384 -23.264114)
		(end 43.738546 -23.264114)
		(width 0.1143)
		(layer "F.Cu")
		(net "XDP_DFX_PORT2")
	)
	(segment
		(start 83.263994 -44.993052)
		(end 83.237832 -45.019214)
		(width 0.1143)
		(layer "F.Cu")
		(net "XDP_DFX_PORT2")
	)
	(segment
		(start 44.3738 -22.62886)
		(end 43.738546 -23.264114)
		(width 0.1143)
		(layer "F.Cu")
		(net "XDP_DFX_PORT2")
	)
	(segment
		(start 83.647788 -44.689014)
		(end 83.58759 -44.689014)
		(width 0.1143)
		(layer "F.Cu")
		(net "XDP_DFX_PORT2")
	)
	(segment
		(start 83.58759 -44.689014)
		(end 83.283552 -44.993052)
		(width 0.1143)
		(layer "F.Cu")
		(net "XDP_DFX_PORT2")
	)
	(segment
		(start 83.283552 -44.993052)
		(end 83.263994 -44.993052)
		(width 0.1143)
		(layer "F.Cu")
		(net "XDP_DFX_PORT2")
	)
	(segment
		(start 43.133264 -23.55469)
		(end 43.42384 -23.264114)
		(width 0.1143)
		(layer "F.Cu")
		(net "XDP_DFX_PORT2")
	)
	(segment
		(start 42.10177 -23.55469)
		(end 43.133264 -23.55469)
		(width 0.1143)
		(layer "F.Cu")
		(net "XDP_DFX_PORT2")
	)
	(via
		(at 83.237832 -45.019214)
		(size 0.4318)
		(drill 0.2032)
		(layers "F.Cu" "B.Cu")
		(net "XDP_DFX_PORT2")
	)
	(via
		(at 44.3738 -22.3774)
		(size 0.7112)
		(drill 0.3556)
		(layers "F.Cu" "B.Cu")
		(net "XDP_DFX_PORT2")
	)
	(via
		(at 43.738546 -23.264114)
		(size 0.508)
		(drill 0.254)
		(layers "F.Cu" "B.Cu")
		(net "XDP_DFX_PORT2")
	)
	(segment
		(start 75.195684 -40.29075)
		(end 75.603862 -40.29075)
		(width 0.0889)
		(layer "In7.Cu")
		(net "XDP_DFX_PORT2")
	)
	(segment
		(start 58.489596 -34.318194)
		(end 60.073794 -34.318194)
		(width 0.0889)
		(layer "In7.Cu")
		(net "XDP_DFX_PORT2")
	)
	(segment
		(start 43.12285 -23.87981)
		(end 43.12285 -27.777694)
		(width 0.0889)
		(layer "In7.Cu")
		(net "XDP_DFX_PORT2")
	)
	(segment
		(start 81.237836 -44.993052)
		(end 83.18373 -44.993052)
		(width 0.0889)
		(layer "In7.Cu")
		(net "XDP_DFX_PORT2")
	)
	(segment
		(start 83.209892 -45.019214)
		(end 83.237832 -45.019214)
		(width 0.0889)
		(layer "In7.Cu")
		(net "XDP_DFX_PORT2")
	)
	(segment
		(start 75.603862 -40.29075)
		(end 77.604112 -42.291)
		(width 0.0889)
		(layer "In7.Cu")
		(net "XDP_DFX_PORT2")
	)
	(segment
		(start 51.000914 -34.541714)
		(end 52.453286 -34.541714)
		(width 0.0889)
		(layer "In7.Cu")
		(net "XDP_DFX_PORT2")
	)
	(segment
		(start 78.535784 -42.291)
		(end 81.237836 -44.993052)
		(width 0.0889)
		(layer "In7.Cu")
		(net "XDP_DFX_PORT2")
	)
	(segment
		(start 57.0103 -34.7853)
		(end 58.02249 -34.7853)
		(width 0.0889)
		(layer "In7.Cu")
		(net "XDP_DFX_PORT2")
	)
	(segment
		(start 52.453286 -34.541714)
		(end 52.9844 -34.0106)
		(width 0.0889)
		(layer "In7.Cu")
		(net "XDP_DFX_PORT2")
	)
	(segment
		(start 73.9775 -38.124638)
		(end 73.9775 -39.072566)
		(width 0.0889)
		(layer "In7.Cu")
		(net "XDP_DFX_PORT2")
	)
	(segment
		(start 52.9844 -34.0106)
		(end 56.2356 -34.0106)
		(width 0.0889)
		(layer "In7.Cu")
		(net "XDP_DFX_PORT2")
	)
	(segment
		(start 60.073794 -34.318194)
		(end 62.29985 -36.54425)
		(width 0.0889)
		(layer "In7.Cu")
		(net "XDP_DFX_PORT2")
	)
	(segment
		(start 83.18373 -44.993052)
		(end 83.209892 -45.019214)
		(width 0.0889)
		(layer "In7.Cu")
		(net "XDP_DFX_PORT2")
	)
	(segment
		(start 72.397112 -36.54425)
		(end 73.9775 -38.124638)
		(width 0.0889)
		(layer "In7.Cu")
		(net "XDP_DFX_PORT2")
	)
	(segment
		(start 77.604112 -42.291)
		(end 78.535784 -42.291)
		(width 0.0889)
		(layer "In7.Cu")
		(net "XDP_DFX_PORT2")
	)
	(segment
		(start 62.29985 -36.54425)
		(end 72.397112 -36.54425)
		(width 0.0889)
		(layer "In7.Cu")
		(net "XDP_DFX_PORT2")
	)
	(segment
		(start 58.02249 -34.7853)
		(end 58.489596 -34.318194)
		(width 0.0889)
		(layer "In7.Cu")
		(net "XDP_DFX_PORT2")
	)
	(segment
		(start 46.472856 -31.1277)
		(end 47.5869 -31.1277)
		(width 0.0889)
		(layer "In7.Cu")
		(net "XDP_DFX_PORT2")
	)
	(segment
		(start 47.5869 -31.1277)
		(end 51.000914 -34.541714)
		(width 0.0889)
		(layer "In7.Cu")
		(net "XDP_DFX_PORT2")
	)
	(segment
		(start 73.9775 -39.072566)
		(end 75.195684 -40.29075)
		(width 0.0889)
		(layer "In7.Cu")
		(net "XDP_DFX_PORT2")
	)
	(segment
		(start 56.2356 -34.0106)
		(end 57.0103 -34.7853)
		(width 0.0889)
		(layer "In7.Cu")
		(net "XDP_DFX_PORT2")
	)
	(segment
		(start 43.738546 -23.264114)
		(end 43.12285 -23.87981)
		(width 0.0889)
		(layer "In7.Cu")
		(net "XDP_DFX_PORT2")
	)
	(segment
		(start 43.12285 -27.777694)
		(end 46.472856 -31.1277)
		(width 0.0889)
		(layer "In7.Cu")
		(net "XDP_DFX_PORT2")
	)
	(segment
		(start 80.22336 -30.508194)
		(end 81.054448 -30.759654)
		(width 0.1016)
		(layer "F.Cu")
		(net "SATA3_RX_DP1")
	)
	(segment
		(start 78.870048 -30.508194)
		(end 80.22336 -30.508194)
		(width 0.1016)
		(layer "F.Cu")
		(net "SATA3_RX_DP1")
	)
	(segment
		(start 78.535276 -29.8958)
		(end 78.534768 -29.896308)
		(width 0.1016)
		(layer "F.Cu")
		(net "SATA3_RX_DP1")
	)
	(segment
		(start 78.534768 -29.896308)
		(end 78.534768 -30.172914)
		(width 0.1016)
		(layer "F.Cu")
		(net "SATA3_RX_DP1")
	)
	(segment
		(start 78.534768 -30.172914)
		(end 78.870048 -30.508194)
		(width 0.1016)
		(layer "F.Cu")
		(net "SATA3_RX_DP1")
	)
	(segment
		(start 10.922 -54.0258)
		(end 10.2616 -54.0258)
		(width 0.1397)
		(layer "F.Cu")
		(net "SATA3_RX_DP1")
	)
	(via
		(at 10.2616 -54.0258)
		(size 0.508)
		(drill 0.254)
		(layers "F.Cu" "B.Cu")
		(net "SATA3_RX_DP1")
	)
	(via
		(at 78.535276 -29.8958)
		(size 0.4318)
		(drill 0.2032)
		(layers "F.Cu" "B.Cu")
		(net "SATA3_RX_DP1")
	)
	(segment
		(start 80.7212 -31.056072)
		(end 80.7212 -31.6738)
		(width 0.1016)
		(layer "In4.Cu")
		(net "SATA3_RX_DP1")
	)
	(segment
		(start 37.068506 -49.76495)
		(end 36.248086 -50.58537)
		(width 0.1143)
		(layer "In4.Cu")
		(net "SATA3_RX_DP1")
	)
	(segment
		(start 51.870356 -49.40935)
		(end 50.367184 -49.40935)
		(width 0.1143)
		(layer "In4.Cu")
		(net "SATA3_RX_DP1")
	)
	(segment
		(start 79.6544 -32.7406)
		(end 78.0542 -32.7406)
		(width 0.1016)
		(layer "In4.Cu")
		(net "SATA3_RX_DP1")
	)
	(segment
		(start 26.942542 -49.705514)
		(end 23.885906 -52.76215)
		(width 0.1143)
		(layer "In4.Cu")
		(net "SATA3_RX_DP1")
	)
	(segment
		(start 78.0542 -32.7406)
		(end 77.5081 -33.2867)
		(width 0.1016)
		(layer "In4.Cu")
		(net "SATA3_RX_DP1")
	)
	(segment
		(start 11.719306 -53.5686)
		(end 10.3886 -53.5686)
		(width 0.1143)
		(layer "In4.Cu")
		(net "SATA3_RX_DP1")
	)
	(segment
		(start 50.367184 -49.40935)
		(end 50.011584 -49.76495)
		(width 0.1143)
		(layer "In4.Cu")
		(net "SATA3_RX_DP1")
	)
	(segment
		(start 65.93205 -33.9471)
		(end 54.794404 -45.084746)
		(width 0.1143)
		(layer "In4.Cu")
		(net "SATA3_RX_DP1")
	)
	(segment
		(start 12.525756 -52.76215)
		(end 11.719306 -53.5686)
		(width 0.1143)
		(layer "In4.Cu")
		(net "SATA3_RX_DP1")
	)
	(segment
		(start 80.7212 -31.6738)
		(end 79.6544 -32.7406)
		(width 0.1016)
		(layer "In4.Cu")
		(net "SATA3_RX_DP1")
	)
	(segment
		(start 78.535276 -29.8958)
		(end 78.534768 -29.896308)
		(width 0.1016)
		(layer "In4.Cu")
		(net "SATA3_RX_DP1")
	)
	(segment
		(start 33.474914 -49.705514)
		(end 26.942542 -49.705514)
		(width 0.1143)
		(layer "In4.Cu")
		(net "SATA3_RX_DP1")
	)
	(segment
		(start 78.534768 -30.172914)
		(end 78.892654 -30.5308)
		(width 0.1016)
		(layer "In4.Cu")
		(net "SATA3_RX_DP1")
	)
	(segment
		(start 54.202584 -45.084746)
		(end 52.324 -46.96333)
		(width 0.1143)
		(layer "In4.Cu")
		(net "SATA3_RX_DP1")
	)
	(segment
		(start 78.534768 -29.896308)
		(end 78.534768 -30.172914)
		(width 0.1016)
		(layer "In4.Cu")
		(net "SATA3_RX_DP1")
	)
	(segment
		(start 75.057 -33.3502)
		(end 74.4601 -33.9471)
		(width 0.1143)
		(layer "In4.Cu")
		(net "SATA3_RX_DP1")
	)
	(segment
		(start 76.962 -33.3502)
		(end 75.057 -33.3502)
		(width 0.1143)
		(layer "In4.Cu")
		(net "SATA3_RX_DP1")
	)
	(segment
		(start 76.9874 -33.3502)
		(end 76.962 -33.3502)
		(width 0.1016)
		(layer "In4.Cu")
		(net "SATA3_RX_DP1")
	)
	(segment
		(start 34.35477 -50.58537)
		(end 33.474914 -49.705514)
		(width 0.1143)
		(layer "In4.Cu")
		(net "SATA3_RX_DP1")
	)
	(segment
		(start 74.4601 -33.9471)
		(end 65.93205 -33.9471)
		(width 0.1143)
		(layer "In4.Cu")
		(net "SATA3_RX_DP1")
	)
	(segment
		(start 77.5081 -33.2867)
		(end 77.0509 -33.2867)
		(width 0.1016)
		(layer "In4.Cu")
		(net "SATA3_RX_DP1")
	)
	(segment
		(start 10.3886 -53.5686)
		(end 10.2616 -53.6956)
		(width 0.1143)
		(layer "In4.Cu")
		(net "SATA3_RX_DP1")
	)
	(segment
		(start 78.892654 -30.5308)
		(end 80.195928 -30.5308)
		(width 0.1016)
		(layer "In4.Cu")
		(net "SATA3_RX_DP1")
	)
	(segment
		(start 80.195928 -30.5308)
		(end 80.7212 -31.056072)
		(width 0.1016)
		(layer "In4.Cu")
		(net "SATA3_RX_DP1")
	)
	(segment
		(start 23.885906 -52.76215)
		(end 12.525756 -52.76215)
		(width 0.1143)
		(layer "In4.Cu")
		(net "SATA3_RX_DP1")
	)
	(segment
		(start 52.324 -46.96333)
		(end 52.324 -48.955706)
		(width 0.1143)
		(layer "In4.Cu")
		(net "SATA3_RX_DP1")
	)
	(segment
		(start 77.0509 -33.2867)
		(end 76.9874 -33.3502)
		(width 0.1016)
		(layer "In4.Cu")
		(net "SATA3_RX_DP1")
	)
	(segment
		(start 36.248086 -50.58537)
		(end 34.35477 -50.58537)
		(width 0.1143)
		(layer "In4.Cu")
		(net "SATA3_RX_DP1")
	)
	(segment
		(start 52.324 -48.955706)
		(end 51.870356 -49.40935)
		(width 0.1143)
		(layer "In4.Cu")
		(net "SATA3_RX_DP1")
	)
	(segment
		(start 50.011584 -49.76495)
		(end 37.068506 -49.76495)
		(width 0.1143)
		(layer "In4.Cu")
		(net "SATA3_RX_DP1")
	)
	(segment
		(start 10.2616 -53.6956)
		(end 10.2616 -54.0258)
		(width 0.1143)
		(layer "In4.Cu")
		(net "SATA3_RX_DP1")
	)
	(segment
		(start 54.794404 -45.084746)
		(end 54.202584 -45.084746)
		(width 0.1143)
		(layer "In4.Cu")
		(net "SATA3_RX_DP1")
	)
	(segment
		(start 49.4792 -52.3494)
		(end 49.4792 -53.111146)
		(width 0.5588)
		(layer "F.Cu")
		(net "P1V5_STBY")
	)
	(segment
		(start 50.113946 -51.460654)
		(end 50.3428 -51.460654)
		(width 0.5588)
		(layer "F.Cu")
		(net "P1V5_STBY")
	)
	(segment
		(start 49.4792 -52.3494)
		(end 49.4792 -52.0954)
		(width 0.5588)
		(layer "F.Cu")
		(net "P1V5_STBY")
	)
	(segment
		(start 49.4792 -53.111146)
		(end 49.746154 -53.3781)
		(width 0.5588)
		(layer "F.Cu")
		(net "P1V5_STBY")
	)
	(segment
		(start 49.4792 -52.0954)
		(end 50.113946 -51.460654)
		(width 0.5588)
		(layer "F.Cu")
		(net "P1V5_STBY")
	)
	(via
		(at 32.639 -41.91)
		(size 0.7112)
		(drill 0.4064)
		(layers "F.Cu" "B.Cu")
		(net "P1V5_STBY")
	)
	(via
		(at 49.4792 -52.3494)
		(size 0.508)
		(drill 0.254)
		(layers "F.Cu" "B.Cu")
		(net "P1V5_STBY")
	)
	(via
		(at 38.054026 -39.42715)
		(size 0.7112)
		(drill 0.3556)
		(layers "F.Cu" "B.Cu")
		(net "P1V5_STBY")
	)
	(segment
		(start 33.432242 -39.5986)
		(end 37.882576 -39.5986)
		(width 0.508)
		(layer "B.Cu")
		(net "P1V5_STBY")
	)
	(segment
		(start 33.0454 -39.985442)
		(end 33.432242 -39.5986)
		(width 0.508)
		(layer "B.Cu")
		(net "P1V5_STBY")
	)
	(segment
		(start 33.0454 -40.6146)
		(end 33.0454 -39.985442)
		(width 0.508)
		(layer "B.Cu")
		(net "P1V5_STBY")
	)
	(segment
		(start 37.882576 -39.5986)
		(end 38.054026 -39.42715)
		(width 0.508)
		(layer "B.Cu")
		(net "P1V5_STBY")
	)
	(segment
		(start 39.3446 -40.005)
		(end 38.76675 -39.42715)
		(width 0.508)
		(layer "B.Cu")
		(net "P1V5_STBY")
	)
	(segment
		(start 38.76675 -39.42715)
		(end 38.054026 -39.42715)
		(width 0.508)
		(layer "B.Cu")
		(net "P1V5_STBY")
	)
	(segment
		(start 32.766 -40.894)
		(end 33.0454 -40.6146)
		(width 0.508)
		(layer "B.Cu")
		(net "P1V5_STBY")
	)
	(segment
		(start 44.777914 -53.929788)
		(end 44.746672 -53.898546)
		(width 0.5588)
		(layer "In2.Cu")
		(net "P1V5_STBY")
	)
	(segment
		(start 49.4792 -52.455826)
		(end 48.005238 -53.929788)
		(width 0.5588)
		(layer "In2.Cu")
		(net "P1V5_STBY")
	)
	(segment
		(start 42.477182 -53.898292)
		(end 37.34689 -48.768)
		(width 0.5588)
		(layer "In2.Cu")
		(net "P1V5_STBY")
	)
	(segment
		(start 34.640774 -48.768)
		(end 33.8582 -47.985426)
		(width 0.5588)
		(layer "In2.Cu")
		(net "P1V5_STBY")
	)
	(segment
		(start 33.8582 -43.1292)
		(end 32.639 -41.91)
		(width 0.5588)
		(layer "In2.Cu")
		(net "P1V5_STBY")
	)
	(segment
		(start 44.745402 -53.898292)
		(end 42.477182 -53.898292)
		(width 0.5588)
		(layer "In2.Cu")
		(net "P1V5_STBY")
	)
	(segment
		(start 44.746672 -53.898546)
		(end 44.745402 -53.898292)
		(width 0.5588)
		(layer "In2.Cu")
		(net "P1V5_STBY")
	)
	(segment
		(start 37.34689 -48.768)
		(end 34.640774 -48.768)
		(width 0.5588)
		(layer "In2.Cu")
		(net "P1V5_STBY")
	)
	(segment
		(start 33.8582 -47.985426)
		(end 33.8582 -43.1292)
		(width 0.5588)
		(layer "In2.Cu")
		(net "P1V5_STBY")
	)
	(segment
		(start 48.005238 -53.929788)
		(end 44.777914 -53.929788)
		(width 0.5588)
		(layer "In2.Cu")
		(net "P1V5_STBY")
	)
	(segment
		(start 49.4792 -52.3494)
		(end 49.4792 -52.455826)
		(width 0.5588)
		(layer "In2.Cu")
		(net "P1V5_STBY")
	)
	(segment
		(start 94.4753 -23.495)
		(end 94.4753 -24.898096)
		(width 0.1016)
		(layer "F.Cu")
		(net "M_B_DQ12")
	)
	(segment
		(start 134.24535 -3.183128)
		(end 134.24535 -3.187446)
		(width 0.1778)
		(layer "F.Cu")
		(net "M_B_DQ12")
	)
	(segment
		(start 96.464628 -27.737562)
		(end 96.464628 -28.135834)
		(width 0.1016)
		(layer "F.Cu")
		(net "M_B_DQ12")
	)
	(segment
		(start 133.75005 -1.68402)
		(end 133.75005 -2.687828)
		(width 0.1778)
		(layer "F.Cu")
		(net "M_B_DQ12")
	)
	(segment
		(start 95.590868 -26.013664)
		(end 95.590868 -27.015186)
		(width 0.1016)
		(layer "F.Cu")
		(net "M_B_DQ12")
	)
	(segment
		(start 95.590868 -27.015186)
		(end 95.833184 -27.257502)
		(width 0.1016)
		(layer "F.Cu")
		(net "M_B_DQ12")
	)
	(segment
		(start 95.833184 -27.257502)
		(end 95.984568 -27.257502)
		(width 0.1016)
		(layer "F.Cu")
		(net "M_B_DQ12")
	)
	(segment
		(start 94.4753 -24.898096)
		(end 95.590868 -26.013664)
		(width 0.1016)
		(layer "F.Cu")
		(net "M_B_DQ12")
	)
	(segment
		(start 95.984568 -27.257502)
		(end 96.464628 -27.737562)
		(width 0.1016)
		(layer "F.Cu")
		(net "M_B_DQ12")
	)
	(segment
		(start 133.75005 -2.687828)
		(end 134.24535 -3.183128)
		(width 0.1778)
		(layer "F.Cu")
		(net "M_B_DQ12")
	)
	(via
		(at 94.4753 -23.495)
		(size 0.4318)
		(drill 0.2032)
		(layers "F.Cu" "B.Cu")
		(net "M_B_DQ12")
	)
	(via
		(at 134.24535 -3.187446)
		(size 0.4318)
		(drill 0.2032)
		(layers "F.Cu" "B.Cu")
		(net "M_B_DQ12")
	)
	(segment
		(start 134.649972 -2.638806)
		(end 134.2644 -3.024378)
		(width 0.1778)
		(layer "B.Cu")
		(net "M_B_DQ12")
	)
	(segment
		(start 134.2644 -3.168396)
		(end 134.24535 -3.187446)
		(width 0.1778)
		(layer "B.Cu")
		(net "M_B_DQ12")
	)
	(segment
		(start 134.2644 -3.024378)
		(end 134.2644 -3.168396)
		(width 0.1778)
		(layer "B.Cu")
		(net "M_B_DQ12")
	)
	(segment
		(start 134.649972 -1.690624)
		(end 134.649972 -2.638806)
		(width 0.1778)
		(layer "B.Cu")
		(net "M_B_DQ12")
	)
	(segment
		(start 105.6894 -14.859)
		(end 109.3978 -11.1506)
		(width 0.1524)
		(layer "In2.Cu")
		(net "M_B_DQ12")
	)
	(segment
		(start 133.6294 -4.9276)
		(end 133.6294 -3.760978)
		(width 0.1524)
		(layer "In2.Cu")
		(net "M_B_DQ12")
	)
	(segment
		(start 131.532122 -7.024878)
		(end 133.6294 -4.9276)
		(width 0.1524)
		(layer "In2.Cu")
		(net "M_B_DQ12")
	)
	(segment
		(start 94.0308 -19.575526)
		(end 98.747326 -14.859)
		(width 0.1524)
		(layer "In2.Cu")
		(net "M_B_DQ12")
	)
	(segment
		(start 123.0376 -8.89)
		(end 124.6124 -10.4648)
		(width 0.1524)
		(layer "In2.Cu")
		(net "M_B_DQ12")
	)
	(segment
		(start 125.349 -10.3124)
		(end 125.349 -9.7282)
		(width 0.1524)
		(layer "In2.Cu")
		(net "M_B_DQ12")
	)
	(segment
		(start 124.6124 -10.4648)
		(end 125.1966 -10.4648)
		(width 0.1524)
		(layer "In2.Cu")
		(net "M_B_DQ12")
	)
	(segment
		(start 98.747326 -14.859)
		(end 105.6894 -14.859)
		(width 0.1524)
		(layer "In2.Cu")
		(net "M_B_DQ12")
	)
	(segment
		(start 125.9586 -9.7282)
		(end 125.9586 -10.3124)
		(width 0.1524)
		(layer "In2.Cu")
		(net "M_B_DQ12")
	)
	(segment
		(start 109.3978 -11.1506)
		(end 113.079276 -11.1506)
		(width 0.1524)
		(layer "In2.Cu")
		(net "M_B_DQ12")
	)
	(segment
		(start 125.8062 -9.5758)
		(end 125.9586 -9.7282)
		(width 0.1524)
		(layer "In2.Cu")
		(net "M_B_DQ12")
	)
	(segment
		(start 115.339876 -8.89)
		(end 123.0376 -8.89)
		(width 0.1524)
		(layer "In2.Cu")
		(net "M_B_DQ12")
	)
	(segment
		(start 127.8128 -9.144)
		(end 127.8128 -7.875778)
		(width 0.1524)
		(layer "In2.Cu")
		(net "M_B_DQ12")
	)
	(segment
		(start 134.202932 -3.187446)
		(end 134.24535 -3.187446)
		(width 0.1524)
		(layer "In2.Cu")
		(net "M_B_DQ12")
	)
	(segment
		(start 127.8128 -7.875778)
		(end 128.6637 -7.024878)
		(width 0.1524)
		(layer "In2.Cu")
		(net "M_B_DQ12")
	)
	(segment
		(start 126.111 -10.4648)
		(end 126.492 -10.4648)
		(width 0.1524)
		(layer "In2.Cu")
		(net "M_B_DQ12")
	)
	(segment
		(start 125.5014 -9.5758)
		(end 125.8062 -9.5758)
		(width 0.1524)
		(layer "In2.Cu")
		(net "M_B_DQ12")
	)
	(segment
		(start 94.0308 -23.0505)
		(end 94.0308 -19.575526)
		(width 0.1524)
		(layer "In2.Cu")
		(net "M_B_DQ12")
	)
	(segment
		(start 126.492 -10.4648)
		(end 127.8128 -9.144)
		(width 0.1524)
		(layer "In2.Cu")
		(net "M_B_DQ12")
	)
	(segment
		(start 113.079276 -11.1506)
		(end 115.339876 -8.89)
		(width 0.1524)
		(layer "In2.Cu")
		(net "M_B_DQ12")
	)
	(segment
		(start 133.6294 -3.760978)
		(end 134.202932 -3.187446)
		(width 0.1524)
		(layer "In2.Cu")
		(net "M_B_DQ12")
	)
	(segment
		(start 125.349 -9.7282)
		(end 125.5014 -9.5758)
		(width 0.1524)
		(layer "In2.Cu")
		(net "M_B_DQ12")
	)
	(segment
		(start 94.4753 -23.495)
		(end 94.0308 -23.0505)
		(width 0.1524)
		(layer "In2.Cu")
		(net "M_B_DQ12")
	)
	(segment
		(start 125.1966 -10.4648)
		(end 125.349 -10.3124)
		(width 0.1524)
		(layer "In2.Cu")
		(net "M_B_DQ12")
	)
	(segment
		(start 125.9586 -10.3124)
		(end 126.111 -10.4648)
		(width 0.1524)
		(layer "In2.Cu")
		(net "M_B_DQ12")
	)
	(segment
		(start 128.6637 -7.024878)
		(end 131.532122 -7.024878)
		(width 0.1524)
		(layer "In2.Cu")
		(net "M_B_DQ12")
	)
	(segment
		(start 45.5676 -23.9268)
		(end 45.5676 -23.0886)
		(width 0.1143)
		(layer "F.Cu")
		(net "XDP_DFX_PORT3")
	)
	(segment
		(start 43.2943 -24.05507)
		(end 42.10177 -24.05507)
		(width 0.1143)
		(layer "F.Cu")
		(net "XDP_DFX_PORT3")
	)
	(segment
		(start 84.061808 -42.702734)
		(end 84.417662 -43.058588)
		(width 0.1143)
		(layer "F.Cu")
		(net "XDP_DFX_PORT3")
	)
	(segment
		(start 45.5676 -23.0886)
		(end 45.464476 -22.985476)
		(width 0.1143)
		(layer "F.Cu")
		(net "XDP_DFX_PORT3")
	)
	(segment
		(start 84.028788 -42.702734)
		(end 84.061808 -42.702734)
		(width 0.1143)
		(layer "F.Cu")
		(net "XDP_DFX_PORT3")
	)
	(segment
		(start 45.464476 -22.985476)
		(end 45.464476 -22.922738)
		(width 0.1143)
		(layer "F.Cu")
		(net "XDP_DFX_PORT3")
	)
	(segment
		(start 45.464476 -22.922738)
		(end 44.895262 -22.922738)
		(width 0.1143)
		(layer "F.Cu")
		(net "XDP_DFX_PORT3")
	)
	(segment
		(start 44.08805 -23.72995)
		(end 43.61942 -23.72995)
		(width 0.1143)
		(layer "F.Cu")
		(net "XDP_DFX_PORT3")
	)
	(segment
		(start 44.895262 -22.922738)
		(end 44.08805 -23.72995)
		(width 0.1143)
		(layer "F.Cu")
		(net "XDP_DFX_PORT3")
	)
	(segment
		(start 43.61942 -23.72995)
		(end 43.2943 -24.05507)
		(width 0.1143)
		(layer "F.Cu")
		(net "XDP_DFX_PORT3")
	)
	(via
		(at 45.464476 -22.922738)
		(size 0.7112)
		(drill 0.3556)
		(layers "F.Cu" "B.Cu")
		(net "XDP_DFX_PORT3")
	)
	(via
		(at 45.5676 -23.9268)
		(size 0.508)
		(drill 0.254)
		(layers "F.Cu" "B.Cu")
		(net "XDP_DFX_PORT3")
	)
	(via
		(at 84.417662 -43.058588)
		(size 0.4318)
		(drill 0.2032)
		(layers "F.Cu" "B.Cu")
		(net "XDP_DFX_PORT3")
	)
	(segment
		(start 73.031858 -34.0868)
		(end 73.9775 -35.032442)
		(width 0.0889)
		(layer "In7.Cu")
		(net "XDP_DFX_PORT3")
	)
	(segment
		(start 52.308252 -32.1056)
		(end 64.608202 -32.1056)
		(width 0.0889)
		(layer "In7.Cu")
		(net "XDP_DFX_PORT3")
	)
	(segment
		(start 76.858622 -38.335966)
		(end 76.858622 -39.756842)
		(width 0.0889)
		(layer "In7.Cu")
		(net "XDP_DFX_PORT3")
	)
	(segment
		(start 79.678784 -40.698674)
		(end 81.794096 -42.813986)
		(width 0.0889)
		(layer "In7.Cu")
		(net "XDP_DFX_PORT3")
	)
	(segment
		(start 73.9775 -35.395408)
		(end 74.920094 -36.338002)
		(width 0.0889)
		(layer "In7.Cu")
		(net "XDP_DFX_PORT3")
	)
	(segment
		(start 74.920094 -36.397438)
		(end 76.858622 -38.335966)
		(width 0.0889)
		(layer "In7.Cu")
		(net "XDP_DFX_PORT3")
	)
	(segment
		(start 48.523652 -28.321)
		(end 52.308252 -32.1056)
		(width 0.0889)
		(layer "In7.Cu")
		(net "XDP_DFX_PORT3")
	)
	(segment
		(start 73.9775 -35.032442)
		(end 73.9775 -35.395408)
		(width 0.0889)
		(layer "In7.Cu")
		(net "XDP_DFX_PORT3")
	)
	(segment
		(start 84.195412 -43.058588)
		(end 84.417662 -43.058588)
		(width 0.0889)
		(layer "In7.Cu")
		(net "XDP_DFX_PORT3")
	)
	(segment
		(start 45.6946 -24.0538)
		(end 45.6946 -27.686)
		(width 0.0889)
		(layer "In7.Cu")
		(net "XDP_DFX_PORT3")
	)
	(segment
		(start 83.267296 -43.144694)
		(end 83.528154 -43.405552)
		(width 0.0889)
		(layer "In7.Cu")
		(net "XDP_DFX_PORT3")
	)
	(segment
		(start 81.794096 -42.813986)
		(end 82.60715 -42.813986)
		(width 0.0889)
		(layer "In7.Cu")
		(net "XDP_DFX_PORT3")
	)
	(segment
		(start 66.589656 -34.087054)
		(end 67.199764 -34.087054)
		(width 0.0889)
		(layer "In7.Cu")
		(net "XDP_DFX_PORT3")
	)
	(segment
		(start 46.3296 -28.321)
		(end 48.523652 -28.321)
		(width 0.0889)
		(layer "In7.Cu")
		(net "XDP_DFX_PORT3")
	)
	(segment
		(start 45.5676 -23.9268)
		(end 45.6946 -24.0538)
		(width 0.0889)
		(layer "In7.Cu")
		(net "XDP_DFX_PORT3")
	)
	(segment
		(start 83.848448 -43.405552)
		(end 84.195412 -43.058588)
		(width 0.0889)
		(layer "In7.Cu")
		(net "XDP_DFX_PORT3")
	)
	(segment
		(start 83.528154 -43.405552)
		(end 83.848448 -43.405552)
		(width 0.0889)
		(layer "In7.Cu")
		(net "XDP_DFX_PORT3")
	)
	(segment
		(start 74.920094 -36.338002)
		(end 74.920094 -36.397438)
		(width 0.0889)
		(layer "In7.Cu")
		(net "XDP_DFX_PORT3")
	)
	(segment
		(start 77.800454 -40.698674)
		(end 79.678784 -40.698674)
		(width 0.0889)
		(layer "In7.Cu")
		(net "XDP_DFX_PORT3")
	)
	(segment
		(start 67.200018 -34.0868)
		(end 73.031858 -34.0868)
		(width 0.0889)
		(layer "In7.Cu")
		(net "XDP_DFX_PORT3")
	)
	(segment
		(start 76.858622 -39.756842)
		(end 77.800454 -40.698674)
		(width 0.0889)
		(layer "In7.Cu")
		(net "XDP_DFX_PORT3")
	)
	(segment
		(start 83.267296 -42.87774)
		(end 83.267296 -43.144694)
		(width 0.0889)
		(layer "In7.Cu")
		(net "XDP_DFX_PORT3")
	)
	(segment
		(start 64.608202 -32.1056)
		(end 66.589656 -34.087054)
		(width 0.0889)
		(layer "In7.Cu")
		(net "XDP_DFX_PORT3")
	)
	(segment
		(start 67.199764 -34.087054)
		(end 67.200018 -34.0868)
		(width 0.0889)
		(layer "In7.Cu")
		(net "XDP_DFX_PORT3")
	)
	(segment
		(start 83.05546 -42.665904)
		(end 83.267296 -42.87774)
		(width 0.0889)
		(layer "In7.Cu")
		(net "XDP_DFX_PORT3")
	)
	(segment
		(start 82.755232 -42.665904)
		(end 83.05546 -42.665904)
		(width 0.0889)
		(layer "In7.Cu")
		(net "XDP_DFX_PORT3")
	)
	(segment
		(start 45.6946 -27.686)
		(end 46.3296 -28.321)
		(width 0.0889)
		(layer "In7.Cu")
		(net "XDP_DFX_PORT3")
	)
	(segment
		(start 82.60715 -42.813986)
		(end 82.755232 -42.665904)
		(width 0.0889)
		(layer "In7.Cu")
		(net "XDP_DFX_PORT3")
	)
	(segment
		(start 79.995268 -30.711394)
		(end 80.096868 -30.812994)
		(width 0.1016)
		(layer "F.Cu")
		(net "SATA3_RX_DN1")
	)
	(segment
		(start 10.922 -52.7812)
		(end 10.2616 -52.7812)
		(width 0.1397)
		(layer "F.Cu")
		(net "SATA3_RX_DN1")
	)
	(segment
		(start 78.78572 -30.711394)
		(end 79.995268 -30.711394)
		(width 0.1016)
		(layer "F.Cu")
		(net "SATA3_RX_DN1")
	)
	(segment
		(start 77.976476 -29.90215)
		(end 78.78572 -30.711394)
		(width 0.1016)
		(layer "F.Cu")
		(net "SATA3_RX_DN1")
	)
	(via
		(at 10.2616 -52.7812)
		(size 0.508)
		(drill 0.254)
		(layers "F.Cu" "B.Cu")
		(net "SATA3_RX_DN1")
	)
	(via
		(at 77.976476 -29.90215)
		(size 0.4318)
		(drill 0.2032)
		(layers "F.Cu" "B.Cu")
		(net "SATA3_RX_DN1")
	)
	(segment
		(start 73.980294 -33.6169)
		(end 73.766934 -33.40354)
		(width 0.1143)
		(layer "In4.Cu")
		(net "SATA3_RX_DN1")
	)
	(segment
		(start 65.795144 -33.6169)
		(end 54.657498 -44.754546)
		(width 0.1143)
		(layer "In4.Cu")
		(net "SATA3_RX_DN1")
	)
	(segment
		(start 67.250564 -33.6169)
		(end 65.795144 -33.6169)
		(width 0.1143)
		(layer "In4.Cu")
		(net "SATA3_RX_DN1")
	)
	(segment
		(start 36.11118 -50.25517)
		(end 34.491676 -50.25517)
		(width 0.1143)
		(layer "In4.Cu")
		(net "SATA3_RX_DN1")
	)
	(segment
		(start 72.098154 -33.6169)
		(end 69.132704 -33.6169)
		(width 0.1143)
		(layer "In4.Cu")
		(net "SATA3_RX_DN1")
	)
	(segment
		(start 80.518 -31.1404)
		(end 80.518 -31.589472)
		(width 0.1016)
		(layer "In4.Cu")
		(net "SATA3_RX_DN1")
	)
	(segment
		(start 77.0509 -33.0835)
		(end 76.9874 -33.02)
		(width 0.1016)
		(layer "In4.Cu")
		(net "SATA3_RX_DN1")
	)
	(segment
		(start 67.463924 -33.40354)
		(end 67.250564 -33.6169)
		(width 0.1143)
		(layer "In4.Cu")
		(net "SATA3_RX_DN1")
	)
	(segment
		(start 76.962 -33.02)
		(end 74.920094 -33.02)
		(width 0.1143)
		(layer "In4.Cu")
		(net "SATA3_RX_DN1")
	)
	(segment
		(start 74.920094 -33.02)
		(end 74.323194 -33.6169)
		(width 0.1143)
		(layer "In4.Cu")
		(net "SATA3_RX_DN1")
	)
	(segment
		(start 77.969872 -32.5374)
		(end 77.423772 -33.0835)
		(width 0.1016)
		(layer "In4.Cu")
		(net "SATA3_RX_DN1")
	)
	(segment
		(start 23.749 -52.43195)
		(end 12.38885 -52.43195)
		(width 0.1143)
		(layer "In4.Cu")
		(net "SATA3_RX_DN1")
	)
	(segment
		(start 51.9938 -48.8188)
		(end 51.73345 -49.07915)
		(width 0.1143)
		(layer "In4.Cu")
		(net "SATA3_RX_DN1")
	)
	(segment
		(start 50.230278 -49.07915)
		(end 49.874678 -49.43475)
		(width 0.1143)
		(layer "In4.Cu")
		(net "SATA3_RX_DN1")
	)
	(segment
		(start 80.518 -31.589472)
		(end 79.570072 -32.5374)
		(width 0.1016)
		(layer "In4.Cu")
		(net "SATA3_RX_DN1")
	)
	(segment
		(start 54.657498 -44.754546)
		(end 54.065678 -44.754546)
		(width 0.1143)
		(layer "In4.Cu")
		(net "SATA3_RX_DN1")
	)
	(segment
		(start 68.919344 -33.40354)
		(end 68.576444 -33.40354)
		(width 0.1143)
		(layer "In4.Cu")
		(net "SATA3_RX_DN1")
	)
	(segment
		(start 51.73345 -49.07915)
		(end 50.230278 -49.07915)
		(width 0.1143)
		(layer "In4.Cu")
		(net "SATA3_RX_DN1")
	)
	(segment
		(start 76.9874 -33.02)
		(end 76.962 -33.02)
		(width 0.1016)
		(layer "In4.Cu")
		(net "SATA3_RX_DN1")
	)
	(segment
		(start 51.9938 -46.826424)
		(end 51.9938 -48.8188)
		(width 0.1143)
		(layer "In4.Cu")
		(net "SATA3_RX_DN1")
	)
	(segment
		(start 72.311514 -33.40354)
		(end 72.098154 -33.6169)
		(width 0.1143)
		(layer "In4.Cu")
		(net "SATA3_RX_DN1")
	)
	(segment
		(start 78.808326 -30.734)
		(end 80.1116 -30.734)
		(width 0.1016)
		(layer "In4.Cu")
		(net "SATA3_RX_DN1")
	)
	(segment
		(start 68.363084 -33.6169)
		(end 68.020184 -33.6169)
		(width 0.1143)
		(layer "In4.Cu")
		(net "SATA3_RX_DN1")
	)
	(segment
		(start 54.065678 -44.754546)
		(end 51.9938 -46.826424)
		(width 0.1143)
		(layer "In4.Cu")
		(net "SATA3_RX_DN1")
	)
	(segment
		(start 73.766934 -33.40354)
		(end 73.424034 -33.40354)
		(width 0.1143)
		(layer "In4.Cu")
		(net "SATA3_RX_DN1")
	)
	(segment
		(start 11.5824 -53.2384)
		(end 10.4902 -53.2384)
		(width 0.1143)
		(layer "In4.Cu")
		(net "SATA3_RX_DN1")
	)
	(segment
		(start 69.132704 -33.6169)
		(end 68.919344 -33.40354)
		(width 0.1143)
		(layer "In4.Cu")
		(net "SATA3_RX_DN1")
	)
	(segment
		(start 10.4902 -53.2384)
		(end 10.2616 -53.0098)
		(width 0.1143)
		(layer "In4.Cu")
		(net "SATA3_RX_DN1")
	)
	(segment
		(start 79.570072 -32.5374)
		(end 77.969872 -32.5374)
		(width 0.1016)
		(layer "In4.Cu")
		(net "SATA3_RX_DN1")
	)
	(segment
		(start 10.2616 -53.0098)
		(end 10.2616 -52.7812)
		(width 0.1143)
		(layer "In4.Cu")
		(net "SATA3_RX_DN1")
	)
	(segment
		(start 73.210674 -33.6169)
		(end 72.867774 -33.6169)
		(width 0.1143)
		(layer "In4.Cu")
		(net "SATA3_RX_DN1")
	)
	(segment
		(start 72.867774 -33.6169)
		(end 72.654414 -33.40354)
		(width 0.1143)
		(layer "In4.Cu")
		(net "SATA3_RX_DN1")
	)
	(segment
		(start 33.61182 -49.375314)
		(end 26.805636 -49.375314)
		(width 0.1143)
		(layer "In4.Cu")
		(net "SATA3_RX_DN1")
	)
	(segment
		(start 34.491676 -50.25517)
		(end 33.61182 -49.375314)
		(width 0.1143)
		(layer "In4.Cu")
		(net "SATA3_RX_DN1")
	)
	(segment
		(start 68.576444 -33.40354)
		(end 68.363084 -33.6169)
		(width 0.1143)
		(layer "In4.Cu")
		(net "SATA3_RX_DN1")
	)
	(segment
		(start 72.654414 -33.40354)
		(end 72.311514 -33.40354)
		(width 0.1143)
		(layer "In4.Cu")
		(net "SATA3_RX_DN1")
	)
	(segment
		(start 74.323194 -33.6169)
		(end 73.980294 -33.6169)
		(width 0.1143)
		(layer "In4.Cu")
		(net "SATA3_RX_DN1")
	)
	(segment
		(start 36.9316 -49.43475)
		(end 36.11118 -50.25517)
		(width 0.1143)
		(layer "In4.Cu")
		(net "SATA3_RX_DN1")
	)
	(segment
		(start 77.423772 -33.0835)
		(end 77.0509 -33.0835)
		(width 0.1016)
		(layer "In4.Cu")
		(net "SATA3_RX_DN1")
	)
	(segment
		(start 67.806824 -33.40354)
		(end 67.463924 -33.40354)
		(width 0.1143)
		(layer "In4.Cu")
		(net "SATA3_RX_DN1")
	)
	(segment
		(start 73.424034 -33.40354)
		(end 73.210674 -33.6169)
		(width 0.1143)
		(layer "In4.Cu")
		(net "SATA3_RX_DN1")
	)
	(segment
		(start 26.805636 -49.375314)
		(end 23.749 -52.43195)
		(width 0.1143)
		(layer "In4.Cu")
		(net "SATA3_RX_DN1")
	)
	(segment
		(start 68.020184 -33.6169)
		(end 67.806824 -33.40354)
		(width 0.1143)
		(layer "In4.Cu")
		(net "SATA3_RX_DN1")
	)
	(segment
		(start 80.1116 -30.734)
		(end 80.518 -31.1404)
		(width 0.1016)
		(layer "In4.Cu")
		(net "SATA3_RX_DN1")
	)
	(segment
		(start 12.38885 -52.43195)
		(end 11.5824 -53.2384)
		(width 0.1143)
		(layer "In4.Cu")
		(net "SATA3_RX_DN1")
	)
	(segment
		(start 49.874678 -49.43475)
		(end 36.9316 -49.43475)
		(width 0.1143)
		(layer "In4.Cu")
		(net "SATA3_RX_DN1")
	)
	(segment
		(start 77.976476 -29.90215)
		(end 78.808326 -30.734)
		(width 0.1016)
		(layer "In4.Cu")
		(net "SATA3_RX_DN1")
	)
	(via
		(at 33.7058 -46.5074)
		(size 0.7112)
		(drill 0.3556)
		(layers "F.Cu" "B.Cu")
		(net "P1V5_STBY_SS")
	)
	(segment
		(start 33.705546 -47.320454)
		(end 33.7058 -47.3202)
		(width 0.254)
		(layer "B.Cu")
		(net "P1V5_STBY_SS")
	)
	(segment
		(start 33.7058 -47.3202)
		(end 33.7058 -46.5074)
		(width 0.254)
		(layer "B.Cu")
		(net "P1V5_STBY_SS")
	)
	(segment
		(start 32.766762 -47.320454)
		(end 33.705546 -47.320454)
		(width 0.254)
		(layer "B.Cu")
		(net "P1V5_STBY_SS")
	)
	(segment
		(start 157.447996 -18.923)
		(end 153.7208 -15.195804)
		(width 0.2032)
		(layer "F.Cu")
		(net "VR_PVDDR_A_VTT")
	)
	(segment
		(start 153.7208 -15.195804)
		(end 153.7208 -13.140436)
		(width 0.2032)
		(layer "F.Cu")
		(net "VR_PVDDR_A_VTT")
	)
	(segment
		(start 178.58486 -21.5011)
		(end 162.7251 -21.5011)
		(width 0.2032)
		(layer "F.Cu")
		(net "VR_PVDDR_A_VTT")
	)
	(segment
		(start 185.884566 -25.273)
		(end 182.35676 -25.273)
		(width 0.2032)
		(layer "F.Cu")
		(net "VR_PVDDR_A_VTT")
	)
	(segment
		(start 153.7208 -13.140436)
		(end 154.413458 -12.447778)
		(width 0.2032)
		(layer "F.Cu")
		(net "VR_PVDDR_A_VTT")
	)
	(segment
		(start 186.646566 -24.511)
		(end 185.884566 -25.273)
		(width 0.2032)
		(layer "F.Cu")
		(net "VR_PVDDR_A_VTT")
	)
	(segment
		(start 182.35676 -25.273)
		(end 178.58486 -21.5011)
		(width 0.2032)
		(layer "F.Cu")
		(net "VR_PVDDR_A_VTT")
	)
	(segment
		(start 162.7251 -21.5011)
		(end 160.147 -18.923)
		(width 0.2032)
		(layer "F.Cu")
		(net "VR_PVDDR_A_VTT")
	)
	(segment
		(start 187.9346 -25.781)
		(end 187.9346 -24.9936)
		(width 0.2032)
		(layer "F.Cu")
		(net "VR_PVDDR_A_VTT")
	)
	(segment
		(start 187.9346 -24.9936)
		(end 187.452 -24.511)
		(width 0.2032)
		(layer "F.Cu")
		(net "VR_PVDDR_A_VTT")
	)
	(segment
		(start 154.413458 -12.447778)
		(end 154.5082 -12.447778)
		(width 0.2032)
		(layer "F.Cu")
		(net "VR_PVDDR_A_VTT")
	)
	(segment
		(start 158.369 -18.923)
		(end 157.447996 -18.923)
		(width 0.2032)
		(layer "F.Cu")
		(net "VR_PVDDR_A_VTT")
	)
	(segment
		(start 187.452 -24.511)
		(end 186.646566 -24.511)
		(width 0.2032)
		(layer "F.Cu")
		(net "VR_PVDDR_A_VTT")
	)
	(segment
		(start 160.147 -18.923)
		(end 158.369 -18.923)
		(width 0.2032)
		(layer "F.Cu")
		(net "VR_PVDDR_A_VTT")
	)
	(via
		(at 158.369 -18.923)
		(size 0.7112)
		(drill 0.3556)
		(layers "F.Cu" "B.Cu")
		(net "VR_PVDDR_A_VTT")
	)
	(segment
		(start 183.8198 -2.973578)
		(end 183.8198 -3.547364)
		(width 0.1778)
		(layer "F.Cu")
		(net "M_B_DQ55")
	)
	(segment
		(start 107.671108 -35.697414)
		(end 107.913424 -36.13658)
		(width 0.1016)
		(layer "F.Cu")
		(net "M_B_DQ55")
	)
	(segment
		(start 183.8198 -3.547364)
		(end 183.790844 -3.57632)
		(width 0.1778)
		(layer "F.Cu")
		(net "M_B_DQ55")
	)
	(segment
		(start 184.15 -2.643378)
		(end 183.8198 -2.973578)
		(width 0.1778)
		(layer "F.Cu")
		(net "M_B_DQ55")
	)
	(segment
		(start 184.15 -1.68402)
		(end 184.15 -2.643378)
		(width 0.1778)
		(layer "F.Cu")
		(net "M_B_DQ55")
	)
	(via
		(at 107.913424 -36.13658)
		(size 0.4318)
		(drill 0.2032)
		(layers "F.Cu" "B.Cu")
		(net "M_B_DQ55")
	)
	(via
		(at 183.790844 -3.57632)
		(size 0.4318)
		(drill 0.2032)
		(layers "F.Cu" "B.Cu")
		(net "M_B_DQ55")
	)
	(segment
		(start 183.249824 -2.522982)
		(end 183.790844 -3.064002)
		(width 0.1778)
		(layer "B.Cu")
		(net "M_B_DQ55")
	)
	(segment
		(start 183.249824 -1.690624)
		(end 183.249824 -2.522982)
		(width 0.1778)
		(layer "B.Cu")
		(net "M_B_DQ55")
	)
	(segment
		(start 183.790844 -3.064002)
		(end 183.790844 -3.57632)
		(width 0.1778)
		(layer "B.Cu")
		(net "M_B_DQ55")
	)
	(segment
		(start 183.6928 -6.402578)
		(end 182.733696 -7.361682)
		(width 0.1524)
		(layer "In9.Cu")
		(net "M_B_DQ55")
	)
	(segment
		(start 113.6142 -38.0238)
		(end 112.8776 -37.2872)
		(width 0.1524)
		(layer "In9.Cu")
		(net "M_B_DQ55")
	)
	(segment
		(start 131.329938 -38.0238)
		(end 113.6142 -38.0238)
		(width 0.1524)
		(layer "In9.Cu")
		(net "M_B_DQ55")
	)
	(segment
		(start 134.605268 -38.3286)
		(end 134.452868 -38.1762)
		(width 0.1524)
		(layer "In9.Cu")
		(net "M_B_DQ55")
	)
	(segment
		(start 179.909724 -15.954248)
		(end 157.535372 -38.3286)
		(width 0.1524)
		(layer "In9.Cu")
		(net "M_B_DQ55")
	)
	(segment
		(start 133.843268 -37.8968)
		(end 133.843268 -38.1762)
		(width 0.1524)
		(layer "In9.Cu")
		(net "M_B_DQ55")
	)
	(segment
		(start 133.843268 -38.1762)
		(end 133.690868 -38.3286)
		(width 0.1524)
		(layer "In9.Cu")
		(net "M_B_DQ55")
	)
	(segment
		(start 134.452868 -38.1762)
		(end 134.452868 -37.8968)
		(width 0.1524)
		(layer "In9.Cu")
		(net "M_B_DQ55")
	)
	(segment
		(start 111.2266 -37.620448)
		(end 109.471968 -37.620448)
		(width 0.1016)
		(layer "In9.Cu")
		(net "M_B_DQ55")
	)
	(segment
		(start 133.690868 -38.3286)
		(end 131.634738 -38.3286)
		(width 0.1524)
		(layer "In9.Cu")
		(net "M_B_DQ55")
	)
	(segment
		(start 108.585254 -36.9951)
		(end 108.341414 -36.79825)
		(width 0.1016)
		(layer "In9.Cu")
		(net "M_B_DQ55")
	)
	(segment
		(start 111.8362 -37.2872)
		(end 111.502952 -37.620448)
		(width 0.1524)
		(layer "In9.Cu")
		(net "M_B_DQ55")
	)
	(segment
		(start 108.341414 -36.79825)
		(end 107.913424 -36.13658)
		(width 0.1016)
		(layer "In9.Cu")
		(net "M_B_DQ55")
	)
	(segment
		(start 134.300468 -37.7444)
		(end 133.995668 -37.7444)
		(width 0.1524)
		(layer "In9.Cu")
		(net "M_B_DQ55")
	)
	(segment
		(start 133.995668 -37.7444)
		(end 133.843268 -37.8968)
		(width 0.1524)
		(layer "In9.Cu")
		(net "M_B_DQ55")
	)
	(segment
		(start 183.6928 -3.684778)
		(end 183.6928 -6.402578)
		(width 0.1524)
		(layer "In9.Cu")
		(net "M_B_DQ55")
	)
	(segment
		(start 111.502952 -37.620448)
		(end 111.2266 -37.620448)
		(width 0.1524)
		(layer "In9.Cu")
		(net "M_B_DQ55")
	)
	(segment
		(start 112.8776 -37.2872)
		(end 111.8362 -37.2872)
		(width 0.1524)
		(layer "In9.Cu")
		(net "M_B_DQ55")
	)
	(segment
		(start 183.790844 -3.57632)
		(end 183.790844 -3.586734)
		(width 0.1524)
		(layer "In9.Cu")
		(net "M_B_DQ55")
	)
	(segment
		(start 131.634738 -38.3286)
		(end 131.329938 -38.0238)
		(width 0.1524)
		(layer "In9.Cu")
		(net "M_B_DQ55")
	)
	(segment
		(start 183.790844 -3.586734)
		(end 183.6928 -3.684778)
		(width 0.1524)
		(layer "In9.Cu")
		(net "M_B_DQ55")
	)
	(segment
		(start 108.66755 -37.077396)
		(end 108.585254 -36.9951)
		(width 0.1016)
		(layer "In9.Cu")
		(net "M_B_DQ55")
	)
	(segment
		(start 182.733696 -8.059674)
		(end 182.88 -8.205978)
		(width 0.1524)
		(layer "In9.Cu")
		(net "M_B_DQ55")
	)
	(segment
		(start 182.88 -8.205978)
		(end 182.88 -9.8552)
		(width 0.1524)
		(layer "In9.Cu")
		(net "M_B_DQ55")
	)
	(segment
		(start 134.452868 -37.8968)
		(end 134.300468 -37.7444)
		(width 0.1524)
		(layer "In9.Cu")
		(net "M_B_DQ55")
	)
	(segment
		(start 179.909724 -12.825476)
		(end 179.909724 -15.954248)
		(width 0.1524)
		(layer "In9.Cu")
		(net "M_B_DQ55")
	)
	(segment
		(start 182.88 -9.8552)
		(end 179.909724 -12.825476)
		(width 0.1524)
		(layer "In9.Cu")
		(net "M_B_DQ55")
	)
	(segment
		(start 157.535372 -38.3286)
		(end 134.605268 -38.3286)
		(width 0.1524)
		(layer "In9.Cu")
		(net "M_B_DQ55")
	)
	(segment
		(start 182.733696 -7.361682)
		(end 182.733696 -8.059674)
		(width 0.1524)
		(layer "In9.Cu")
		(net "M_B_DQ55")
	)
	(segment
		(start 109.471968 -37.620448)
		(end 108.66755 -37.077396)
		(width 0.1016)
		(layer "In9.Cu")
		(net "M_B_DQ55")
	)
	(segment
		(start 45.212 -24.7142)
		(end 44.91736 -25.00884)
		(width 0.1143)
		(layer "F.Cu")
		(net "XDP_DFX_PORT4")
	)
	(segment
		(start 44.91736 -26.76144)
		(end 44.7294 -26.9494)
		(width 0.1143)
		(layer "F.Cu")
		(net "XDP_DFX_PORT4")
	)
	(segment
		(start 44.91736 -25.00884)
		(end 44.91736 -26.76144)
		(width 0.1143)
		(layer "F.Cu")
		(net "XDP_DFX_PORT4")
	)
	(segment
		(start 85.552788 -43.403774)
		(end 85.552788 -44.176696)
		(width 0.1143)
		(layer "F.Cu")
		(net "XDP_DFX_PORT4")
	)
	(segment
		(start 42.971974 -26.55697)
		(end 42.969434 -26.55443)
		(width 0.1143)
		(layer "F.Cu")
		(net "XDP_DFX_PORT4")
	)
	(segment
		(start 44.7294 -26.9494)
		(end 44.35983 -26.9494)
		(width 0.1143)
		(layer "F.Cu")
		(net "XDP_DFX_PORT4")
	)
	(segment
		(start 44.35983 -26.9494)
		(end 43.9674 -26.55697)
		(width 0.1143)
		(layer "F.Cu")
		(net "XDP_DFX_PORT4")
	)
	(segment
		(start 43.9674 -26.55697)
		(end 42.971974 -26.55697)
		(width 0.1143)
		(layer "F.Cu")
		(net "XDP_DFX_PORT4")
	)
	(segment
		(start 42.969434 -26.55443)
		(end 42.10177 -26.55443)
		(width 0.1143)
		(layer "F.Cu")
		(net "XDP_DFX_PORT4")
	)
	(segment
		(start 85.552788 -44.176696)
		(end 85.598 -44.221908)
		(width 0.1143)
		(layer "F.Cu")
		(net "XDP_DFX_PORT4")
	)
	(via
		(at 45.212 -24.7142)
		(size 0.508)
		(drill 0.254)
		(layers "F.Cu" "B.Cu")
		(net "XDP_DFX_PORT4")
	)
	(via
		(at 85.598 -44.221908)
		(size 0.4318)
		(drill 0.2032)
		(layers "F.Cu" "B.Cu")
		(net "XDP_DFX_PORT4")
	)
	(via
		(at 44.7294 -26.9494)
		(size 0.7112)
		(drill 0.3556)
		(layers "F.Cu" "B.Cu")
		(net "XDP_DFX_PORT4")
	)
	(segment
		(start 76.668122 -39.835836)
		(end 77.72146 -40.889174)
		(width 0.0889)
		(layer "In7.Cu")
		(net "XDP_DFX_PORT4")
	)
	(segment
		(start 81.715102 -43.004486)
		(end 82.197956 -43.004486)
		(width 0.0889)
		(layer "In7.Cu")
		(net "XDP_DFX_PORT4")
	)
	(segment
		(start 76.668122 -38.606984)
		(end 76.668122 -39.835836)
		(width 0.0889)
		(layer "In7.Cu")
		(net "XDP_DFX_PORT4")
	)
	(segment
		(start 84.99221 -43.687746)
		(end 85.526372 -44.221908)
		(width 0.0889)
		(layer "In7.Cu")
		(net "XDP_DFX_PORT4")
	)
	(segment
		(start 82.881216 -43.687746)
		(end 84.99221 -43.687746)
		(width 0.0889)
		(layer "In7.Cu")
		(net "XDP_DFX_PORT4")
	)
	(segment
		(start 46.1772 -28.689554)
		(end 46.482 -28.689554)
		(width 0.0889)
		(layer "In7.Cu")
		(net "XDP_DFX_PORT4")
	)
	(segment
		(start 72.609456 -34.99485)
		(end 73.055988 -34.99485)
		(width 0.0889)
		(layer "In7.Cu")
		(net "XDP_DFX_PORT4")
	)
	(segment
		(start 66.437002 -34.455354)
		(end 67.352418 -34.455354)
		(width 0.0889)
		(layer "In7.Cu")
		(net "XDP_DFX_PORT4")
	)
	(segment
		(start 45.212 -25.0444)
		(end 45.3263 -25.1587)
		(width 0.0889)
		(layer "In7.Cu")
		(net "XDP_DFX_PORT4")
	)
	(segment
		(start 73.055988 -34.99485)
		(end 76.668122 -38.606984)
		(width 0.0889)
		(layer "In7.Cu")
		(net "XDP_DFX_PORT4")
	)
	(segment
		(start 46.482 -28.689554)
		(end 46.482254 -28.6893)
		(width 0.0889)
		(layer "In7.Cu")
		(net "XDP_DFX_PORT4")
	)
	(segment
		(start 77.72146 -40.889174)
		(end 79.59979 -40.889174)
		(width 0.0889)
		(layer "In7.Cu")
		(net "XDP_DFX_PORT4")
	)
	(segment
		(start 45.3263 -25.1587)
		(end 45.3263 -27.838654)
		(width 0.0889)
		(layer "In7.Cu")
		(net "XDP_DFX_PORT4")
	)
	(segment
		(start 45.3263 -27.838654)
		(end 46.1772 -28.689554)
		(width 0.0889)
		(layer "In7.Cu")
		(net "XDP_DFX_PORT4")
	)
	(segment
		(start 82.197956 -43.004486)
		(end 82.881216 -43.687746)
		(width 0.0889)
		(layer "In7.Cu")
		(net "XDP_DFX_PORT4")
	)
	(segment
		(start 45.212 -24.7142)
		(end 45.212 -25.0444)
		(width 0.0889)
		(layer "In7.Cu")
		(net "XDP_DFX_PORT4")
	)
	(segment
		(start 79.59979 -40.889174)
		(end 81.715102 -43.004486)
		(width 0.0889)
		(layer "In7.Cu")
		(net "XDP_DFX_PORT4")
	)
	(segment
		(start 46.482254 -28.6893)
		(end 48.370998 -28.6893)
		(width 0.0889)
		(layer "In7.Cu")
		(net "XDP_DFX_PORT4")
	)
	(segment
		(start 67.352672 -34.4551)
		(end 72.069706 -34.4551)
		(width 0.0889)
		(layer "In7.Cu")
		(net "XDP_DFX_PORT4")
	)
	(segment
		(start 67.352418 -34.455354)
		(end 67.352672 -34.4551)
		(width 0.0889)
		(layer "In7.Cu")
		(net "XDP_DFX_PORT4")
	)
	(segment
		(start 72.069706 -34.4551)
		(end 72.609456 -34.99485)
		(width 0.0889)
		(layer "In7.Cu")
		(net "XDP_DFX_PORT4")
	)
	(segment
		(start 85.526372 -44.221908)
		(end 85.598 -44.221908)
		(width 0.0889)
		(layer "In7.Cu")
		(net "XDP_DFX_PORT4")
	)
	(segment
		(start 48.370998 -28.6893)
		(end 52.155598 -32.4739)
		(width 0.0889)
		(layer "In7.Cu")
		(net "XDP_DFX_PORT4")
	)
	(segment
		(start 52.155598 -32.4739)
		(end 64.455548 -32.4739)
		(width 0.0889)
		(layer "In7.Cu")
		(net "XDP_DFX_PORT4")
	)
	(segment
		(start 64.455548 -32.4739)
		(end 66.437002 -34.455354)
		(width 0.0889)
		(layer "In7.Cu")
		(net "XDP_DFX_PORT4")
	)
	(via
		(at 31.5722 -52.2224)
		(size 0.7112)
		(drill 0.3556)
		(layers "F.Cu" "B.Cu")
		(net "P1V5_STBY_BIAS")
	)
	(segment
		(start 31.719012 -52.075588)
		(end 31.719012 -50.968148)
		(width 0.3048)
		(layer "B.Cu")
		(net "P1V5_STBY_BIAS")
	)
	(segment
		(start 31.5722 -52.2224)
		(end 31.719012 -52.075588)
		(width 0.3048)
		(layer "B.Cu")
		(net "P1V5_STBY_BIAS")
	)
	(segment
		(start 31.5214 -53.1368)
		(end 32.258 -53.1368)
		(width 0.3048)
		(layer "B.Cu")
		(net "P1V5_STBY_BIAS")
	)
	(segment
		(start 31.496 -53.1622)
		(end 31.5214 -53.1368)
		(width 0.3048)
		(layer "B.Cu")
		(net "P1V5_STBY_BIAS")
	)
	(segment
		(start 31.496 -52.2986)
		(end 31.496 -53.1622)
		(width 0.3048)
		(layer "B.Cu")
		(net "P1V5_STBY_BIAS")
	)
	(segment
		(start 31.5722 -52.2224)
		(end 31.496 -52.2986)
		(width 0.3048)
		(layer "B.Cu")
		(net "P1V5_STBY_BIAS")
	)
	(segment
		(start 106.147108 -34.996374)
		(end 106.497882 -34.6456)
		(width 0.1016)
		(layer "F.Cu")
		(net "M_B_DQ49")
	)
	(segment
		(start 180.850032 -9.897364)
		(end 180.850032 -8.966962)
		(width 0.1778)
		(layer "F.Cu")
		(net "M_B_DQ49")
	)
	(segment
		(start 180.5305 -8.64743)
		(end 180.5305 -8.218678)
		(width 0.1778)
		(layer "F.Cu")
		(net "M_B_DQ49")
	)
	(segment
		(start 180.5305 -8.218678)
		(end 180.891434 -7.857744)
		(width 0.1778)
		(layer "F.Cu")
		(net "M_B_DQ49")
	)
	(segment
		(start 180.850032 -8.966962)
		(end 180.5305 -8.64743)
		(width 0.1778)
		(layer "F.Cu")
		(net "M_B_DQ49")
	)
	(segment
		(start 106.497882 -34.6456)
		(end 106.553 -34.6456)
		(width 0.1016)
		(layer "F.Cu")
		(net "M_B_DQ49")
	)
	(segment
		(start 180.891434 -7.857744)
		(end 180.916834 -7.857744)
		(width 0.1778)
		(layer "F.Cu")
		(net "M_B_DQ49")
	)
	(segment
		(start 180.916834 -7.857744)
		(end 180.9496 -7.824978)
		(width 0.1778)
		(layer "F.Cu")
		(net "M_B_DQ49")
	)
	(via
		(at 106.553 -34.6456)
		(size 0.4318)
		(drill 0.2032)
		(layers "F.Cu" "B.Cu")
		(net "M_B_DQ49")
	)
	(via
		(at 180.9496 -7.824978)
		(size 0.4318)
		(drill 0.2032)
		(layers "F.Cu" "B.Cu")
		(net "M_B_DQ49")
	)
	(segment
		(start 180.5305 -8.64743)
		(end 180.5305 -8.218678)
		(width 0.1778)
		(layer "B.Cu")
		(net "M_B_DQ49")
	)
	(segment
		(start 180.916834 -7.857744)
		(end 180.9496 -7.824978)
		(width 0.1778)
		(layer "B.Cu")
		(net "M_B_DQ49")
	)
	(segment
		(start 180.5305 -8.218678)
		(end 180.891434 -7.857744)
		(width 0.1778)
		(layer "B.Cu")
		(net "M_B_DQ49")
	)
	(segment
		(start 180.550058 -9.89076)
		(end 180.550058 -8.666988)
		(width 0.1778)
		(layer "B.Cu")
		(net "M_B_DQ49")
	)
	(segment
		(start 180.550058 -8.666988)
		(end 180.5305 -8.64743)
		(width 0.1778)
		(layer "B.Cu")
		(net "M_B_DQ49")
	)
	(segment
		(start 180.891434 -7.857744)
		(end 180.916834 -7.857744)
		(width 0.1778)
		(layer "B.Cu")
		(net "M_B_DQ49")
	)
	(segment
		(start 180.891434 -7.857744)
		(end 180.916834 -7.857744)
		(width 0.1524)
		(layer "In9.Cu")
		(net "M_B_DQ49")
	)
	(segment
		(start 144.9324 -36.2204)
		(end 145.0848 -36.068)
		(width 0.1524)
		(layer "In9.Cu")
		(net "M_B_DQ49")
	)
	(segment
		(start 137.66673 -35.91814)
		(end 137.66673 -35.4584)
		(width 0.1524)
		(layer "In9.Cu")
		(net "M_B_DQ49")
	)
	(segment
		(start 107.2388 -34.6456)
		(end 106.553 -34.6456)
		(width 0.1016)
		(layer "In9.Cu")
		(net "M_B_DQ49")
	)
	(segment
		(start 139.34313 -35.306)
		(end 139.49553 -35.4584)
		(width 0.1524)
		(layer "In9.Cu")
		(net "M_B_DQ49")
	)
	(segment
		(start 157.2768 -35.306)
		(end 158.50997 -35.306)
		(width 0.1524)
		(layer "In9.Cu")
		(net "M_B_DQ49")
	)
	(segment
		(start 107.5436 -34.9504)
		(end 107.2388 -34.6456)
		(width 0.1016)
		(layer "In9.Cu")
		(net "M_B_DQ49")
	)
	(segment
		(start 180.52288 -8.226298)
		(end 180.891434 -7.857744)
		(width 0.1524)
		(layer "In9.Cu")
		(net "M_B_DQ49")
	)
	(segment
		(start 156.5148 -35.9664)
		(end 156.6672 -36.1188)
		(width 0.1524)
		(layer "In9.Cu")
		(net "M_B_DQ49")
	)
	(segment
		(start 145.0848 -36.068)
		(end 145.0848 -35.4584)
		(width 0.1524)
		(layer "In9.Cu")
		(net "M_B_DQ49")
	)
	(segment
		(start 109.3978 -34.9504)
		(end 107.5436 -34.9504)
		(width 0.1016)
		(layer "In9.Cu")
		(net "M_B_DQ49")
	)
	(segment
		(start 178.3842 -12.15644)
		(end 180.52288 -10.01776)
		(width 0.1524)
		(layer "In9.Cu")
		(net "M_B_DQ49")
	)
	(segment
		(start 110.363762 -35.433762)
		(end 110.070392 -35.140392)
		(width 0.1016)
		(layer "In9.Cu")
		(net "M_B_DQ49")
	)
	(segment
		(start 137.05713 -35.4584)
		(end 137.05713 -35.91814)
		(width 0.1524)
		(layer "In9.Cu")
		(net "M_B_DQ49")
	)
	(segment
		(start 156.5148 -35.4584)
		(end 156.5148 -35.9664)
		(width 0.1524)
		(layer "In9.Cu")
		(net "M_B_DQ49")
	)
	(segment
		(start 156.3624 -35.306)
		(end 156.5148 -35.4584)
		(width 0.1524)
		(layer "In9.Cu")
		(net "M_B_DQ49")
	)
	(segment
		(start 138.12393 -35.306)
		(end 138.27633 -35.4584)
		(width 0.1524)
		(layer "In9.Cu")
		(net "M_B_DQ49")
	)
	(segment
		(start 137.05713 -35.91814)
		(end 137.20953 -36.07054)
		(width 0.1524)
		(layer "In9.Cu")
		(net "M_B_DQ49")
	)
	(segment
		(start 140.10513 -35.4584)
		(end 140.25753 -35.306)
		(width 0.1524)
		(layer "In9.Cu")
		(net "M_B_DQ49")
	)
	(segment
		(start 114.247676 -36.322)
		(end 130.7084 -36.322)
		(width 0.1524)
		(layer "In9.Cu")
		(net "M_B_DQ49")
	)
	(segment
		(start 140.25753 -35.306)
		(end 140.589 -35.306)
		(width 0.1524)
		(layer "In9.Cu")
		(net "M_B_DQ49")
	)
	(segment
		(start 158.50997 -35.306)
		(end 178.3842 -15.43177)
		(width 0.1524)
		(layer "In9.Cu")
		(net "M_B_DQ49")
	)
	(segment
		(start 144.3228 -35.306)
		(end 144.4752 -35.4584)
		(width 0.1524)
		(layer "In9.Cu")
		(net "M_B_DQ49")
	)
	(segment
		(start 138.88593 -35.91814)
		(end 138.88593 -35.4584)
		(width 0.1524)
		(layer "In9.Cu")
		(net "M_B_DQ49")
	)
	(segment
		(start 137.66673 -35.4584)
		(end 137.81913 -35.306)
		(width 0.1524)
		(layer "In9.Cu")
		(net "M_B_DQ49")
	)
	(segment
		(start 139.49553 -35.4584)
		(end 139.49553 -35.9918)
		(width 0.1524)
		(layer "In9.Cu")
		(net "M_B_DQ49")
	)
	(segment
		(start 137.81913 -35.306)
		(end 138.12393 -35.306)
		(width 0.1524)
		(layer "In9.Cu")
		(net "M_B_DQ49")
	)
	(segment
		(start 140.10513 -35.9918)
		(end 140.10513 -35.4584)
		(width 0.1524)
		(layer "In9.Cu")
		(net "M_B_DQ49")
	)
	(segment
		(start 140.9954 -35.941)
		(end 141.450314 -35.941)
		(width 0.1524)
		(layer "In9.Cu")
		(net "M_B_DQ49")
	)
	(segment
		(start 140.843 -35.56)
		(end 140.843 -35.7886)
		(width 0.1524)
		(layer "In9.Cu")
		(net "M_B_DQ49")
	)
	(segment
		(start 139.03833 -35.306)
		(end 139.34313 -35.306)
		(width 0.1524)
		(layer "In9.Cu")
		(net "M_B_DQ49")
	)
	(segment
		(start 157.1244 -35.4584)
		(end 157.2768 -35.306)
		(width 0.1524)
		(layer "In9.Cu")
		(net "M_B_DQ49")
	)
	(segment
		(start 144.4752 -36.068)
		(end 144.6276 -36.2204)
		(width 0.1524)
		(layer "In9.Cu")
		(net "M_B_DQ49")
	)
	(segment
		(start 138.42873 -36.07054)
		(end 138.73353 -36.07054)
		(width 0.1524)
		(layer "In9.Cu")
		(net "M_B_DQ49")
	)
	(segment
		(start 180.916834 -7.857744)
		(end 180.9496 -7.824978)
		(width 0.1524)
		(layer "In9.Cu")
		(net "M_B_DQ49")
	)
	(segment
		(start 141.450314 -35.941)
		(end 142.085314 -35.306)
		(width 0.1524)
		(layer "In9.Cu")
		(net "M_B_DQ49")
	)
	(segment
		(start 156.972 -36.1188)
		(end 157.1244 -35.9664)
		(width 0.1524)
		(layer "In9.Cu")
		(net "M_B_DQ49")
	)
	(segment
		(start 109.587792 -35.140392)
		(end 109.3978 -34.9504)
		(width 0.1016)
		(layer "In9.Cu")
		(net "M_B_DQ49")
	)
	(segment
		(start 111.024162 -35.433762)
		(end 110.363762 -35.433762)
		(width 0.1016)
		(layer "In9.Cu")
		(net "M_B_DQ49")
	)
	(segment
		(start 136.90473 -35.306)
		(end 137.05713 -35.4584)
		(width 0.1524)
		(layer "In9.Cu")
		(net "M_B_DQ49")
	)
	(segment
		(start 144.6276 -36.2204)
		(end 144.9324 -36.2204)
		(width 0.1524)
		(layer "In9.Cu")
		(net "M_B_DQ49")
	)
	(segment
		(start 138.27633 -35.4584)
		(end 138.27633 -35.91814)
		(width 0.1524)
		(layer "In9.Cu")
		(net "M_B_DQ49")
	)
	(segment
		(start 178.3842 -15.43177)
		(end 178.3842 -12.15644)
		(width 0.1524)
		(layer "In9.Cu")
		(net "M_B_DQ49")
	)
	(segment
		(start 139.95273 -36.1442)
		(end 140.10513 -35.9918)
		(width 0.1524)
		(layer "In9.Cu")
		(net "M_B_DQ49")
	)
	(segment
		(start 145.0848 -35.4584)
		(end 145.2372 -35.306)
		(width 0.1524)
		(layer "In9.Cu")
		(net "M_B_DQ49")
	)
	(segment
		(start 156.6672 -36.1188)
		(end 156.972 -36.1188)
		(width 0.1524)
		(layer "In9.Cu")
		(net "M_B_DQ49")
	)
	(segment
		(start 144.4752 -35.4584)
		(end 144.4752 -36.068)
		(width 0.1524)
		(layer "In9.Cu")
		(net "M_B_DQ49")
	)
	(segment
		(start 130.7084 -36.322)
		(end 131.7244 -35.306)
		(width 0.1524)
		(layer "In9.Cu")
		(net "M_B_DQ49")
	)
	(segment
		(start 138.27633 -35.91814)
		(end 138.42873 -36.07054)
		(width 0.1524)
		(layer "In9.Cu")
		(net "M_B_DQ49")
	)
	(segment
		(start 137.20953 -36.07054)
		(end 137.51433 -36.07054)
		(width 0.1524)
		(layer "In9.Cu")
		(net "M_B_DQ49")
	)
	(segment
		(start 180.52288 -10.01776)
		(end 180.52288 -8.226298)
		(width 0.1524)
		(layer "In9.Cu")
		(net "M_B_DQ49")
	)
	(segment
		(start 157.1244 -35.9664)
		(end 157.1244 -35.4584)
		(width 0.1524)
		(layer "In9.Cu")
		(net "M_B_DQ49")
	)
	(segment
		(start 111.024162 -35.433762)
		(end 113.359438 -35.433762)
		(width 0.1524)
		(layer "In9.Cu")
		(net "M_B_DQ49")
	)
	(segment
		(start 139.64793 -36.1442)
		(end 139.95273 -36.1442)
		(width 0.1524)
		(layer "In9.Cu")
		(net "M_B_DQ49")
	)
	(segment
		(start 140.589 -35.306)
		(end 140.843 -35.56)
		(width 0.1524)
		(layer "In9.Cu")
		(net "M_B_DQ49")
	)
	(segment
		(start 113.359438 -35.433762)
		(end 114.247676 -36.322)
		(width 0.1524)
		(layer "In9.Cu")
		(net "M_B_DQ49")
	)
	(segment
		(start 138.73353 -36.07054)
		(end 138.88593 -35.91814)
		(width 0.1524)
		(layer "In9.Cu")
		(net "M_B_DQ49")
	)
	(segment
		(start 142.085314 -35.306)
		(end 144.3228 -35.306)
		(width 0.1524)
		(layer "In9.Cu")
		(net "M_B_DQ49")
	)
	(segment
		(start 131.7244 -35.306)
		(end 136.90473 -35.306)
		(width 0.1524)
		(layer "In9.Cu")
		(net "M_B_DQ49")
	)
	(segment
		(start 139.49553 -35.9918)
		(end 139.64793 -36.1442)
		(width 0.1524)
		(layer "In9.Cu")
		(net "M_B_DQ49")
	)
	(segment
		(start 145.2372 -35.306)
		(end 156.3624 -35.306)
		(width 0.1524)
		(layer "In9.Cu")
		(net "M_B_DQ49")
	)
	(segment
		(start 140.843 -35.7886)
		(end 140.9954 -35.941)
		(width 0.1524)
		(layer "In9.Cu")
		(net "M_B_DQ49")
	)
	(segment
		(start 110.070392 -35.140392)
		(end 109.587792 -35.140392)
		(width 0.1016)
		(layer "In9.Cu")
		(net "M_B_DQ49")
	)
	(segment
		(start 138.88593 -35.4584)
		(end 139.03833 -35.306)
		(width 0.1524)
		(layer "In9.Cu")
		(net "M_B_DQ49")
	)
	(segment
		(start 137.51433 -36.07054)
		(end 137.66673 -35.91814)
		(width 0.1524)
		(layer "In9.Cu")
		(net "M_B_DQ49")
	)
	(segment
		(start 81.308448 -43.599354)
		(end 80.93583 -43.599354)
		(width 0.1143)
		(layer "F.Cu")
		(net "BD_ID_0")
	)
	(segment
		(start 80.290162 -43.339004)
		(end 80.262222 -43.366944)
		(width 0.1143)
		(layer "F.Cu")
		(net "BD_ID_0")
	)
	(segment
		(start 76.42225 -44.009056)
		(end 76.42225 -45.811186)
		(width 0.1143)
		(layer "F.Cu")
		(net "BD_ID_0")
	)
	(segment
		(start 75.438 -48.768)
		(end 75.3618 -48.8442)
		(width 0.1143)
		(layer "F.Cu")
		(net "BD_ID_0")
	)
	(segment
		(start 76.2 -46.033436)
		(end 76.2 -47.117)
		(width 0.1143)
		(layer "F.Cu")
		(net "BD_ID_0")
	)
	(segment
		(start 76.2 -47.117)
		(end 75.9206 -47.3964)
		(width 0.1143)
		(layer "F.Cu")
		(net "BD_ID_0")
	)
	(segment
		(start 80.262222 -43.366944)
		(end 79.817976 -43.366944)
		(width 0.1143)
		(layer "F.Cu")
		(net "BD_ID_0")
	)
	(segment
		(start 76.42225 -45.811186)
		(end 76.2 -46.033436)
		(width 0.1143)
		(layer "F.Cu")
		(net "BD_ID_0")
	)
	(segment
		(start 80.93583 -43.599354)
		(end 80.67548 -43.339004)
		(width 0.1143)
		(layer "F.Cu")
		(net "BD_ID_0")
	)
	(segment
		(start 79.69631 -43.245278)
		(end 77.186028 -43.245278)
		(width 0.1143)
		(layer "F.Cu")
		(net "BD_ID_0")
	)
	(segment
		(start 75.9206 -48.2854)
		(end 75.438 -48.768)
		(width 0.1143)
		(layer "F.Cu")
		(net "BD_ID_0")
	)
	(segment
		(start 79.817976 -43.366944)
		(end 79.69631 -43.245278)
		(width 0.1143)
		(layer "F.Cu")
		(net "BD_ID_0")
	)
	(segment
		(start 77.186028 -43.245278)
		(end 76.42225 -44.009056)
		(width 0.1143)
		(layer "F.Cu")
		(net "BD_ID_0")
	)
	(segment
		(start 80.67548 -43.339004)
		(end 80.290162 -43.339004)
		(width 0.1143)
		(layer "F.Cu")
		(net "BD_ID_0")
	)
	(segment
		(start 75.3618 -48.8442)
		(end 74.422 -48.8442)
		(width 0.1143)
		(layer "F.Cu")
		(net "BD_ID_0")
	)
	(segment
		(start 74.422 -48.8442)
		(end 73.66 -48.8442)
		(width 0.1143)
		(layer "F.Cu")
		(net "BD_ID_0")
	)
	(segment
		(start 75.9206 -47.3964)
		(end 75.9206 -48.2854)
		(width 0.1143)
		(layer "F.Cu")
		(net "BD_ID_0")
	)
	(via
		(at 75.438 -48.768)
		(size 0.7112)
		(drill 0.3556)
		(layers "F.Cu" "B.Cu")
		(net "BD_ID_0")
	)
	(segment
		(start 56.8452 -15.6718)
		(end 56.7182 -15.5448)
		(width 0.1143)
		(layer "F.Cu")
		(net "GBE_SMBCLK")
	)
	(segment
		(start 56.2864 -13.9954)
		(end 56.2864 -13.335)
		(width 0.1143)
		(layer "F.Cu")
		(net "GBE_SMBCLK")
	)
	(segment
		(start 56.7182 -14.4272)
		(end 56.2864 -13.9954)
		(width 0.1143)
		(layer "F.Cu")
		(net "GBE_SMBCLK")
	)
	(segment
		(start 87.673688 -32.664654)
		(end 87.191596 -32.664654)
		(width 0.1143)
		(layer "F.Cu")
		(net "GBE_SMBCLK")
	)
	(segment
		(start 56.6801 -12.9413)
		(end 57.43956 -12.9413)
		(width 0.1143)
		(layer "F.Cu")
		(net "GBE_SMBCLK")
	)
	(segment
		(start 56.2864 -13.335)
		(end 56.6801 -12.9413)
		(width 0.1143)
		(layer "F.Cu")
		(net "GBE_SMBCLK")
	)
	(segment
		(start 56.7182 -15.5448)
		(end 56.7182 -14.4272)
		(width 0.1143)
		(layer "F.Cu")
		(net "GBE_SMBCLK")
	)
	(segment
		(start 87.191596 -32.664654)
		(end 87.159084 -32.632142)
		(width 0.1143)
		(layer "F.Cu")
		(net "GBE_SMBCLK")
	)
	(via
		(at 76.5302 -24.638)
		(size 0.508)
		(drill 0.254)
		(layers "F.Cu" "B.Cu")
		(net "GBE_SMBCLK")
	)
	(via
		(at 87.159084 -32.632142)
		(size 0.4318)
		(drill 0.2032)
		(layers "F.Cu" "B.Cu")
		(net "GBE_SMBCLK")
	)
	(via
		(at 77.392276 -25.896824)
		(size 0.7112)
		(drill 0.3556)
		(layers "F.Cu" "B.Cu")
		(net "GBE_SMBCLK")
	)
	(via
		(at 56.8452 -15.6718)
		(size 0.508)
		(drill 0.254)
		(layers "F.Cu" "B.Cu")
		(net "GBE_SMBCLK")
	)
	(segment
		(start 80.4926 -27.994356)
		(end 79.987394 -27.48915)
		(width 0.1143)
		(layer "B.Cu")
		(net "GBE_SMBCLK")
	)
	(segment
		(start 77.234796 -24.60625)
		(end 76.56195 -24.60625)
		(width 0.1143)
		(layer "B.Cu")
		(net "GBE_SMBCLK")
	)
	(segment
		(start 79.987394 -27.48915)
		(end 78.526132 -27.48915)
		(width 0.1143)
		(layer "B.Cu")
		(net "GBE_SMBCLK")
	)
	(segment
		(start 83.826604 -30.085792)
		(end 82.288888 -30.085792)
		(width 0.1143)
		(layer "B.Cu")
		(net "GBE_SMBCLK")
	)
	(segment
		(start 86.233 -31.738824)
		(end 86.233 -31.605982)
		(width 0.1143)
		(layer "B.Cu")
		(net "GBE_SMBCLK")
	)
	(segment
		(start 87.159084 -32.632142)
		(end 87.126318 -32.632142)
		(width 0.1143)
		(layer "B.Cu")
		(net "GBE_SMBCLK")
	)
	(segment
		(start 77.392276 -26.355294)
		(end 77.392276 -25.896824)
		(width 0.1143)
		(layer "B.Cu")
		(net "GBE_SMBCLK")
	)
	(segment
		(start 78.526132 -27.48915)
		(end 77.392276 -26.355294)
		(width 0.1143)
		(layer "B.Cu")
		(net "GBE_SMBCLK")
	)
	(segment
		(start 75.29195 -24.60625)
		(end 75.1078 -24.7904)
		(width 0.1143)
		(layer "B.Cu")
		(net "GBE_SMBCLK")
	)
	(segment
		(start 81.485232 -29.742892)
		(end 80.4926 -28.75026)
		(width 0.1143)
		(layer "B.Cu")
		(net "GBE_SMBCLK")
	)
	(segment
		(start 77.5208 -24.892254)
		(end 77.234796 -24.60625)
		(width 0.1143)
		(layer "B.Cu")
		(net "GBE_SMBCLK")
	)
	(segment
		(start 87.126318 -32.632142)
		(end 86.233 -31.738824)
		(width 0.1143)
		(layer "B.Cu")
		(net "GBE_SMBCLK")
	)
	(segment
		(start 76.49845 -24.60625)
		(end 75.29195 -24.60625)
		(width 0.1143)
		(layer "B.Cu")
		(net "GBE_SMBCLK")
	)
	(segment
		(start 77.5208 -25.7302)
		(end 77.5208 -24.892254)
		(width 0.1143)
		(layer "B.Cu")
		(net "GBE_SMBCLK")
	)
	(segment
		(start 84.04606 -30.305248)
		(end 83.826604 -30.085792)
		(width 0.1143)
		(layer "B.Cu")
		(net "GBE_SMBCLK")
	)
	(segment
		(start 76.5302 -24.638)
		(end 76.49845 -24.60625)
		(width 0.1143)
		(layer "B.Cu")
		(net "GBE_SMBCLK")
	)
	(segment
		(start 81.945988 -29.742892)
		(end 81.485232 -29.742892)
		(width 0.1143)
		(layer "B.Cu")
		(net "GBE_SMBCLK")
	)
	(segment
		(start 86.233 -31.605982)
		(end 85.964268 -31.33725)
		(width 0.1143)
		(layer "B.Cu")
		(net "GBE_SMBCLK")
	)
	(segment
		(start 76.56195 -24.60625)
		(end 76.5302 -24.638)
		(width 0.1143)
		(layer "B.Cu")
		(net "GBE_SMBCLK")
	)
	(segment
		(start 77.392276 -25.896824)
		(end 77.392276 -25.858724)
		(width 0.1143)
		(layer "B.Cu")
		(net "GBE_SMBCLK")
	)
	(segment
		(start 84.04606 -30.771846)
		(end 84.04606 -30.305248)
		(width 0.1143)
		(layer "B.Cu")
		(net "GBE_SMBCLK")
	)
	(segment
		(start 77.392276 -25.858724)
		(end 77.5208 -25.7302)
		(width 0.1143)
		(layer "B.Cu")
		(net "GBE_SMBCLK")
	)
	(segment
		(start 82.288888 -30.085792)
		(end 81.945988 -29.742892)
		(width 0.1143)
		(layer "B.Cu")
		(net "GBE_SMBCLK")
	)
	(segment
		(start 80.4926 -28.75026)
		(end 80.4926 -27.994356)
		(width 0.1143)
		(layer "B.Cu")
		(net "GBE_SMBCLK")
	)
	(segment
		(start 84.611464 -31.33725)
		(end 84.04606 -30.771846)
		(width 0.1143)
		(layer "B.Cu")
		(net "GBE_SMBCLK")
	)
	(segment
		(start 85.964268 -31.33725)
		(end 84.611464 -31.33725)
		(width 0.1143)
		(layer "B.Cu")
		(net "GBE_SMBCLK")
	)
	(segment
		(start 69.6722 -20.542504)
		(end 68.274946 -19.14525)
		(width 0.0889)
		(layer "In7.Cu")
		(net "GBE_SMBCLK")
	)
	(segment
		(start 68.274946 -19.14525)
		(end 65.631568 -19.14525)
		(width 0.0889)
		(layer "In7.Cu")
		(net "GBE_SMBCLK")
	)
	(segment
		(start 57.277 -15.6718)
		(end 56.8452 -15.6718)
		(width 0.0889)
		(layer "In7.Cu")
		(net "GBE_SMBCLK")
	)
	(segment
		(start 61.722 -15.03045)
		(end 61.20765 -14.5161)
		(width 0.0889)
		(layer "In7.Cu")
		(net "GBE_SMBCLK")
	)
	(segment
		(start 76.5302 -24.638)
		(end 76.423774 -24.531574)
		(width 0.0889)
		(layer "In7.Cu")
		(net "GBE_SMBCLK")
	)
	(segment
		(start 61.20765 -14.5161)
		(end 58.4327 -14.5161)
		(width 0.0889)
		(layer "In7.Cu")
		(net "GBE_SMBCLK")
	)
	(segment
		(start 74.2315 -24.214582)
		(end 74.2315 -23.458424)
		(width 0.0889)
		(layer "In7.Cu")
		(net "GBE_SMBCLK")
	)
	(segment
		(start 74.2315 -23.458424)
		(end 71.31558 -20.542504)
		(width 0.0889)
		(layer "In7.Cu")
		(net "GBE_SMBCLK")
	)
	(segment
		(start 76.423774 -24.531574)
		(end 74.548492 -24.531574)
		(width 0.0889)
		(layer "In7.Cu")
		(net "GBE_SMBCLK")
	)
	(segment
		(start 58.4327 -14.5161)
		(end 57.277 -15.6718)
		(width 0.0889)
		(layer "In7.Cu")
		(net "GBE_SMBCLK")
	)
	(segment
		(start 61.722 -15.235682)
		(end 61.722 -15.03045)
		(width 0.0889)
		(layer "In7.Cu")
		(net "GBE_SMBCLK")
	)
	(segment
		(start 71.31558 -20.542504)
		(end 69.6722 -20.542504)
		(width 0.0889)
		(layer "In7.Cu")
		(net "GBE_SMBCLK")
	)
	(segment
		(start 65.631568 -19.14525)
		(end 61.722 -15.235682)
		(width 0.0889)
		(layer "In7.Cu")
		(net "GBE_SMBCLK")
	)
	(segment
		(start 74.548492 -24.531574)
		(end 74.2315 -24.214582)
		(width 0.0889)
		(layer "In7.Cu")
		(net "GBE_SMBCLK")
	)
	(segment
		(start 40.961818 -33.55467)
		(end 40.12565 -34.390838)
		(width 0.127)
		(layer "F.Cu")
		(net "TP_XDP0_TCK1")
	)
	(segment
		(start 40.12565 -34.390838)
		(end 40.12565 -37.066982)
		(width 0.127)
		(layer "F.Cu")
		(net "TP_XDP0_TCK1")
	)
	(segment
		(start 39.2303 -37.962332)
		(end 39.2303 -39.9034)
		(width 0.127)
		(layer "F.Cu")
		(net "TP_XDP0_TCK1")
	)
	(segment
		(start 40.12565 -37.066982)
		(end 39.2303 -37.962332)
		(width 0.127)
		(layer "F.Cu")
		(net "TP_XDP0_TCK1")
	)
	(segment
		(start 42.10177 -33.55467)
		(end 40.961818 -33.55467)
		(width 0.127)
		(layer "F.Cu")
		(net "TP_XDP0_TCK1")
	)
	(segment
		(start 39.2303 -39.9034)
		(end 39.64178 -40.31488)
		(width 0.127)
		(layer "F.Cu")
		(net "TP_XDP0_TCK1")
	)
	(segment
		(start 79.912972 -32.521906)
		(end 79.57566 -32.18434)
		(width 0.1397)
		(layer "F.Cu")
		(net "SATA3_TX_DN1")
	)
	(segment
		(start 10.2108 -51.7398)
		(end 9.5504 -51.7398)
		(width 0.1397)
		(layer "F.Cu")
		(net "SATA3_TX_DN1")
	)
	(segment
		(start 80.208628 -32.804354)
		(end 79.92618 -32.521906)
		(width 0.1397)
		(layer "F.Cu")
		(net "SATA3_TX_DN1")
	)
	(segment
		(start 79.57566 -32.18434)
		(end 78.6638 -31.27248)
		(width 0.1397)
		(layer "F.Cu")
		(net "SATA3_TX_DN1")
	)
	(segment
		(start 78.6638 -31.27248)
		(end 78.6638 -31.190184)
		(width 0.1397)
		(layer "F.Cu")
		(net "SATA3_TX_DN1")
	)
	(segment
		(start 79.92618 -32.521906)
		(end 79.912972 -32.521906)
		(width 0.1397)
		(layer "F.Cu")
		(net "SATA3_TX_DN1")
	)
	(via
		(at 78.6638 -31.190184)
		(size 0.4318)
		(drill 0.2032)
		(layers "F.Cu" "B.Cu")
		(net "SATA3_TX_DN1")
	)
	(via
		(at 9.5504 -51.7398)
		(size 0.508)
		(drill 0.254)
		(layers "F.Cu" "B.Cu")
		(net "SATA3_TX_DN1")
	)
	(segment
		(start 77.089 -31.720028)
		(end 77.1144 -31.720028)
		(width 0.1016)
		(layer "In4.Cu")
		(net "SATA3_TX_DN1")
	)
	(segment
		(start 16.49095 -51.15941)
		(end 16.83385 -51.15941)
		(width 0.1143)
		(layer "In4.Cu")
		(net "SATA3_TX_DN1")
	)
	(segment
		(start 54.366922 -43.877484)
		(end 66.524378 -31.720028)
		(width 0.1143)
		(layer "In4.Cu")
		(net "SATA3_TX_DN1")
	)
	(segment
		(start 23.15718 -49.74336)
		(end 23.50008 -49.74336)
		(width 0.1143)
		(layer "In4.Cu")
		(net "SATA3_TX_DN1")
	)
	(segment
		(start 77.572108 -31.784036)
		(end 78.274164 -31.784036)
		(width 0.1016)
		(layer "In4.Cu")
		(net "SATA3_TX_DN1")
	)
	(segment
		(start 18.15973 -50.94605)
		(end 19.61515 -50.94605)
		(width 0.1143)
		(layer "In4.Cu")
		(net "SATA3_TX_DN1")
	)
	(segment
		(start 22.04466 -49.74336)
		(end 22.38756 -49.74336)
		(width 0.1143)
		(layer "In4.Cu")
		(net "SATA3_TX_DN1")
	)
	(segment
		(start 52.789328 -44.388786)
		(end 53.30063 -43.877484)
		(width 0.1143)
		(layer "In4.Cu")
		(net "SATA3_TX_DN1")
	)
	(segment
		(start 77.1144 -31.720028)
		(end 77.1779 -31.656528)
		(width 0.1016)
		(layer "In4.Cu")
		(net "SATA3_TX_DN1")
	)
	(segment
		(start 53.30063 -43.877484)
		(end 54.366922 -43.877484)
		(width 0.1143)
		(layer "In4.Cu")
		(net "SATA3_TX_DN1")
	)
	(segment
		(start 22.38756 -49.74336)
		(end 22.60092 -49.53)
		(width 0.1143)
		(layer "In4.Cu")
		(net "SATA3_TX_DN1")
	)
	(segment
		(start 35.893756 -48.41875)
		(end 48.10125 -48.41875)
		(width 0.1143)
		(layer "In4.Cu")
		(net "SATA3_TX_DN1")
	)
	(segment
		(start 78.274164 -31.784036)
		(end 78.507336 -31.550864)
		(width 0.1016)
		(layer "In4.Cu")
		(net "SATA3_TX_DN1")
	)
	(segment
		(start 78.507336 -31.346648)
		(end 78.6638 -31.190184)
		(width 0.1016)
		(layer "In4.Cu")
		(net "SATA3_TX_DN1")
	)
	(segment
		(start 51.216052 -46.263814)
		(end 51.216052 -45.962062)
		(width 0.1143)
		(layer "In4.Cu")
		(net "SATA3_TX_DN1")
	)
	(segment
		(start 77.4446 -31.656528)
		(end 77.572108 -31.784036)
		(width 0.1016)
		(layer "In4.Cu")
		(net "SATA3_TX_DN1")
	)
	(segment
		(start 52.789328 -44.690538)
		(end 52.789328 -44.388786)
		(width 0.1143)
		(layer "In4.Cu")
		(net "SATA3_TX_DN1")
	)
	(segment
		(start 50.671984 -46.50613)
		(end 50.973736 -46.50613)
		(width 0.1143)
		(layer "In4.Cu")
		(net "SATA3_TX_DN1")
	)
	(segment
		(start 15.713456 -50.94605)
		(end 16.27759 -50.94605)
		(width 0.1143)
		(layer "In4.Cu")
		(net "SATA3_TX_DN1")
	)
	(segment
		(start 49.7713 -46.7487)
		(end 50.429414 -46.7487)
		(width 0.1143)
		(layer "In4.Cu")
		(net "SATA3_TX_DN1")
	)
	(segment
		(start 51.760374 -45.719492)
		(end 52.00269 -45.477176)
		(width 0.1143)
		(layer "In4.Cu")
		(net "SATA3_TX_DN1")
	)
	(segment
		(start 15.376906 -51.2826)
		(end 15.713456 -50.94605)
		(width 0.1143)
		(layer "In4.Cu")
		(net "SATA3_TX_DN1")
	)
	(segment
		(start 21.8313 -49.53)
		(end 22.04466 -49.74336)
		(width 0.1143)
		(layer "In4.Cu")
		(net "SATA3_TX_DN1")
	)
	(segment
		(start 34.3916 -48.9712)
		(end 35.341306 -48.9712)
		(width 0.1143)
		(layer "In4.Cu")
		(net "SATA3_TX_DN1")
	)
	(segment
		(start 35.341306 -48.9712)
		(end 35.893756 -48.41875)
		(width 0.1143)
		(layer "In4.Cu")
		(net "SATA3_TX_DN1")
	)
	(segment
		(start 19.61515 -50.94605)
		(end 21.0312 -49.53)
		(width 0.1143)
		(layer "In4.Cu")
		(net "SATA3_TX_DN1")
	)
	(segment
		(start 52.00269 -45.175424)
		(end 52.24526 -44.932854)
		(width 0.1143)
		(layer "In4.Cu")
		(net "SATA3_TX_DN1")
	)
	(segment
		(start 16.27759 -50.94605)
		(end 16.49095 -51.15941)
		(width 0.1143)
		(layer "In4.Cu")
		(net "SATA3_TX_DN1")
	)
	(segment
		(start 33.2486 -47.8282)
		(end 34.3916 -48.9712)
		(width 0.1143)
		(layer "In4.Cu")
		(net "SATA3_TX_DN1")
	)
	(segment
		(start 66.524378 -31.720028)
		(end 77.089 -31.720028)
		(width 0.1143)
		(layer "In4.Cu")
		(net "SATA3_TX_DN1")
	)
	(segment
		(start 52.24526 -44.932854)
		(end 52.547012 -44.932854)
		(width 0.1143)
		(layer "In4.Cu")
		(net "SATA3_TX_DN1")
	)
	(segment
		(start 77.1779 -31.656528)
		(end 77.4446 -31.656528)
		(width 0.1016)
		(layer "In4.Cu")
		(net "SATA3_TX_DN1")
	)
	(segment
		(start 51.216052 -45.962062)
		(end 51.458622 -45.719492)
		(width 0.1143)
		(layer "In4.Cu")
		(net "SATA3_TX_DN1")
	)
	(segment
		(start 9.6647 -51.2826)
		(end 15.376906 -51.2826)
		(width 0.1143)
		(layer "In4.Cu")
		(net "SATA3_TX_DN1")
	)
	(segment
		(start 23.50008 -49.74336)
		(end 23.71344 -49.53)
		(width 0.1143)
		(layer "In4.Cu")
		(net "SATA3_TX_DN1")
	)
	(segment
		(start 17.39011 -50.94605)
		(end 17.60347 -51.15941)
		(width 0.1143)
		(layer "In4.Cu")
		(net "SATA3_TX_DN1")
	)
	(segment
		(start 48.10125 -48.41875)
		(end 49.7713 -46.7487)
		(width 0.1143)
		(layer "In4.Cu")
		(net "SATA3_TX_DN1")
	)
	(segment
		(start 50.429414 -46.7487)
		(end 50.671984 -46.50613)
		(width 0.1143)
		(layer "In4.Cu")
		(net "SATA3_TX_DN1")
	)
	(segment
		(start 17.04721 -50.94605)
		(end 17.39011 -50.94605)
		(width 0.1143)
		(layer "In4.Cu")
		(net "SATA3_TX_DN1")
	)
	(segment
		(start 26.806906 -47.8282)
		(end 33.2486 -47.8282)
		(width 0.1143)
		(layer "In4.Cu")
		(net "SATA3_TX_DN1")
	)
	(segment
		(start 17.60347 -51.15941)
		(end 17.94637 -51.15941)
		(width 0.1143)
		(layer "In4.Cu")
		(net "SATA3_TX_DN1")
	)
	(segment
		(start 52.00269 -45.477176)
		(end 52.00269 -45.175424)
		(width 0.1143)
		(layer "In4.Cu")
		(net "SATA3_TX_DN1")
	)
	(segment
		(start 9.5504 -51.3969)
		(end 9.6647 -51.2826)
		(width 0.1143)
		(layer "In4.Cu")
		(net "SATA3_TX_DN1")
	)
	(segment
		(start 16.83385 -51.15941)
		(end 17.04721 -50.94605)
		(width 0.1143)
		(layer "In4.Cu")
		(net "SATA3_TX_DN1")
	)
	(segment
		(start 78.507336 -31.550864)
		(end 78.507336 -31.346648)
		(width 0.1016)
		(layer "In4.Cu")
		(net "SATA3_TX_DN1")
	)
	(segment
		(start 23.71344 -49.53)
		(end 25.105106 -49.53)
		(width 0.1143)
		(layer "In4.Cu")
		(net "SATA3_TX_DN1")
	)
	(segment
		(start 21.0312 -49.53)
		(end 21.8313 -49.53)
		(width 0.1143)
		(layer "In4.Cu")
		(net "SATA3_TX_DN1")
	)
	(segment
		(start 17.94637 -51.15941)
		(end 18.15973 -50.94605)
		(width 0.1143)
		(layer "In4.Cu")
		(net "SATA3_TX_DN1")
	)
	(segment
		(start 25.105106 -49.53)
		(end 26.806906 -47.8282)
		(width 0.1143)
		(layer "In4.Cu")
		(net "SATA3_TX_DN1")
	)
	(segment
		(start 50.973736 -46.50613)
		(end 51.216052 -46.263814)
		(width 0.1143)
		(layer "In4.Cu")
		(net "SATA3_TX_DN1")
	)
	(segment
		(start 22.94382 -49.53)
		(end 23.15718 -49.74336)
		(width 0.1143)
		(layer "In4.Cu")
		(net "SATA3_TX_DN1")
	)
	(segment
		(start 9.5504 -51.7398)
		(end 9.5504 -51.3969)
		(width 0.1143)
		(layer "In4.Cu")
		(net "SATA3_TX_DN1")
	)
	(segment
		(start 22.60092 -49.53)
		(end 22.94382 -49.53)
		(width 0.1143)
		(layer "In4.Cu")
		(net "SATA3_TX_DN1")
	)
	(segment
		(start 51.458622 -45.719492)
		(end 51.760374 -45.719492)
		(width 0.1143)
		(layer "In4.Cu")
		(net "SATA3_TX_DN1")
	)
	(segment
		(start 52.547012 -44.932854)
		(end 52.789328 -44.690538)
		(width 0.1143)
		(layer "In4.Cu")
		(net "SATA3_TX_DN1")
	)
	(via
		(at 28.829 -45.085)
		(size 0.7112)
		(drill 0.3556)
		(layers "F.Cu" "B.Cu")
		(net "P1V5_STBY_OUT")
	)
	(segment
		(start 190.8048 -30.58668)
		(end 190.8048 -30.0482)
		(width 0.2032)
		(layer "F.Cu")
		(net "VR_PVDDRA_ISUMP1")
	)
	(segment
		(start 190.656464 -30.735016)
		(end 190.8048 -30.58668)
		(width 0.2032)
		(layer "F.Cu")
		(net "VR_PVDDRA_ISUMP1")
	)
	(segment
		(start 190.656464 -31.575502)
		(end 190.656464 -30.735016)
		(width 0.2032)
		(layer "F.Cu")
		(net "VR_PVDDRA_ISUMP1")
	)
	(segment
		(start 190.8048 -30.0482)
		(end 190.8302 -30.0228)
		(width 0.2032)
		(layer "F.Cu")
		(net "VR_PVDDRA_ISUMP1")
	)
	(via
		(at 189.26556 -30.60192)
		(size 0.7112)
		(drill 0.3556)
		(layers "F.Cu" "B.Cu")
		(net "VR_PVDDRA_ISUMP1")
	)
	(via
		(at 190.8302 -30.0228)
		(size 0.508)
		(drill 0.254)
		(layers "F.Cu" "B.Cu")
		(net "VR_PVDDRA_ISUMP1")
	)
	(segment
		(start 189.2554 -30.066234)
		(end 189.2554 -30.59176)
		(width 0.2032)
		(layer "B.Cu")
		(net "VR_PVDDRA_ISUMP1")
	)
	(segment
		(start 185.2676 -26.797)
		(end 186.1312 -26.797)
		(width 0.2032)
		(layer "B.Cu")
		(net "VR_PVDDRA_ISUMP1")
	)
	(segment
		(start 189.26556 -30.60192)
		(end 189.85484 -31.1912)
		(width 0.2032)
		(layer "B.Cu")
		(net "VR_PVDDRA_ISUMP1")
	)
	(segment
		(start 190.119 -28.575)
		(end 190.8302 -29.2862)
		(width 0.2032)
		(layer "B.Cu")
		(net "VR_PVDDRA_ISUMP1")
	)
	(segment
		(start 186.182 -26.8478)
		(end 186.182 -27.6098)
		(width 0.2032)
		(layer "B.Cu")
		(net "VR_PVDDRA_ISUMP1")
	)
	(segment
		(start 186.7408 -28.9052)
		(end 187.5282 -29.6926)
		(width 0.2032)
		(layer "B.Cu")
		(net "VR_PVDDRA_ISUMP1")
	)
	(segment
		(start 188.0616 -29.6926)
		(end 188.2394 -29.5148)
		(width 0.2032)
		(layer "B.Cu")
		(net "VR_PVDDRA_ISUMP1")
	)
	(segment
		(start 188.703966 -29.5148)
		(end 189.2554 -30.066234)
		(width 0.2032)
		(layer "B.Cu")
		(net "VR_PVDDRA_ISUMP1")
	)
	(segment
		(start 190.8302 -30.734)
		(end 190.8302 -30.0228)
		(width 0.2032)
		(layer "B.Cu")
		(net "VR_PVDDRA_ISUMP1")
	)
	(segment
		(start 189.85484 -31.1912)
		(end 190.373 -31.1912)
		(width 0.2032)
		(layer "B.Cu")
		(net "VR_PVDDRA_ISUMP1")
	)
	(segment
		(start 187.5282 -29.6926)
		(end 188.0616 -29.6926)
		(width 0.2032)
		(layer "B.Cu")
		(net "VR_PVDDRA_ISUMP1")
	)
	(segment
		(start 189.2554 -30.59176)
		(end 189.26556 -30.60192)
		(width 0.2032)
		(layer "B.Cu")
		(net "VR_PVDDRA_ISUMP1")
	)
	(segment
		(start 186.1312 -26.797)
		(end 186.182 -26.8478)
		(width 0.2032)
		(layer "B.Cu")
		(net "VR_PVDDRA_ISUMP1")
	)
	(segment
		(start 186.1566 -28.4226)
		(end 186.182 -28.3972)
		(width 0.2032)
		(layer "B.Cu")
		(net "VR_PVDDRA_ISUMP1")
	)
	(segment
		(start 186.182 -28.3972)
		(end 186.182 -27.6098)
		(width 0.2032)
		(layer "B.Cu")
		(net "VR_PVDDRA_ISUMP1")
	)
	(segment
		(start 186.188858 -28.4226)
		(end 186.671458 -28.9052)
		(width 0.2032)
		(layer "B.Cu")
		(net "VR_PVDDRA_ISUMP1")
	)
	(segment
		(start 186.1566 -28.4226)
		(end 186.188858 -28.4226)
		(width 0.2032)
		(layer "B.Cu")
		(net "VR_PVDDRA_ISUMP1")
	)
	(segment
		(start 190.119 -28.3718)
		(end 190.119 -28.575)
		(width 0.2032)
		(layer "B.Cu")
		(net "VR_PVDDRA_ISUMP1")
	)
	(segment
		(start 186.671458 -28.9052)
		(end 186.7408 -28.9052)
		(width 0.2032)
		(layer "B.Cu")
		(net "VR_PVDDRA_ISUMP1")
	)
	(segment
		(start 190.8302 -29.2862)
		(end 190.8302 -30.0228)
		(width 0.2032)
		(layer "B.Cu")
		(net "VR_PVDDRA_ISUMP1")
	)
	(segment
		(start 190.373 -31.1912)
		(end 190.8302 -30.734)
		(width 0.2032)
		(layer "B.Cu")
		(net "VR_PVDDRA_ISUMP1")
	)
	(segment
		(start 188.2394 -29.5148)
		(end 188.703966 -29.5148)
		(width 0.2032)
		(layer "B.Cu")
		(net "VR_PVDDRA_ISUMP1")
	)
	(segment
		(start 179.077874 -3.509772)
		(end 179.077874 -3.68681)
		(width 0.1778)
		(layer "F.Cu")
		(net "M_B_DQ47")
	)
	(segment
		(start 116.7638 -32.9946)
		(end 116.4082 -33.3502)
		(width 0.1016)
		(layer "F.Cu")
		(net "M_B_DQ47")
	)
	(segment
		(start 178.74996 -3.181858)
		(end 179.077874 -3.509772)
		(width 0.1778)
		(layer "F.Cu")
		(net "M_B_DQ47")
	)
	(segment
		(start 113.074704 -35.439096)
		(end 111.777526 -35.439096)
		(width 0.1016)
		(layer "F.Cu")
		(net "M_B_DQ47")
	)
	(segment
		(start 111.777526 -35.439096)
		(end 111.656368 -35.560254)
		(width 0.1016)
		(layer "F.Cu")
		(net "M_B_DQ47")
	)
	(segment
		(start 116.4082 -33.3502)
		(end 115.1636 -33.3502)
		(width 0.1016)
		(layer "F.Cu")
		(net "M_B_DQ47")
	)
	(segment
		(start 115.1636 -33.3502)
		(end 113.074704 -35.439096)
		(width 0.1016)
		(layer "F.Cu")
		(net "M_B_DQ47")
	)
	(segment
		(start 178.74996 -1.68402)
		(end 178.74996 -3.181858)
		(width 0.1778)
		(layer "F.Cu")
		(net "M_B_DQ47")
	)
	(via
		(at 116.7638 -32.9946)
		(size 0.4318)
		(drill 0.2032)
		(layers "F.Cu" "B.Cu")
		(net "M_B_DQ47")
	)
	(via
		(at 179.077874 -3.68681)
		(size 0.4318)
		(drill 0.2032)
		(layers "F.Cu" "B.Cu")
		(net "M_B_DQ47")
	)
	(segment
		(start 179.049934 -1.690624)
		(end 179.049934 -2.903474)
		(width 0.1778)
		(layer "B.Cu")
		(net "M_B_DQ47")
	)
	(segment
		(start 178.98364 -2.969768)
		(end 178.98364 -3.592576)
		(width 0.1778)
		(layer "B.Cu")
		(net "M_B_DQ47")
	)
	(segment
		(start 179.049934 -2.903474)
		(end 178.98364 -2.969768)
		(width 0.1778)
		(layer "B.Cu")
		(net "M_B_DQ47")
	)
	(segment
		(start 178.98364 -3.592576)
		(end 179.077874 -3.68681)
		(width 0.1778)
		(layer "B.Cu")
		(net "M_B_DQ47")
	)
	(segment
		(start 177.61204 -10.01776)
		(end 177.61204 -7.276338)
		(width 0.1524)
		(layer "In2.Cu")
		(net "M_B_DQ47")
	)
	(segment
		(start 179.037488 -3.68681)
		(end 179.077874 -3.68681)
		(width 0.1524)
		(layer "In2.Cu")
		(net "M_B_DQ47")
	)
	(segment
		(start 178.7779 -6.110478)
		(end 178.7779 -3.946398)
		(width 0.1524)
		(layer "In2.Cu")
		(net "M_B_DQ47")
	)
	(segment
		(start 163.9316 -20.9804)
		(end 166.394638 -20.9804)
		(width 0.1524)
		(layer "In2.Cu")
		(net "M_B_DQ47")
	)
	(segment
		(start 131.975352 -29.81198)
		(end 155.10002 -29.81198)
		(width 0.1524)
		(layer "In2.Cu")
		(net "M_B_DQ47")
	)
	(segment
		(start 117.9322 -32.9946)
		(end 116.7638 -32.9946)
		(width 0.1016)
		(layer "In2.Cu")
		(net "M_B_DQ47")
	)
	(segment
		(start 176.8348 -10.795)
		(end 177.61204 -10.01776)
		(width 0.1524)
		(layer "In2.Cu")
		(net "M_B_DQ47")
	)
	(segment
		(start 177.61204 -7.276338)
		(end 178.7779 -6.110478)
		(width 0.1524)
		(layer "In2.Cu")
		(net "M_B_DQ47")
	)
	(segment
		(start 166.394638 -20.9804)
		(end 176.580038 -10.795)
		(width 0.1524)
		(layer "In2.Cu")
		(net "M_B_DQ47")
	)
	(segment
		(start 129.671318 -32.116014)
		(end 131.975352 -29.81198)
		(width 0.1524)
		(layer "In2.Cu")
		(net "M_B_DQ47")
	)
	(segment
		(start 176.580038 -10.795)
		(end 176.8348 -10.795)
		(width 0.1524)
		(layer "In2.Cu")
		(net "M_B_DQ47")
	)
	(segment
		(start 118.810786 -32.116014)
		(end 117.9322 -32.9946)
		(width 0.1016)
		(layer "In2.Cu")
		(net "M_B_DQ47")
	)
	(segment
		(start 178.7779 -3.946398)
		(end 179.037488 -3.68681)
		(width 0.1524)
		(layer "In2.Cu")
		(net "M_B_DQ47")
	)
	(segment
		(start 118.810786 -32.116014)
		(end 129.671318 -32.116014)
		(width 0.1524)
		(layer "In2.Cu")
		(net "M_B_DQ47")
	)
	(segment
		(start 155.10002 -29.81198)
		(end 163.9316 -20.9804)
		(width 0.1524)
		(layer "In2.Cu")
		(net "M_B_DQ47")
	)
	(via
		(at 46.0502 -53.213)
		(size 0.7112)
		(drill 0.3556)
		(layers "F.Cu" "B.Cu")
		(net "CLKREQB")
	)
	(segment
		(start 46.1518 -54.102)
		(end 46.1518 -53.3146)
		(width 0.1143)
		(layer "B.Cu")
		(net "CLKREQB")
	)
	(segment
		(start 45.658786 -52.821586)
		(end 46.0502 -53.213)
		(width 0.1143)
		(layer "B.Cu")
		(net "CLKREQB")
	)
	(segment
		(start 45.658786 -51.70678)
		(end 45.658786 -52.821586)
		(width 0.1143)
		(layer "B.Cu")
		(net "CLKREQB")
	)
	(segment
		(start 46.1518 -53.3146)
		(end 46.0502 -53.213)
		(width 0.1143)
		(layer "B.Cu")
		(net "CLKREQB")
	)
	(segment
		(start 163.24834 -46.07814)
		(end 163.449 -46.2788)
		(width 0.1143)
		(layer "F.Cu")
		(net "XDP_SOC_CPU_TCK")
	)
	(segment
		(start 40.005 -37.85235)
		(end 40.5257 -37.33165)
		(width 0.1143)
		(layer "F.Cu")
		(net "XDP_SOC_CPU_TCK")
	)
	(segment
		(start 39.7002 -38.15715)
		(end 40.005 -37.85235)
		(width 0.1143)
		(layer "F.Cu")
		(net "XDP_SOC_CPU_TCK")
	)
	(segment
		(start 40.5257 -37.33165)
		(end 40.5257 -34.5567)
		(width 0.1143)
		(layer "F.Cu")
		(net "XDP_SOC_CPU_TCK")
	)
	(segment
		(start 76.93406 -36.67125)
		(end 76.481686 -37.123624)
		(width 0.1143)
		(layer "F.Cu")
		(net "XDP_SOC_CPU_TCK")
	)
	(segment
		(start 31.4198 -39.4208)
		(end 32.3088 -40.3098)
		(width 0.1143)
		(layer "F.Cu")
		(net "XDP_SOC_CPU_TCK")
	)
	(segment
		(start 31.4198 -39.1922)
		(end 31.4198 -39.4208)
		(width 0.1143)
		(layer "F.Cu")
		(net "XDP_SOC_CPU_TCK")
	)
	(segment
		(start 80.208628 -37.307774)
		(end 79.813404 -36.91255)
		(width 0.1143)
		(layer "F.Cu")
		(net "XDP_SOC_CPU_TCK")
	)
	(segment
		(start 77.782674 -36.91255)
		(end 77.541374 -36.67125)
		(width 0.1143)
		(layer "F.Cu")
		(net "XDP_SOC_CPU_TCK")
	)
	(segment
		(start 40.5257 -34.5567)
		(end 41.02735 -34.05505)
		(width 0.1143)
		(layer "F.Cu")
		(net "XDP_SOC_CPU_TCK")
	)
	(segment
		(start 39.7002 -38.6588)
		(end 39.7002 -38.15715)
		(width 0.1143)
		(layer "F.Cu")
		(net "XDP_SOC_CPU_TCK")
	)
	(segment
		(start 162.677094 -46.07814)
		(end 163.24834 -46.07814)
		(width 0.1143)
		(layer "F.Cu")
		(net "XDP_SOC_CPU_TCK")
	)
	(segment
		(start 77.541374 -36.67125)
		(end 76.93406 -36.67125)
		(width 0.1143)
		(layer "F.Cu")
		(net "XDP_SOC_CPU_TCK")
	)
	(segment
		(start 79.813404 -36.91255)
		(end 77.782674 -36.91255)
		(width 0.1143)
		(layer "F.Cu")
		(net "XDP_SOC_CPU_TCK")
	)
	(segment
		(start 41.02735 -34.05505)
		(end 42.10177 -34.05505)
		(width 0.1143)
		(layer "F.Cu")
		(net "XDP_SOC_CPU_TCK")
	)
	(via
		(at 66.9544 -64.1858)
		(size 0.508)
		(drill 0.254)
		(layers "F.Cu" "B.Cu")
		(net "XDP_SOC_CPU_TCK")
	)
	(via
		(at 162.677094 -46.07814)
		(size 0.508)
		(drill 0.254)
		(layers "F.Cu" "B.Cu")
		(net "XDP_SOC_CPU_TCK")
	)
	(via
		(at 40.005 -37.85235)
		(size 0.508)
		(drill 0.254)
		(layers "F.Cu" "B.Cu")
		(net "XDP_SOC_CPU_TCK")
	)
	(via
		(at 76.481686 -37.123624)
		(size 0.508)
		(drill 0.254)
		(layers "F.Cu" "B.Cu")
		(net "XDP_SOC_CPU_TCK")
	)
	(via
		(at 189.0014 -56.3626)
		(size 0.508)
		(drill 0.254)
		(layers "F.Cu" "B.Cu")
		(net "XDP_SOC_CPU_TCK")
	)
	(via
		(at 32.3088 -40.3098)
		(size 0.508)
		(drill 0.254)
		(layers "F.Cu" "B.Cu")
		(net "XDP_SOC_CPU_TCK")
	)
	(via
		(at 23.876 -16.0782)
		(size 0.508)
		(drill 0.254)
		(layers "F.Cu" "B.Cu")
		(net "XDP_SOC_CPU_TCK")
	)
	(via
		(at 52.47767 -30.922214)
		(size 0.508)
		(drill 0.254)
		(layers "F.Cu" "B.Cu")
		(net "XDP_SOC_CPU_TCK")
	)
	(segment
		(start 23.876 -16.0782)
		(end 24.8158 -16.0782)
		(width 0.1143)
		(layer "B.Cu")
		(net "XDP_SOC_CPU_TCK")
	)
	(segment
		(start 39.99865 -37.846)
		(end 40.005 -37.85235)
		(width 0.1143)
		(layer "B.Cu")
		(net "XDP_SOC_CPU_TCK")
	)
	(segment
		(start 32.3088 -39.4462)
		(end 32.79775 -38.95725)
		(width 0.1143)
		(layer "B.Cu")
		(net "XDP_SOC_CPU_TCK")
	)
	(segment
		(start 32.3088 -40.3098)
		(end 32.3088 -39.4462)
		(width 0.1143)
		(layer "B.Cu")
		(net "XDP_SOC_CPU_TCK")
	)
	(segment
		(start 32.79775 -38.95725)
		(end 37.62375 -38.95725)
		(width 0.1143)
		(layer "B.Cu")
		(net "XDP_SOC_CPU_TCK")
	)
	(segment
		(start 37.62375 -38.95725)
		(end 38.735 -37.846)
		(width 0.1143)
		(layer "B.Cu")
		(net "XDP_SOC_CPU_TCK")
	)
	(segment
		(start 38.735 -37.846)
		(end 39.99865 -37.846)
		(width 0.1143)
		(layer "B.Cu")
		(net "XDP_SOC_CPU_TCK")
	)
	(segment
		(start 24.8158 -16.0782)
		(end 25.4 -15.494)
		(width 0.1143)
		(layer "B.Cu")
		(net "XDP_SOC_CPU_TCK")
	)
	(segment
		(start 65.7352 -62.9666)
		(end 60.7568 -62.9666)
		(width 0.0889)
		(layer "In2.Cu")
		(net "XDP_SOC_CPU_TCK")
	)
	(segment
		(start 44.704 -46.1772)
		(end 43.2054 -44.6786)
		(width 0.0889)
		(layer "In2.Cu")
		(net "XDP_SOC_CPU_TCK")
	)
	(segment
		(start 66.9544 -64.1858)
		(end 65.7352 -62.9666)
		(width 0.0889)
		(layer "In2.Cu")
		(net "XDP_SOC_CPU_TCK")
	)
	(segment
		(start 53.126386 -52.21351)
		(end 53.126386 -52.095908)
		(width 0.0889)
		(layer "In2.Cu")
		(net "XDP_SOC_CPU_TCK")
	)
	(segment
		(start 39.43985 -38.4175)
		(end 40.005 -37.85235)
		(width 0.0889)
		(layer "In2.Cu")
		(net "XDP_SOC_CPU_TCK")
	)
	(segment
		(start 53.126386 -52.095908)
		(end 50.839878 -49.8094)
		(width 0.0889)
		(layer "In2.Cu")
		(net "XDP_SOC_CPU_TCK")
	)
	(segment
		(start 50.839878 -49.8094)
		(end 49.336452 -49.8094)
		(width 0.0889)
		(layer "In2.Cu")
		(net "XDP_SOC_CPU_TCK")
	)
	(segment
		(start 54.608476 -53.6956)
		(end 53.126386 -52.21351)
		(width 0.0889)
		(layer "In2.Cu")
		(net "XDP_SOC_CPU_TCK")
	)
	(segment
		(start 60.7568 -62.9666)
		(end 60.1218 -62.3316)
		(width 0.0889)
		(layer "In2.Cu")
		(net "XDP_SOC_CPU_TCK")
	)
	(segment
		(start 45.704252 -46.1772)
		(end 44.704 -46.1772)
		(width 0.0889)
		(layer "In2.Cu")
		(net "XDP_SOC_CPU_TCK")
	)
	(segment
		(start 43.2054 -44.6786)
		(end 42.371518 -44.6786)
		(width 0.0889)
		(layer "In2.Cu")
		(net "XDP_SOC_CPU_TCK")
	)
	(segment
		(start 60.1218 -58.468768)
		(end 55.348632 -53.6956)
		(width 0.0889)
		(layer "In2.Cu")
		(net "XDP_SOC_CPU_TCK")
	)
	(segment
		(start 60.1218 -62.3316)
		(end 60.1218 -58.468768)
		(width 0.0889)
		(layer "In2.Cu")
		(net "XDP_SOC_CPU_TCK")
	)
	(segment
		(start 39.43985 -41.746932)
		(end 39.43985 -38.4175)
		(width 0.0889)
		(layer "In2.Cu")
		(net "XDP_SOC_CPU_TCK")
	)
	(segment
		(start 42.371518 -44.6786)
		(end 39.43985 -41.746932)
		(width 0.0889)
		(layer "In2.Cu")
		(net "XDP_SOC_CPU_TCK")
	)
	(segment
		(start 55.348632 -53.6956)
		(end 54.608476 -53.6956)
		(width 0.0889)
		(layer "In2.Cu")
		(net "XDP_SOC_CPU_TCK")
	)
	(segment
		(start 49.336452 -49.8094)
		(end 45.704252 -46.1772)
		(width 0.0889)
		(layer "In2.Cu")
		(net "XDP_SOC_CPU_TCK")
	)
	(segment
		(start 76.9366 -66.3194)
		(end 76.581 -66.675)
		(width 0.0889)
		(layer "In4.Cu")
		(net "XDP_SOC_CPU_TCK")
	)
	(segment
		(start 66.9544 -65.1764)
		(end 66.9544 -64.1858)
		(width 0.0889)
		(layer "In4.Cu")
		(net "XDP_SOC_CPU_TCK")
	)
	(segment
		(start 85.8774 -66.3194)
		(end 76.9366 -66.3194)
		(width 0.0889)
		(layer "In4.Cu")
		(net "XDP_SOC_CPU_TCK")
	)
	(segment
		(start 76.581 -66.675)
		(end 76.581 -66.9798)
		(width 0.0889)
		(layer "In4.Cu")
		(net "XDP_SOC_CPU_TCK")
	)
	(segment
		(start 44.669202 -38.58895)
		(end 43.342052 -37.2618)
		(width 0.0889)
		(layer "In4.Cu")
		(net "XDP_SOC_CPU_TCK")
	)
	(segment
		(start 43.342052 -37.2618)
		(end 40.59555 -37.2618)
		(width 0.0889)
		(layer "In4.Cu")
		(net "XDP_SOC_CPU_TCK")
	)
	(segment
		(start 75.73645 -67.82435)
		(end 74.20991 -67.82435)
		(width 0.0889)
		(layer "In4.Cu")
		(net "XDP_SOC_CPU_TCK")
	)
	(segment
		(start 193.525648 -60.659264)
		(end 193.525648 -68.867528)
		(width 0.0889)
		(layer "In4.Cu")
		(net "XDP_SOC_CPU_TCK")
	)
	(segment
		(start 189.0014 -56.3626)
		(end 189.228984 -56.3626)
		(width 0.0889)
		(layer "In4.Cu")
		(net "XDP_SOC_CPU_TCK")
	)
	(segment
		(start 46.1518 -37.15385)
		(end 46.1518 -37.785548)
		(width 0.0889)
		(layer "In4.Cu")
		(net "XDP_SOC_CPU_TCK")
	)
	(segment
		(start 46.1518 -37.785548)
		(end 45.348398 -38.58895)
		(width 0.0889)
		(layer "In4.Cu")
		(net "XDP_SOC_CPU_TCK")
	)
	(segment
		(start 190.771272 -71.621904)
		(end 91.179904 -71.621904)
		(width 0.0889)
		(layer "In4.Cu")
		(net "XDP_SOC_CPU_TCK")
	)
	(segment
		(start 73.19391 -68.84035)
		(end 70.61835 -68.84035)
		(width 0.0889)
		(layer "In4.Cu")
		(net "XDP_SOC_CPU_TCK")
	)
	(segment
		(start 40.59555 -37.2618)
		(end 40.005 -37.85235)
		(width 0.0889)
		(layer "In4.Cu")
		(net "XDP_SOC_CPU_TCK")
	)
	(segment
		(start 189.228984 -56.3626)
		(end 193.525648 -60.659264)
		(width 0.0889)
		(layer "In4.Cu")
		(net "XDP_SOC_CPU_TCK")
	)
	(segment
		(start 52.47767 -30.922214)
		(end 52.383436 -30.922214)
		(width 0.0889)
		(layer "In4.Cu")
		(net "XDP_SOC_CPU_TCK")
	)
	(segment
		(start 193.525648 -68.867528)
		(end 190.771272 -71.621904)
		(width 0.0889)
		(layer "In4.Cu")
		(net "XDP_SOC_CPU_TCK")
	)
	(segment
		(start 91.179904 -71.621904)
		(end 85.8774 -66.3194)
		(width 0.0889)
		(layer "In4.Cu")
		(net "XDP_SOC_CPU_TCK")
	)
	(segment
		(start 74.20991 -67.82435)
		(end 73.19391 -68.84035)
		(width 0.0889)
		(layer "In4.Cu")
		(net "XDP_SOC_CPU_TCK")
	)
	(segment
		(start 70.61835 -68.84035)
		(end 66.9544 -65.1764)
		(width 0.0889)
		(layer "In4.Cu")
		(net "XDP_SOC_CPU_TCK")
	)
	(segment
		(start 52.383436 -30.922214)
		(end 46.1518 -37.15385)
		(width 0.0889)
		(layer "In4.Cu")
		(net "XDP_SOC_CPU_TCK")
	)
	(segment
		(start 76.581 -66.9798)
		(end 75.73645 -67.82435)
		(width 0.0889)
		(layer "In4.Cu")
		(net "XDP_SOC_CPU_TCK")
	)
	(segment
		(start 45.348398 -38.58895)
		(end 44.669202 -38.58895)
		(width 0.0889)
		(layer "In4.Cu")
		(net "XDP_SOC_CPU_TCK")
	)
	(segment
		(start 75.59675 -35.97275)
		(end 75.59675 -36.338256)
		(width 0.0889)
		(layer "In7.Cu")
		(net "XDP_SOC_CPU_TCK")
	)
	(segment
		(start 52.924456 -31.369)
		(end 64.91351 -31.369)
		(width 0.0889)
		(layer "In7.Cu")
		(net "XDP_SOC_CPU_TCK")
	)
	(segment
		(start 64.91351 -31.369)
		(end 66.89471 -33.3502)
		(width 0.0889)
		(layer "In7.Cu")
		(net "XDP_SOC_CPU_TCK")
	)
	(segment
		(start 76.132944 -36.87445)
		(end 76.232512 -36.87445)
		(width 0.0889)
		(layer "In7.Cu")
		(net "XDP_SOC_CPU_TCK")
	)
	(segment
		(start 76.232512 -36.87445)
		(end 76.481686 -37.123624)
		(width 0.0889)
		(layer "In7.Cu")
		(net "XDP_SOC_CPU_TCK")
	)
	(segment
		(start 74.7141 -35.0901)
		(end 75.59675 -35.97275)
		(width 0.0889)
		(layer "In7.Cu")
		(net "XDP_SOC_CPU_TCK")
	)
	(segment
		(start 66.89471 -33.3502)
		(end 73.337166 -33.3502)
		(width 0.0889)
		(layer "In7.Cu")
		(net "XDP_SOC_CPU_TCK")
	)
	(segment
		(start 75.59675 -36.338256)
		(end 76.132944 -36.87445)
		(width 0.0889)
		(layer "In7.Cu")
		(net "XDP_SOC_CPU_TCK")
	)
	(segment
		(start 73.337166 -33.3502)
		(end 74.7141 -34.727134)
		(width 0.0889)
		(layer "In7.Cu")
		(net "XDP_SOC_CPU_TCK")
	)
	(segment
		(start 74.7141 -34.727134)
		(end 74.7141 -35.0901)
		(width 0.0889)
		(layer "In7.Cu")
		(net "XDP_SOC_CPU_TCK")
	)
	(segment
		(start 52.47767 -30.922214)
		(end 52.924456 -31.369)
		(width 0.0889)
		(layer "In7.Cu")
		(net "XDP_SOC_CPU_TCK")
	)
	(segment
		(start 34.22015 -32.267144)
		(end 36.705286 -34.75228)
		(width 0.0889)
		(layer "In9.Cu")
		(net "XDP_SOC_CPU_TCK")
	)
	(segment
		(start 23.55215 -16.40205)
		(end 23.55215 -19.541744)
		(width 0.0889)
		(layer "In9.Cu")
		(net "XDP_SOC_CPU_TCK")
	)
	(segment
		(start 29.14015 -29.894784)
		(end 30.538166 -31.2928)
		(width 0.0889)
		(layer "In9.Cu")
		(net "XDP_SOC_CPU_TCK")
	)
	(segment
		(start 40.005 -37.384736)
		(end 40.005 -37.85235)
		(width 0.0889)
		(layer "In9.Cu")
		(net "XDP_SOC_CPU_TCK")
	)
	(segment
		(start 23.949406 -19.939)
		(end 25.848818 -19.939)
		(width 0.0889)
		(layer "In9.Cu")
		(net "XDP_SOC_CPU_TCK")
	)
	(segment
		(start 36.705286 -34.75228)
		(end 37.372544 -34.75228)
		(width 0.0889)
		(layer "In9.Cu")
		(net "XDP_SOC_CPU_TCK")
	)
	(segment
		(start 187.569602 -55.75935)
		(end 188.39815 -55.75935)
		(width 0.0889)
		(layer "In9.Cu")
		(net "XDP_SOC_CPU_TCK")
	)
	(segment
		(start 23.876 -16.0782)
		(end 23.55215 -16.40205)
		(width 0.0889)
		(layer "In9.Cu")
		(net "XDP_SOC_CPU_TCK")
	)
	(segment
		(start 37.372544 -34.75228)
		(end 40.005 -37.384736)
		(width 0.0889)
		(layer "In9.Cu")
		(net "XDP_SOC_CPU_TCK")
	)
	(segment
		(start 25.848818 -19.939)
		(end 29.14015 -23.230332)
		(width 0.0889)
		(layer "In9.Cu")
		(net "XDP_SOC_CPU_TCK")
	)
	(segment
		(start 162.677094 -46.07814)
		(end 158.62935 -50.125884)
		(width 0.0889)
		(layer "In9.Cu")
		(net "XDP_SOC_CPU_TCK")
	)
	(segment
		(start 33.292796 -31.2928)
		(end 34.22015 -32.220154)
		(width 0.0889)
		(layer "In9.Cu")
		(net "XDP_SOC_CPU_TCK")
	)
	(segment
		(start 23.55215 -19.541744)
		(end 23.949406 -19.939)
		(width 0.0889)
		(layer "In9.Cu")
		(net "XDP_SOC_CPU_TCK")
	)
	(segment
		(start 158.62935 -50.542444)
		(end 163.458906 -55.372)
		(width 0.0889)
		(layer "In9.Cu")
		(net "XDP_SOC_CPU_TCK")
	)
	(segment
		(start 29.14015 -23.230332)
		(end 29.14015 -29.894784)
		(width 0.0889)
		(layer "In9.Cu")
		(net "XDP_SOC_CPU_TCK")
	)
	(segment
		(start 188.39815 -55.75935)
		(end 189.0014 -56.3626)
		(width 0.0889)
		(layer "In9.Cu")
		(net "XDP_SOC_CPU_TCK")
	)
	(segment
		(start 158.62935 -50.125884)
		(end 158.62935 -50.542444)
		(width 0.0889)
		(layer "In9.Cu")
		(net "XDP_SOC_CPU_TCK")
	)
	(segment
		(start 34.22015 -32.220154)
		(end 34.22015 -32.267144)
		(width 0.0889)
		(layer "In9.Cu")
		(net "XDP_SOC_CPU_TCK")
	)
	(segment
		(start 163.458906 -55.372)
		(end 187.182252 -55.372)
		(width 0.0889)
		(layer "In9.Cu")
		(net "XDP_SOC_CPU_TCK")
	)
	(segment
		(start 30.538166 -31.2928)
		(end 33.292796 -31.2928)
		(width 0.0889)
		(layer "In9.Cu")
		(net "XDP_SOC_CPU_TCK")
	)
	(segment
		(start 187.182252 -55.372)
		(end 187.569602 -55.75935)
		(width 0.0889)
		(layer "In9.Cu")
		(net "XDP_SOC_CPU_TCK")
	)
	(via
		(at 34.0614 -50.1396)
		(size 0.7112)
		(drill 0.3556)
		(layers "F.Cu" "B.Cu")
		(net "P1V5_STBY_EN")
	)
	(segment
		(start 32.766762 -49.920398)
		(end 33.842198 -49.920398)
		(width 0.254)
		(layer "B.Cu")
		(net "P1V5_STBY_EN")
	)
	(segment
		(start 34.0614 -50.1396)
		(end 34.6202 -50.6984)
		(width 0.254)
		(layer "B.Cu")
		(net "P1V5_STBY_EN")
	)
	(segment
		(start 35.0266 -49.0728)
		(end 35.2044 -48.895)
		(width 0.254)
		(layer "B.Cu")
		(net "P1V5_STBY_EN")
	)
	(segment
		(start 35.3822 -50.305462)
		(end 35.0266 -49.949862)
		(width 0.254)
		(layer "B.Cu")
		(net "P1V5_STBY_EN")
	)
	(segment
		(start 34.6202 -51.054)
		(end 35.3822 -51.054)
		(width 0.254)
		(layer "B.Cu")
		(net "P1V5_STBY_EN")
	)
	(segment
		(start 33.842198 -49.920398)
		(end 34.0614 -50.1396)
		(width 0.254)
		(layer "B.Cu")
		(net "P1V5_STBY_EN")
	)
	(segment
		(start 35.0266 -49.949862)
		(end 35.0266 -49.0728)
		(width 0.254)
		(layer "B.Cu")
		(net "P1V5_STBY_EN")
	)
	(segment
		(start 35.3822 -51.054)
		(end 35.3822 -50.305462)
		(width 0.254)
		(layer "B.Cu")
		(net "P1V5_STBY_EN")
	)
	(segment
		(start 34.6202 -50.6984)
		(end 34.6202 -51.054)
		(width 0.254)
		(layer "B.Cu")
		(net "P1V5_STBY_EN")
	)
	(segment
		(start 191.656716 -32.175704)
		(end 192.004696 -32.175704)
		(width 0.2032)
		(layer "F.Cu")
		(net "VR_PVDDR_A_VIN")
	)
	(segment
		(start 192.6082 -31.5722)
		(end 192.5066 -31.6738)
		(width 0.508)
		(layer "F.Cu")
		(net "VR_PVDDR_A_VIN")
	)
	(segment
		(start 192.004696 -32.175704)
		(end 192.5066 -31.6738)
		(width 0.2032)
		(layer "F.Cu")
		(net "VR_PVDDR_A_VIN")
	)
	(segment
		(start 192.6082 -30.988)
		(end 192.6082 -31.5722)
		(width 0.508)
		(layer "F.Cu")
		(net "VR_PVDDR_A_VIN")
	)
	(via
		(at 196.226938 -34.449258)
		(size 0.7112)
		(drill 0.3556)
		(layers "F.Cu" "B.Cu")
		(net "VR_PVDDR_A_VIN")
	)
	(via
		(at 192.5066 -31.6738)
		(size 0.508)
		(drill 0.254)
		(layers "F.Cu" "B.Cu")
		(net "VR_PVDDR_A_VIN")
	)
	(segment
		(start 194.945 -32.7152)
		(end 193.548 -32.7152)
		(width 0.508)
		(layer "B.Cu")
		(net "VR_PVDDR_A_VIN")
	)
	(segment
		(start 196.226938 -33.387538)
		(end 195.5546 -32.7152)
		(width 0.508)
		(layer "B.Cu")
		(net "VR_PVDDR_A_VIN")
	)
	(segment
		(start 196.226938 -34.449258)
		(end 196.226938 -33.387538)
		(width 0.508)
		(layer "B.Cu")
		(net "VR_PVDDR_A_VIN")
	)
	(segment
		(start 193.548 -32.7152)
		(end 192.5066 -31.6738)
		(width 0.508)
		(layer "B.Cu")
		(net "VR_PVDDR_A_VIN")
	)
	(segment
		(start 195.5546 -32.7152)
		(end 194.945 -32.7152)
		(width 0.508)
		(layer "B.Cu")
		(net "VR_PVDDR_A_VIN")
	)
	(segment
		(start 96.8502 -28.2194)
		(end 96.624648 -28.444952)
		(width 0.1016)
		(layer "F.Cu")
		(net "M_B_DQ28")
	)
	(segment
		(start 96.624648 -29.311854)
		(end 96.319848 -29.616654)
		(width 0.1016)
		(layer "F.Cu")
		(net "M_B_DQ28")
	)
	(segment
		(start 97.148142 -27.5844)
		(end 96.8502 -27.882342)
		(width 0.1016)
		(layer "F.Cu")
		(net "M_B_DQ28")
	)
	(segment
		(start 96.8502 -27.882342)
		(end 96.8502 -28.2194)
		(width 0.1016)
		(layer "F.Cu")
		(net "M_B_DQ28")
	)
	(segment
		(start 96.624648 -28.444952)
		(end 96.624648 -29.311854)
		(width 0.1016)
		(layer "F.Cu")
		(net "M_B_DQ28")
	)
	(segment
		(start 144.549876 -3.014472)
		(end 144.41297 -3.151378)
		(width 0.1778)
		(layer "F.Cu")
		(net "M_B_DQ28")
	)
	(segment
		(start 97.179384 -27.5844)
		(end 97.148142 -27.5844)
		(width 0.1016)
		(layer "F.Cu")
		(net "M_B_DQ28")
	)
	(segment
		(start 144.549876 -1.68402)
		(end 144.549876 -3.014472)
		(width 0.1778)
		(layer "F.Cu")
		(net "M_B_DQ28")
	)
	(via
		(at 97.179384 -27.5844)
		(size 0.4318)
		(drill 0.2032)
		(layers "F.Cu" "B.Cu")
		(net "M_B_DQ28")
	)
	(via
		(at 144.41297 -3.151378)
		(size 0.4318)
		(drill 0.2032)
		(layers "F.Cu" "B.Cu")
		(net "M_B_DQ28")
	)
	(segment
		(start 144.249902 -1.690624)
		(end 144.249902 -2.98831)
		(width 0.1778)
		(layer "B.Cu")
		(net "M_B_DQ28")
	)
	(segment
		(start 144.249902 -2.98831)
		(end 144.41297 -3.151378)
		(width 0.1778)
		(layer "B.Cu")
		(net "M_B_DQ28")
	)
	(segment
		(start 98.7044 -25.5524)
		(end 97.179384 -27.077416)
		(width 0.1016)
		(layer "In4.Cu")
		(net "M_B_DQ28")
	)
	(segment
		(start 113.800128 -18.2118)
		(end 118.3894 -18.2118)
		(width 0.1524)
		(layer "In4.Cu")
		(net "M_B_DQ28")
	)
	(segment
		(start 144.04848 -6.829298)
		(end 144.41297 -6.464808)
		(width 0.1524)
		(layer "In4.Cu")
		(net "M_B_DQ28")
	)
	(segment
		(start 120.0404 -18.0594)
		(end 120.0404 -17.0688)
		(width 0.1524)
		(layer "In4.Cu")
		(net "M_B_DQ28")
	)
	(segment
		(start 119.3038 -18.0594)
		(end 119.4562 -18.2118)
		(width 0.1524)
		(layer "In4.Cu")
		(net "M_B_DQ28")
	)
	(segment
		(start 144.04848 -10.25652)
		(end 144.04848 -6.829298)
		(width 0.1524)
		(layer "In4.Cu")
		(net "M_B_DQ28")
	)
	(segment
		(start 118.3894 -18.2118)
		(end 118.5418 -18.0594)
		(width 0.1524)
		(layer "In4.Cu")
		(net "M_B_DQ28")
	)
	(segment
		(start 143.474694 -17.974056)
		(end 143.474694 -10.830306)
		(width 0.1524)
		(layer "In4.Cu")
		(net "M_B_DQ28")
	)
	(segment
		(start 102.995984 -21.108416)
		(end 103.4288 -20.6756)
		(width 0.1524)
		(layer "In4.Cu")
		(net "M_B_DQ28")
	)
	(segment
		(start 119.888 -18.2118)
		(end 120.0404 -18.0594)
		(width 0.1524)
		(layer "In4.Cu")
		(net "M_B_DQ28")
	)
	(segment
		(start 120.1928 -16.9164)
		(end 138.5824 -16.9164)
		(width 0.1524)
		(layer "In4.Cu")
		(net "M_B_DQ28")
	)
	(segment
		(start 119.3038 -17.145)
		(end 119.3038 -18.0594)
		(width 0.1524)
		(layer "In4.Cu")
		(net "M_B_DQ28")
	)
	(segment
		(start 118.6942 -16.9926)
		(end 119.1514 -16.9926)
		(width 0.1524)
		(layer "In4.Cu")
		(net "M_B_DQ28")
	)
	(segment
		(start 118.5418 -18.0594)
		(end 118.5418 -17.145)
		(width 0.1524)
		(layer "In4.Cu")
		(net "M_B_DQ28")
	)
	(segment
		(start 138.7348 -18.034)
		(end 138.8872 -18.1864)
		(width 0.1524)
		(layer "In4.Cu")
		(net "M_B_DQ28")
	)
	(segment
		(start 138.8872 -18.1864)
		(end 143.26235 -18.1864)
		(width 0.1524)
		(layer "In4.Cu")
		(net "M_B_DQ28")
	)
	(segment
		(start 144.41297 -6.464808)
		(end 144.41297 -3.151378)
		(width 0.1524)
		(layer "In4.Cu")
		(net "M_B_DQ28")
	)
	(segment
		(start 138.5824 -16.9164)
		(end 138.7348 -17.0688)
		(width 0.1524)
		(layer "In4.Cu")
		(net "M_B_DQ28")
	)
	(segment
		(start 103.4288 -20.6756)
		(end 111.336328 -20.6756)
		(width 0.1524)
		(layer "In4.Cu")
		(net "M_B_DQ28")
	)
	(segment
		(start 111.336328 -20.6756)
		(end 113.800128 -18.2118)
		(width 0.1524)
		(layer "In4.Cu")
		(net "M_B_DQ28")
	)
	(segment
		(start 118.5418 -17.145)
		(end 118.6942 -16.9926)
		(width 0.1524)
		(layer "In4.Cu")
		(net "M_B_DQ28")
	)
	(segment
		(start 119.4562 -18.2118)
		(end 119.888 -18.2118)
		(width 0.1524)
		(layer "In4.Cu")
		(net "M_B_DQ28")
	)
	(segment
		(start 102.108 -25.5524)
		(end 98.7044 -25.5524)
		(width 0.1016)
		(layer "In4.Cu")
		(net "M_B_DQ28")
	)
	(segment
		(start 102.995984 -24.664416)
		(end 102.995984 -21.108416)
		(width 0.1524)
		(layer "In4.Cu")
		(net "M_B_DQ28")
	)
	(segment
		(start 102.995984 -24.664416)
		(end 102.108 -25.5524)
		(width 0.1016)
		(layer "In4.Cu")
		(net "M_B_DQ28")
	)
	(segment
		(start 143.474694 -10.830306)
		(end 144.04848 -10.25652)
		(width 0.1524)
		(layer "In4.Cu")
		(net "M_B_DQ28")
	)
	(segment
		(start 119.1514 -16.9926)
		(end 119.3038 -17.145)
		(width 0.1524)
		(layer "In4.Cu")
		(net "M_B_DQ28")
	)
	(segment
		(start 143.26235 -18.1864)
		(end 143.474694 -17.974056)
		(width 0.1524)
		(layer "In4.Cu")
		(net "M_B_DQ28")
	)
	(segment
		(start 97.179384 -27.077416)
		(end 97.179384 -27.5844)
		(width 0.1016)
		(layer "In4.Cu")
		(net "M_B_DQ28")
	)
	(segment
		(start 138.7348 -17.0688)
		(end 138.7348 -18.034)
		(width 0.1524)
		(layer "In4.Cu")
		(net "M_B_DQ28")
	)
	(segment
		(start 120.0404 -17.0688)
		(end 120.1928 -16.9164)
		(width 0.1524)
		(layer "In4.Cu")
		(net "M_B_DQ28")
	)
	(segment
		(start 39.33571 -27.05481)
		(end 39.2557 -26.9748)
		(width 0.1143)
		(layer "F.Cu")
		(net "XDP_DFX_PORT5")
	)
	(segment
		(start 84.409788 -45.390054)
		(end 84.409788 -45.496988)
		(width 0.1143)
		(layer "F.Cu")
		(net "XDP_DFX_PORT5")
	)
	(segment
		(start 84.409788 -45.496988)
		(end 84.455 -45.5422)
		(width 0.1143)
		(layer "F.Cu")
		(net "XDP_DFX_PORT5")
	)
	(segment
		(start 42.10177 -27.05481)
		(end 39.33571 -27.05481)
		(width 0.1143)
		(layer "F.Cu")
		(net "XDP_DFX_PORT5")
	)
	(segment
		(start 84.455 -45.5422)
		(end 84.455 -45.9486)
		(width 0.1143)
		(layer "F.Cu")
		(net "XDP_DFX_PORT5")
	)
	(via
		(at 85.471 -46.482)
		(size 0.7112)
		(drill 0.3556)
		(layers "F.Cu" "B.Cu")
		(net "XDP_DFX_PORT5")
	)
	(via
		(at 39.2557 -26.9748)
		(size 0.508)
		(drill 0.254)
		(layers "F.Cu" "B.Cu")
		(net "XDP_DFX_PORT5")
	)
	(via
		(at 84.455 -45.9486)
		(size 0.4318)
		(drill 0.2032)
		(layers "F.Cu" "B.Cu")
		(net "XDP_DFX_PORT5")
	)
	(segment
		(start 85.471 -46.482)
		(end 84.9884 -46.482)
		(width 0.1143)
		(layer "B.Cu")
		(net "XDP_DFX_PORT5")
	)
	(segment
		(start 84.9884 -46.482)
		(end 84.455 -45.9486)
		(width 0.1143)
		(layer "B.Cu")
		(net "XDP_DFX_PORT5")
	)
	(segment
		(start 39.735506 -29.78785)
		(end 40.080438 -29.78785)
		(width 0.0889)
		(layer "In7.Cu")
		(net "XDP_DFX_PORT5")
	)
	(segment
		(start 78.892908 -44.59605)
		(end 79.67091 -45.374052)
		(width 0.0889)
		(layer "In7.Cu")
		(net "XDP_DFX_PORT5")
	)
	(segment
		(start 65.322958 -38.75405)
		(end 69.362574 -42.793666)
		(width 0.0889)
		(layer "In7.Cu")
		(net "XDP_DFX_PORT5")
	)
	(segment
		(start 50.442876 -37.595556)
		(end 55.978044 -37.595556)
		(width 0.0889)
		(layer "In7.Cu")
		(net "XDP_DFX_PORT5")
	)
	(segment
		(start 44.487338 -34.19475)
		(end 45.980858 -34.19475)
		(width 0.0889)
		(layer "In7.Cu")
		(net "XDP_DFX_PORT5")
	)
	(segment
		(start 69.362574 -42.793666)
		(end 74.027284 -42.793666)
		(width 0.0889)
		(layer "In7.Cu")
		(net "XDP_DFX_PORT5")
	)
	(segment
		(start 75.829668 -44.59605)
		(end 78.892908 -44.59605)
		(width 0.0889)
		(layer "In7.Cu")
		(net "XDP_DFX_PORT5")
	)
	(segment
		(start 45.980858 -34.19475)
		(end 47.739808 -35.9537)
		(width 0.0889)
		(layer "In7.Cu")
		(net "XDP_DFX_PORT5")
	)
	(segment
		(start 48.80102 -35.9537)
		(end 50.442876 -37.595556)
		(width 0.0889)
		(layer "In7.Cu")
		(net "XDP_DFX_PORT5")
	)
	(segment
		(start 39.4716 -27.939492)
		(end 39.4716 -29.523944)
		(width 0.0889)
		(layer "In7.Cu")
		(net "XDP_DFX_PORT5")
	)
	(segment
		(start 40.080438 -29.78785)
		(end 44.487338 -34.19475)
		(width 0.0889)
		(layer "In7.Cu")
		(net "XDP_DFX_PORT5")
	)
	(segment
		(start 82.809334 -45.374052)
		(end 83.006946 -45.571664)
		(width 0.0889)
		(layer "In7.Cu")
		(net "XDP_DFX_PORT5")
	)
	(segment
		(start 39.2557 -27.723592)
		(end 39.4716 -27.939492)
		(width 0.0889)
		(layer "In7.Cu")
		(net "XDP_DFX_PORT5")
	)
	(segment
		(start 83.006946 -45.571664)
		(end 84.078064 -45.571664)
		(width 0.0889)
		(layer "In7.Cu")
		(net "XDP_DFX_PORT5")
	)
	(segment
		(start 39.2557 -26.9748)
		(end 39.2557 -27.723592)
		(width 0.0889)
		(layer "In7.Cu")
		(net "XDP_DFX_PORT5")
	)
	(segment
		(start 47.739808 -35.9537)
		(end 48.80102 -35.9537)
		(width 0.0889)
		(layer "In7.Cu")
		(net "XDP_DFX_PORT5")
	)
	(segment
		(start 39.4716 -29.523944)
		(end 39.735506 -29.78785)
		(width 0.0889)
		(layer "In7.Cu")
		(net "XDP_DFX_PORT5")
	)
	(segment
		(start 84.078064 -45.571664)
		(end 84.455 -45.9486)
		(width 0.0889)
		(layer "In7.Cu")
		(net "XDP_DFX_PORT5")
	)
	(segment
		(start 74.027284 -42.793666)
		(end 75.829668 -44.59605)
		(width 0.0889)
		(layer "In7.Cu")
		(net "XDP_DFX_PORT5")
	)
	(segment
		(start 57.136538 -38.75405)
		(end 65.322958 -38.75405)
		(width 0.0889)
		(layer "In7.Cu")
		(net "XDP_DFX_PORT5")
	)
	(segment
		(start 55.978044 -37.595556)
		(end 57.136538 -38.75405)
		(width 0.0889)
		(layer "In7.Cu")
		(net "XDP_DFX_PORT5")
	)
	(segment
		(start 79.67091 -45.374052)
		(end 82.809334 -45.374052)
		(width 0.0889)
		(layer "In7.Cu")
		(net "XDP_DFX_PORT5")
	)
	(segment
		(start 78.105 -31.1658)
		(end 78.105 -31.199074)
		(width 0.1397)
		(layer "F.Cu")
		(net "SATA3_TX_DP1")
	)
	(segment
		(start 78.105 -31.199074)
		(end 79.770732 -32.864806)
		(width 0.1397)
		(layer "F.Cu")
		(net "SATA3_TX_DP1")
	)
	(segment
		(start 80.390746 -33.147254)
		(end 80.738726 -32.799274)
		(width 0.1397)
		(layer "F.Cu")
		(net "SATA3_TX_DP1")
	)
	(segment
		(start 10.2108 -50.4952)
		(end 9.5504 -50.4952)
		(width 0.1397)
		(layer "F.Cu")
		(net "SATA3_TX_DP1")
	)
	(segment
		(start 79.78394 -32.864806)
		(end 80.066388 -33.147254)
		(width 0.1397)
		(layer "F.Cu")
		(net "SATA3_TX_DP1")
	)
	(segment
		(start 80.738726 -32.799274)
		(end 80.950308 -32.799274)
		(width 0.1397)
		(layer "F.Cu")
		(net "SATA3_TX_DP1")
	)
	(segment
		(start 80.066388 -33.147254)
		(end 80.390746 -33.147254)
		(width 0.1397)
		(layer "F.Cu")
		(net "SATA3_TX_DP1")
	)
	(segment
		(start 79.770732 -32.864806)
		(end 79.78394 -32.864806)
		(width 0.1397)
		(layer "F.Cu")
		(net "SATA3_TX_DP1")
	)
	(via
		(at 78.105 -31.1658)
		(size 0.4318)
		(drill 0.2032)
		(layers "F.Cu" "B.Cu")
		(net "SATA3_TX_DP1")
	)
	(via
		(at 9.5504 -50.4952)
		(size 0.508)
		(drill 0.254)
		(layers "F.Cu" "B.Cu")
		(net "SATA3_TX_DP1")
	)
	(segment
		(start 9.6647 -50.9524)
		(end 15.24 -50.9524)
		(width 0.1143)
		(layer "In4.Cu")
		(net "SATA3_TX_DP1")
	)
	(segment
		(start 9.5504 -50.4952)
		(end 9.5504 -50.8381)
		(width 0.1143)
		(layer "In4.Cu")
		(net "SATA3_TX_DP1")
	)
	(segment
		(start 50.292508 -46.4185)
		(end 51.76901 -44.941744)
		(width 0.1143)
		(layer "In4.Cu")
		(net "SATA3_TX_DP1")
	)
	(segment
		(start 19.478244 -50.61585)
		(end 20.894294 -49.1998)
		(width 0.1143)
		(layer "In4.Cu")
		(net "SATA3_TX_DP1")
	)
	(segment
		(start 34.528506 -48.641)
		(end 35.2044 -48.641)
		(width 0.1143)
		(layer "In4.Cu")
		(net "SATA3_TX_DP1")
	)
	(segment
		(start 33.385506 -47.498)
		(end 34.528506 -48.641)
		(width 0.1143)
		(layer "In4.Cu")
		(net "SATA3_TX_DP1")
	)
	(segment
		(start 35.2044 -48.641)
		(end 35.75685 -48.08855)
		(width 0.1143)
		(layer "In4.Cu")
		(net "SATA3_TX_DP1")
	)
	(segment
		(start 24.9682 -49.1998)
		(end 26.67 -47.498)
		(width 0.1143)
		(layer "In4.Cu")
		(net "SATA3_TX_DP1")
	)
	(segment
		(start 26.67 -47.498)
		(end 33.385506 -47.498)
		(width 0.1143)
		(layer "In4.Cu")
		(net "SATA3_TX_DP1")
	)
	(segment
		(start 78.189836 -31.580836)
		(end 78.304136 -31.466536)
		(width 0.1016)
		(layer "In4.Cu")
		(net "SATA3_TX_DP1")
	)
	(segment
		(start 51.76901 -44.941744)
		(end 51.76901 -44.941998)
		(width 0.1143)
		(layer "In4.Cu")
		(net "SATA3_TX_DP1")
	)
	(segment
		(start 15.57655 -50.61585)
		(end 19.478244 -50.61585)
		(width 0.1143)
		(layer "In4.Cu")
		(net "SATA3_TX_DP1")
	)
	(segment
		(start 66.387472 -31.389828)
		(end 77.089 -31.389828)
		(width 0.1143)
		(layer "In4.Cu")
		(net "SATA3_TX_DP1")
	)
	(segment
		(start 77.089 -31.389828)
		(end 77.1144 -31.389828)
		(width 0.1016)
		(layer "In4.Cu")
		(net "SATA3_TX_DP1")
	)
	(segment
		(start 9.5504 -50.8381)
		(end 9.6647 -50.9524)
		(width 0.1143)
		(layer "In4.Cu")
		(net "SATA3_TX_DP1")
	)
	(segment
		(start 49.634394 -46.4185)
		(end 50.292508 -46.4185)
		(width 0.1143)
		(layer "In4.Cu")
		(net "SATA3_TX_DP1")
	)
	(segment
		(start 53.163724 -43.547284)
		(end 54.230016 -43.547284)
		(width 0.1143)
		(layer "In4.Cu")
		(net "SATA3_TX_DP1")
	)
	(segment
		(start 78.304136 -31.466536)
		(end 78.304136 -31.364936)
		(width 0.1016)
		(layer "In4.Cu")
		(net "SATA3_TX_DP1")
	)
	(segment
		(start 35.75685 -48.08855)
		(end 47.964344 -48.08855)
		(width 0.1143)
		(layer "In4.Cu")
		(net "SATA3_TX_DP1")
	)
	(segment
		(start 51.76901 -44.941998)
		(end 53.163724 -43.547284)
		(width 0.1143)
		(layer "In4.Cu")
		(net "SATA3_TX_DP1")
	)
	(segment
		(start 77.1144 -31.389828)
		(end 77.1779 -31.453328)
		(width 0.1016)
		(layer "In4.Cu")
		(net "SATA3_TX_DP1")
	)
	(segment
		(start 77.528928 -31.453328)
		(end 77.656436 -31.580836)
		(width 0.1016)
		(layer "In4.Cu")
		(net "SATA3_TX_DP1")
	)
	(segment
		(start 77.1779 -31.453328)
		(end 77.528928 -31.453328)
		(width 0.1016)
		(layer "In4.Cu")
		(net "SATA3_TX_DP1")
	)
	(segment
		(start 15.24 -50.9524)
		(end 15.57655 -50.61585)
		(width 0.1143)
		(layer "In4.Cu")
		(net "SATA3_TX_DP1")
	)
	(segment
		(start 54.230016 -43.547284)
		(end 66.387472 -31.389828)
		(width 0.1143)
		(layer "In4.Cu")
		(net "SATA3_TX_DP1")
	)
	(segment
		(start 77.656436 -31.580836)
		(end 78.189836 -31.580836)
		(width 0.1016)
		(layer "In4.Cu")
		(net "SATA3_TX_DP1")
	)
	(segment
		(start 47.964344 -48.08855)
		(end 49.634394 -46.4185)
		(width 0.1143)
		(layer "In4.Cu")
		(net "SATA3_TX_DP1")
	)
	(segment
		(start 20.894294 -49.1998)
		(end 24.9682 -49.1998)
		(width 0.1143)
		(layer "In4.Cu")
		(net "SATA3_TX_DP1")
	)
	(segment
		(start 78.304136 -31.364936)
		(end 78.105 -31.1658)
		(width 0.1016)
		(layer "In4.Cu")
		(net "SATA3_TX_DP1")
	)
	(via
		(at 26.543 -50.673)
		(size 0.7112)
		(drill 0.3556)
		(layers "F.Cu" "B.Cu")
		(net "P1V5_STBY_IN")
	)
	(via
		(at 27.94 -51.2826)
		(size 0.508)
		(drill 0.254)
		(layers "F.Cu" "B.Cu")
		(net "P1V5_STBY_IN")
	)
	(via
		(at 27.36596 -51.93284)
		(size 0.508)
		(drill 0.254)
		(layers "F.Cu" "B.Cu")
		(net "P1V5_STBY_IN")
	)
	(segment
		(start 186.856116 -36.439348)
		(end 185.061606 -38.233858)
		(width 0.1143)
		(layer "F.Cu")
		(net "SVID_DIO_A")
	)
	(segment
		(start 186.856116 -35.7759)
		(end 186.856116 -36.439348)
		(width 0.1143)
		(layer "F.Cu")
		(net "SVID_DIO_A")
	)
	(segment
		(start 184.0738 -38.862)
		(end 184.433464 -38.862)
		(width 0.1143)
		(layer "F.Cu")
		(net "SVID_DIO_A")
	)
	(segment
		(start 184.433464 -38.862)
		(end 185.061606 -38.233858)
		(width 0.1143)
		(layer "F.Cu")
		(net "SVID_DIO_A")
	)
	(via
		(at 185.061606 -38.233858)
		(size 0.7112)
		(drill 0.3556)
		(layers "F.Cu" "B.Cu")
		(net "SVID_DIO_A")
	)
	(segment
		(start 134.392924 -8.791702)
		(end 134.2136 -8.612378)
		(width 0.1778)
		(layer "F.Cu")
		(net "M_B_DQ8")
	)
	(segment
		(start 96.436688 -25.706832)
		(end 96.436688 -26.116534)
		(width 0.1016)
		(layer "F.Cu")
		(net "M_B_DQ8")
	)
	(segment
		(start 134.649972 -9.054846)
		(end 134.392924 -8.797798)
		(width 0.1778)
		(layer "F.Cu")
		(net "M_B_DQ8")
	)
	(segment
		(start 96.436688 -26.116534)
		(end 96.713548 -26.393394)
		(width 0.1016)
		(layer "F.Cu")
		(net "M_B_DQ8")
	)
	(segment
		(start 134.649972 -9.897364)
		(end 134.649972 -9.054846)
		(width 0.1778)
		(layer "F.Cu")
		(net "M_B_DQ8")
	)
	(segment
		(start 95.4532 -24.723344)
		(end 96.436688 -25.706832)
		(width 0.1016)
		(layer "F.Cu")
		(net "M_B_DQ8")
	)
	(segment
		(start 95.4532 -22.987)
		(end 95.4532 -24.723344)
		(width 0.1016)
		(layer "F.Cu")
		(net "M_B_DQ8")
	)
	(segment
		(start 134.2136 -8.42645)
		(end 134.366 -8.27405)
		(width 0.1778)
		(layer "F.Cu")
		(net "M_B_DQ8")
	)
	(segment
		(start 134.366 -8.27405)
		(end 134.39648 -8.27405)
		(width 0.1778)
		(layer "F.Cu")
		(net "M_B_DQ8")
	)
	(segment
		(start 134.2136 -8.612378)
		(end 134.2136 -8.42645)
		(width 0.1778)
		(layer "F.Cu")
		(net "M_B_DQ8")
	)
	(segment
		(start 134.392924 -8.797798)
		(end 134.392924 -8.791702)
		(width 0.1778)
		(layer "F.Cu")
		(net "M_B_DQ8")
	)
	(via
		(at 95.4532 -22.987)
		(size 0.4318)
		(drill 0.2032)
		(layers "F.Cu" "B.Cu")
		(net "M_B_DQ8")
	)
	(via
		(at 134.39648 -8.27405)
		(size 0.4318)
		(drill 0.2032)
		(layers "F.Cu" "B.Cu")
		(net "M_B_DQ8")
	)
	(segment
		(start 134.366 -8.561578)
		(end 134.366 -8.30453)
		(width 0.1778)
		(layer "B.Cu")
		(net "M_B_DQ8")
	)
	(segment
		(start 134.366 -8.30453)
		(end 134.39648 -8.27405)
		(width 0.1778)
		(layer "B.Cu")
		(net "M_B_DQ8")
	)
	(segment
		(start 133.75005 -9.89076)
		(end 133.75005 -9.177528)
		(width 0.1778)
		(layer "B.Cu")
		(net "M_B_DQ8")
	)
	(segment
		(start 133.75005 -9.177528)
		(end 134.366 -8.561578)
		(width 0.1778)
		(layer "B.Cu")
		(net "M_B_DQ8")
	)
	(segment
		(start 134.366 -8.763)
		(end 134.366 -8.30453)
		(width 0.1524)
		(layer "In2.Cu")
		(net "M_B_DQ8")
	)
	(segment
		(start 132.482082 -12.0904)
		(end 132.9436 -12.0904)
		(width 0.1524)
		(layer "In2.Cu")
		(net "M_B_DQ8")
	)
	(segment
		(start 106.173524 -16.0274)
		(end 109.881924 -12.319)
		(width 0.1524)
		(layer "In2.Cu")
		(net "M_B_DQ8")
	)
	(segment
		(start 134.366 -8.30453)
		(end 134.39648 -8.27405)
		(width 0.1524)
		(layer "In2.Cu")
		(net "M_B_DQ8")
	)
	(segment
		(start 99.23145 -16.0274)
		(end 106.173524 -16.0274)
		(width 0.1524)
		(layer "In2.Cu")
		(net "M_B_DQ8")
	)
	(segment
		(start 95.4532 -22.987)
		(end 94.96044 -22.49424)
		(width 0.1524)
		(layer "In2.Cu")
		(net "M_B_DQ8")
	)
	(segment
		(start 132.329682 -11.938)
		(end 132.482082 -12.0904)
		(width 0.1524)
		(layer "In2.Cu")
		(net "M_B_DQ8")
	)
	(segment
		(start 132.9436 -12.0904)
		(end 133.096 -11.938)
		(width 0.1524)
		(layer "In2.Cu")
		(net "M_B_DQ8")
	)
	(segment
		(start 109.881924 -12.319)
		(end 113.5634 -12.319)
		(width 0.1524)
		(layer "In2.Cu")
		(net "M_B_DQ8")
	)
	(segment
		(start 124.714 -12.319)
		(end 130.348482 -12.319)
		(width 0.1524)
		(layer "In2.Cu")
		(net "M_B_DQ8")
	)
	(segment
		(start 94.96044 -20.29841)
		(end 99.23145 -16.0274)
		(width 0.1524)
		(layer "In2.Cu")
		(net "M_B_DQ8")
	)
	(segment
		(start 133.096 -11.938)
		(end 133.096 -10.033)
		(width 0.1524)
		(layer "In2.Cu")
		(net "M_B_DQ8")
	)
	(segment
		(start 130.958082 -10.3632)
		(end 131.110482 -10.5156)
		(width 0.1524)
		(layer "In2.Cu")
		(net "M_B_DQ8")
	)
	(segment
		(start 131.720082 -12.1666)
		(end 131.720082 -10.5156)
		(width 0.1524)
		(layer "In2.Cu")
		(net "M_B_DQ8")
	)
	(segment
		(start 131.110482 -12.1666)
		(end 131.262882 -12.319)
		(width 0.1524)
		(layer "In2.Cu")
		(net "M_B_DQ8")
	)
	(segment
		(start 130.500882 -10.5156)
		(end 130.653282 -10.3632)
		(width 0.1524)
		(layer "In2.Cu")
		(net "M_B_DQ8")
	)
	(segment
		(start 130.348482 -12.319)
		(end 130.500882 -12.1666)
		(width 0.1524)
		(layer "In2.Cu")
		(net "M_B_DQ8")
	)
	(segment
		(start 131.720082 -10.5156)
		(end 131.872482 -10.3632)
		(width 0.1524)
		(layer "In2.Cu")
		(net "M_B_DQ8")
	)
	(segment
		(start 131.567682 -12.319)
		(end 131.720082 -12.1666)
		(width 0.1524)
		(layer "In2.Cu")
		(net "M_B_DQ8")
	)
	(segment
		(start 132.329682 -10.5156)
		(end 132.329682 -11.938)
		(width 0.1524)
		(layer "In2.Cu")
		(net "M_B_DQ8")
	)
	(segment
		(start 131.872482 -10.3632)
		(end 132.177282 -10.3632)
		(width 0.1524)
		(layer "In2.Cu")
		(net "M_B_DQ8")
	)
	(segment
		(start 131.262882 -12.319)
		(end 131.567682 -12.319)
		(width 0.1524)
		(layer "In2.Cu")
		(net "M_B_DQ8")
	)
	(segment
		(start 133.096 -10.033)
		(end 134.366 -8.763)
		(width 0.1524)
		(layer "In2.Cu")
		(net "M_B_DQ8")
	)
	(segment
		(start 94.96044 -22.49424)
		(end 94.96044 -20.29841)
		(width 0.1524)
		(layer "In2.Cu")
		(net "M_B_DQ8")
	)
	(segment
		(start 130.500882 -12.1666)
		(end 130.500882 -10.5156)
		(width 0.1524)
		(layer "In2.Cu")
		(net "M_B_DQ8")
	)
	(segment
		(start 122.4534 -10.0584)
		(end 124.714 -12.319)
		(width 0.1524)
		(layer "In2.Cu")
		(net "M_B_DQ8")
	)
	(segment
		(start 132.177282 -10.3632)
		(end 132.329682 -10.5156)
		(width 0.1524)
		(layer "In2.Cu")
		(net "M_B_DQ8")
	)
	(segment
		(start 115.824 -10.0584)
		(end 122.4534 -10.0584)
		(width 0.1524)
		(layer "In2.Cu")
		(net "M_B_DQ8")
	)
	(segment
		(start 130.653282 -10.3632)
		(end 130.958082 -10.3632)
		(width 0.1524)
		(layer "In2.Cu")
		(net "M_B_DQ8")
	)
	(segment
		(start 113.5634 -12.319)
		(end 115.824 -10.0584)
		(width 0.1524)
		(layer "In2.Cu")
		(net "M_B_DQ8")
	)
	(segment
		(start 131.110482 -10.5156)
		(end 131.110482 -12.1666)
		(width 0.1524)
		(layer "In2.Cu")
		(net "M_B_DQ8")
	)
	(segment
		(start 40.02786 -28.05557)
		(end 39.038022 -29.045408)
		(width 0.1143)
		(layer "F.Cu")
		(net "XDP_DFX_PORT6")
	)
	(segment
		(start 78.5368 -45.847)
		(end 78.76159 -45.62221)
		(width 0.1143)
		(layer "F.Cu")
		(net "XDP_DFX_PORT6")
	)
	(segment
		(start 79.703676 -45.62221)
		(end 79.78013 -45.698664)
		(width 0.1143)
		(layer "F.Cu")
		(net "XDP_DFX_PORT6")
	)
	(segment
		(start 39.038022 -29.045408)
		(end 39.038022 -31.700978)
		(width 0.1143)
		(layer "F.Cu")
		(net "XDP_DFX_PORT6")
	)
	(segment
		(start 79.78013 -45.698664)
		(end 80.3402 -45.698664)
		(width 0.1143)
		(layer "F.Cu")
		(net "XDP_DFX_PORT6")
	)
	(segment
		(start 78.76159 -45.62221)
		(end 79.703676 -45.62221)
		(width 0.1143)
		(layer "F.Cu")
		(net "XDP_DFX_PORT6")
	)
	(segment
		(start 80.3402 -45.698664)
		(end 80.62087 -45.417994)
		(width 0.1143)
		(layer "F.Cu")
		(net "XDP_DFX_PORT6")
	)
	(segment
		(start 80.62087 -45.417994)
		(end 80.950308 -45.417994)
		(width 0.1143)
		(layer "F.Cu")
		(net "XDP_DFX_PORT6")
	)
	(segment
		(start 42.10177 -28.05557)
		(end 40.02786 -28.05557)
		(width 0.1143)
		(layer "F.Cu")
		(net "XDP_DFX_PORT6")
	)
	(via
		(at 39.038022 -31.700978)
		(size 0.508)
		(drill 0.254)
		(layers "F.Cu" "B.Cu")
		(net "XDP_DFX_PORT6")
	)
	(via
		(at 40.003222 -31.69793)
		(size 0.7112)
		(drill 0.3556)
		(layers "F.Cu" "B.Cu")
		(net "XDP_DFX_PORT6")
	)
	(via
		(at 78.5368 -45.847)
		(size 0.508)
		(drill 0.254)
		(layers "F.Cu" "B.Cu")
		(net "XDP_DFX_PORT6")
	)
	(segment
		(start 39.04107 -31.69793)
		(end 39.038022 -31.700978)
		(width 0.1143)
		(layer "B.Cu")
		(net "XDP_DFX_PORT6")
	)
	(segment
		(start 40.003222 -31.69793)
		(end 39.04107 -31.69793)
		(width 0.1143)
		(layer "B.Cu")
		(net "XDP_DFX_PORT6")
	)
	(segment
		(start 49.840896 -39.61765)
		(end 45.687996 -35.46475)
		(width 0.0889)
		(layer "In7.Cu")
		(net "XDP_DFX_PORT6")
	)
	(segment
		(start 45.687996 -35.46475)
		(end 43.309032 -35.46475)
		(width 0.0889)
		(layer "In7.Cu")
		(net "XDP_DFX_PORT6")
	)
	(segment
		(start 52.000404 -39.37)
		(end 51.752754 -39.61765)
		(width 0.0889)
		(layer "In7.Cu")
		(net "XDP_DFX_PORT6")
	)
	(segment
		(start 43.309032 -35.46475)
		(end 39.54526 -31.700978)
		(width 0.0889)
		(layer "In7.Cu")
		(net "XDP_DFX_PORT6")
	)
	(segment
		(start 62.526926 -41.5925)
		(end 60.844176 -39.90975)
		(width 0.0889)
		(layer "In7.Cu")
		(net "XDP_DFX_PORT6")
	)
	(segment
		(start 66.6242 -44.047918)
		(end 66.6242 -43.465496)
		(width 0.0889)
		(layer "In7.Cu")
		(net "XDP_DFX_PORT6")
	)
	(segment
		(start 56.729376 -39.90975)
		(end 56.189626 -39.37)
		(width 0.0889)
		(layer "In7.Cu")
		(net "XDP_DFX_PORT6")
	)
	(segment
		(start 51.752754 -39.61765)
		(end 49.840896 -39.61765)
		(width 0.0889)
		(layer "In7.Cu")
		(net "XDP_DFX_PORT6")
	)
	(segment
		(start 60.844176 -39.90975)
		(end 56.729376 -39.90975)
		(width 0.0889)
		(layer "In7.Cu")
		(net "XDP_DFX_PORT6")
	)
	(segment
		(start 67.045332 -44.46905)
		(end 66.6242 -44.047918)
		(width 0.0889)
		(layer "In7.Cu")
		(net "XDP_DFX_PORT6")
	)
	(segment
		(start 56.189626 -39.37)
		(end 52.000404 -39.37)
		(width 0.0889)
		(layer "In7.Cu")
		(net "XDP_DFX_PORT6")
	)
	(segment
		(start 78.082902 -45.393102)
		(end 74.965814 -45.393102)
		(width 0.0889)
		(layer "In7.Cu")
		(net "XDP_DFX_PORT6")
	)
	(segment
		(start 78.5368 -45.847)
		(end 78.082902 -45.393102)
		(width 0.0889)
		(layer "In7.Cu")
		(net "XDP_DFX_PORT6")
	)
	(segment
		(start 39.54526 -31.700978)
		(end 39.038022 -31.700978)
		(width 0.0889)
		(layer "In7.Cu")
		(net "XDP_DFX_PORT6")
	)
	(segment
		(start 74.965814 -45.393102)
		(end 74.041762 -44.46905)
		(width 0.0889)
		(layer "In7.Cu")
		(net "XDP_DFX_PORT6")
	)
	(segment
		(start 66.6242 -43.465496)
		(end 64.751204 -41.5925)
		(width 0.0889)
		(layer "In7.Cu")
		(net "XDP_DFX_PORT6")
	)
	(segment
		(start 74.041762 -44.46905)
		(end 67.045332 -44.46905)
		(width 0.0889)
		(layer "In7.Cu")
		(net "XDP_DFX_PORT6")
	)
	(segment
		(start 64.751204 -41.5925)
		(end 62.526926 -41.5925)
		(width 0.0889)
		(layer "In7.Cu")
		(net "XDP_DFX_PORT6")
	)
	(via
		(at 33.0708 -45.3644)
		(size 0.7112)
		(drill 0.3556)
		(layers "F.Cu" "B.Cu")
		(net "P1V5_STBY_FB")
	)
	(segment
		(start 33.5788 -44.8564)
		(end 33.0708 -45.3644)
		(width 0.254)
		(layer "B.Cu")
		(net "P1V5_STBY_FB")
	)
	(segment
		(start 33.6042 -42.9514)
		(end 33.6042 -43.688)
		(width 0.254)
		(layer "B.Cu")
		(net "P1V5_STBY_FB")
	)
	(segment
		(start 32.162496 -46.272704)
		(end 31.719012 -46.272704)
		(width 0.254)
		(layer "B.Cu")
		(net "P1V5_STBY_FB")
	)
	(segment
		(start 33.5788 -43.7134)
		(end 33.5788 -44.45)
		(width 0.254)
		(layer "B.Cu")
		(net "P1V5_STBY_FB")
	)
	(segment
		(start 33.0708 -45.3644)
		(end 32.162496 -46.272704)
		(width 0.254)
		(layer "B.Cu")
		(net "P1V5_STBY_FB")
	)
	(segment
		(start 33.5788 -44.45)
		(end 33.5788 -44.8564)
		(width 0.254)
		(layer "B.Cu")
		(net "P1V5_STBY_FB")
	)
	(segment
		(start 33.6042 -43.688)
		(end 33.5788 -43.7134)
		(width 0.254)
		(layer "B.Cu")
		(net "P1V5_STBY_FB")
	)
	(segment
		(start 33.5788 -42.926)
		(end 33.6042 -42.9514)
		(width 0.254)
		(layer "B.Cu")
		(net "P1V5_STBY_FB")
	)
	(segment
		(start 191.056514 -31.575502)
		(end 191.056514 -30.939486)
		(width 0.2032)
		(layer "F.Cu")
		(net "VR_PVDDR_A_VDD")
	)
	(segment
		(start 194.7418 -36.2966)
		(end 194.7418 -35.814)
		(width 0.4572)
		(layer "F.Cu")
		(net "VR_PVDDR_A_VDD")
	)
	(segment
		(start 194.7164 -35.7886)
		(end 194.7164 -35.5092)
		(width 0.4572)
		(layer "F.Cu")
		(net "VR_PVDDR_A_VDD")
	)
	(segment
		(start 194.7418 -35.814)
		(end 194.7164 -35.7886)
		(width 0.4572)
		(layer "F.Cu")
		(net "VR_PVDDR_A_VDD")
	)
	(segment
		(start 183.9468 -27.5336)
		(end 183.9468 -26.4922)
		(width 0.508)
		(layer "F.Cu")
		(net "VR_PVDDR_A_VDD")
	)
	(segment
		(start 191.516 -30.48)
		(end 191.516 -29.2354)
		(width 0.508)
		(layer "F.Cu")
		(net "VR_PVDDR_A_VDD")
	)
	(segment
		(start 183.9468 -26.4922)
		(end 184.912 -26.4922)
		(width 0.508)
		(layer "F.Cu")
		(net "VR_PVDDR_A_VDD")
	)
	(segment
		(start 191.056514 -30.939486)
		(end 191.516 -30.48)
		(width 0.2032)
		(layer "F.Cu")
		(net "VR_PVDDR_A_VDD")
	)
	(segment
		(start 190.4492 -28.1686)
		(end 191.516 -29.2354)
		(width 0.508)
		(layer "F.Cu")
		(net "VR_PVDDR_A_VDD")
	)
	(via
		(at 183.9468 -26.4922)
		(size 0.7112)
		(drill 0.3556)
		(layers "F.Cu" "B.Cu")
		(net "VR_PVDDR_A_VDD")
	)
	(via
		(at 183.9468 -27.5336)
		(size 0.508)
		(drill 0.254)
		(layers "F.Cu" "B.Cu")
		(net "VR_PVDDR_A_VDD")
	)
	(via
		(at 191.516 -29.2354)
		(size 0.508)
		(drill 0.254)
		(layers "F.Cu" "B.Cu")
		(net "VR_PVDDR_A_VDD")
	)
	(via
		(at 194.7164 -35.5092)
		(size 0.508)
		(drill 0.254)
		(layers "F.Cu" "B.Cu")
		(net "VR_PVDDR_A_VDD")
	)
	(segment
		(start 191.516 -29.0068)
		(end 191.516 -29.2354)
		(width 0.508)
		(layer "B.Cu")
		(net "VR_PVDDR_A_VDD")
	)
	(segment
		(start 190.881 -28.3718)
		(end 191.516 -29.0068)
		(width 0.508)
		(layer "B.Cu")
		(net "VR_PVDDR_A_VDD")
	)
	(segment
		(start 192.6336 -35.4076)
		(end 191.643 -34.417)
		(width 0.508)
		(layer "In7.Cu")
		(net "VR_PVDDR_A_VDD")
	)
	(segment
		(start 184.277 -27.8638)
		(end 183.9468 -27.5336)
		(width 0.508)
		(layer "In7.Cu")
		(net "VR_PVDDR_A_VDD")
	)
	(segment
		(start 194.7164 -35.5092)
		(end 194.6148 -35.4076)
		(width 0.508)
		(layer "In7.Cu")
		(net "VR_PVDDR_A_VDD")
	)
	(segment
		(start 191.516 -29.2354)
		(end 190.1444 -27.8638)
		(width 0.508)
		(layer "In7.Cu")
		(net "VR_PVDDR_A_VDD")
	)
	(segment
		(start 191.643 -34.417)
		(end 191.643 -29.3624)
		(width 0.508)
		(layer "In7.Cu")
		(net "VR_PVDDR_A_VDD")
	)
	(segment
		(start 194.6148 -35.4076)
		(end 192.6336 -35.4076)
		(width 0.508)
		(layer "In7.Cu")
		(net "VR_PVDDR_A_VDD")
	)
	(segment
		(start 191.643 -29.3624)
		(end 191.516 -29.2354)
		(width 0.508)
		(layer "In7.Cu")
		(net "VR_PVDDR_A_VDD")
	)
	(segment
		(start 190.1444 -27.8638)
		(end 184.277 -27.8638)
		(width 0.508)
		(layer "In7.Cu")
		(net "VR_PVDDR_A_VDD")
	)
	(segment
		(start 147.54987 -1.68402)
		(end 147.54987 -2.469388)
		(width 0.1778)
		(layer "F.Cu")
		(net "M_B_DQ31")
	)
	(segment
		(start 147.54987 -2.469388)
		(end 147.99437 -2.913888)
		(width 0.1778)
		(layer "F.Cu")
		(net "M_B_DQ31")
	)
	(segment
		(start 97.605088 -32.283654)
		(end 97.605088 -32.201104)
		(width 0.1016)
		(layer "F.Cu")
		(net "M_B_DQ31")
	)
	(segment
		(start 97.605088 -32.201104)
		(end 97.911666 -31.894526)
		(width 0.1016)
		(layer "F.Cu")
		(net "M_B_DQ31")
	)
	(segment
		(start 147.99437 -2.913888)
		(end 147.99437 -3.151378)
		(width 0.1778)
		(layer "F.Cu")
		(net "M_B_DQ31")
	)
	(via
		(at 97.911666 -31.894526)
		(size 0.4318)
		(drill 0.2032)
		(layers "F.Cu" "B.Cu")
		(net "M_B_DQ31")
	)
	(via
		(at 147.99437 -3.151378)
		(size 0.4318)
		(drill 0.2032)
		(layers "F.Cu" "B.Cu")
		(net "M_B_DQ31")
	)
	(segment
		(start 147.99437 -2.901188)
		(end 147.99437 -3.151378)
		(width 0.1778)
		(layer "B.Cu")
		(net "M_B_DQ31")
	)
	(segment
		(start 148.450046 -2.445512)
		(end 147.99437 -2.901188)
		(width 0.1778)
		(layer "B.Cu")
		(net "M_B_DQ31")
	)
	(segment
		(start 148.450046 -1.690624)
		(end 148.450046 -2.445512)
		(width 0.1778)
		(layer "B.Cu")
		(net "M_B_DQ31")
	)
	(segment
		(start 147.345654 -20.917408)
		(end 146.266662 -21.9964)
		(width 0.1524)
		(layer "In4.Cu")
		(net "M_B_DQ31")
	)
	(segment
		(start 116.329206 -21.9964)
		(end 115.3922 -21.9964)
		(width 0.1524)
		(layer "In4.Cu")
		(net "M_B_DQ31")
	)
	(segment
		(start 148.45157 -6.147054)
		(end 147.2692 -7.329424)
		(width 0.1524)
		(layer "In4.Cu")
		(net "M_B_DQ31")
	)
	(segment
		(start 115.3922 -21.9964)
		(end 113.1316 -24.257)
		(width 0.1524)
		(layer "In4.Cu")
		(net "M_B_DQ31")
	)
	(segment
		(start 100.900484 -28.922472)
		(end 102.1969 -28.922472)
		(width 0.1016)
		(layer "In4.Cu")
		(net "M_B_DQ31")
	)
	(segment
		(start 110.0328 -24.257)
		(end 108.6612 -25.6286)
		(width 0.1524)
		(layer "In4.Cu")
		(net "M_B_DQ31")
	)
	(segment
		(start 97.959926 -31.894526)
		(end 99.416362 -30.43809)
		(width 0.1016)
		(layer "In4.Cu")
		(net "M_B_DQ31")
	)
	(segment
		(start 147.2692 -8.019542)
		(end 147.574 -8.324342)
		(width 0.1524)
		(layer "In4.Cu")
		(net "M_B_DQ31")
	)
	(segment
		(start 102.412546 -28.346654)
		(end 102.5652 -28.194)
		(width 0.1016)
		(layer "In4.Cu")
		(net "M_B_DQ31")
	)
	(segment
		(start 148.45157 -3.608578)
		(end 148.45157 -6.147054)
		(width 0.1524)
		(layer "In4.Cu")
		(net "M_B_DQ31")
	)
	(segment
		(start 146.266662 -21.9964)
		(end 146.014948 -21.9964)
		(width 0.1524)
		(layer "In4.Cu")
		(net "M_B_DQ31")
	)
	(segment
		(start 117.091206 -22.352)
		(end 116.938806 -22.5044)
		(width 0.1524)
		(layer "In4.Cu")
		(net "M_B_DQ31")
	)
	(segment
		(start 117.243606 -21.9964)
		(end 117.091206 -22.1488)
		(width 0.1524)
		(layer "In4.Cu")
		(net "M_B_DQ31")
	)
	(segment
		(start 108.233464 -25.6286)
		(end 107.16641 -26.6954)
		(width 0.1524)
		(layer "In4.Cu")
		(net "M_B_DQ31")
	)
	(segment
		(start 100.063808 -29.605478)
		(end 100.735384 -28.933902)
		(width 0.1016)
		(layer "In4.Cu")
		(net "M_B_DQ31")
	)
	(segment
		(start 105.504996 -27.84475)
		(end 102.91445 -27.84475)
		(width 0.1524)
		(layer "In4.Cu")
		(net "M_B_DQ31")
	)
	(segment
		(start 116.481606 -22.1488)
		(end 116.329206 -21.9964)
		(width 0.1524)
		(layer "In4.Cu")
		(net "M_B_DQ31")
	)
	(segment
		(start 147.574 -8.324342)
		(end 147.574 -8.790178)
		(width 0.1524)
		(layer "In4.Cu")
		(net "M_B_DQ31")
	)
	(segment
		(start 147.574 -8.790178)
		(end 147.345654 -9.018524)
		(width 0.1524)
		(layer "In4.Cu")
		(net "M_B_DQ31")
	)
	(segment
		(start 145.531078 -21.996654)
		(end 145.530824 -21.9964)
		(width 0.1524)
		(layer "In4.Cu")
		(net "M_B_DQ31")
	)
	(segment
		(start 147.99437 -3.151378)
		(end 148.45157 -3.608578)
		(width 0.1524)
		(layer "In4.Cu")
		(net "M_B_DQ31")
	)
	(segment
		(start 97.911666 -31.894526)
		(end 97.959926 -31.894526)
		(width 0.1016)
		(layer "In4.Cu")
		(net "M_B_DQ31")
	)
	(segment
		(start 99.416362 -29.782516)
		(end 99.5934 -29.605478)
		(width 0.1016)
		(layer "In4.Cu")
		(net "M_B_DQ31")
	)
	(segment
		(start 145.530824 -21.9964)
		(end 117.243606 -21.9964)
		(width 0.1524)
		(layer "In4.Cu")
		(net "M_B_DQ31")
	)
	(segment
		(start 100.889054 -28.933902)
		(end 100.900484 -28.922472)
		(width 0.1016)
		(layer "In4.Cu")
		(net "M_B_DQ31")
	)
	(segment
		(start 116.634006 -22.5044)
		(end 116.481606 -22.352)
		(width 0.1524)
		(layer "In4.Cu")
		(net "M_B_DQ31")
	)
	(segment
		(start 146.014948 -21.9964)
		(end 146.014694 -21.996654)
		(width 0.1524)
		(layer "In4.Cu")
		(net "M_B_DQ31")
	)
	(segment
		(start 108.6612 -25.6286)
		(end 108.233464 -25.6286)
		(width 0.1524)
		(layer "In4.Cu")
		(net "M_B_DQ31")
	)
	(segment
		(start 107.16641 -26.6954)
		(end 106.6546 -26.6954)
		(width 0.1524)
		(layer "In4.Cu")
		(net "M_B_DQ31")
	)
	(segment
		(start 99.416362 -30.43809)
		(end 99.416362 -29.782516)
		(width 0.1016)
		(layer "In4.Cu")
		(net "M_B_DQ31")
	)
	(segment
		(start 113.1316 -24.257)
		(end 110.0328 -24.257)
		(width 0.1524)
		(layer "In4.Cu")
		(net "M_B_DQ31")
	)
	(segment
		(start 102.91445 -27.84475)
		(end 102.5652 -28.194)
		(width 0.1524)
		(layer "In4.Cu")
		(net "M_B_DQ31")
	)
	(segment
		(start 102.412546 -28.706826)
		(end 102.412546 -28.346654)
		(width 0.1016)
		(layer "In4.Cu")
		(net "M_B_DQ31")
	)
	(segment
		(start 100.735384 -28.933902)
		(end 100.889054 -28.933902)
		(width 0.1016)
		(layer "In4.Cu")
		(net "M_B_DQ31")
	)
	(segment
		(start 146.014694 -21.996654)
		(end 145.531078 -21.996654)
		(width 0.1524)
		(layer "In4.Cu")
		(net "M_B_DQ31")
	)
	(segment
		(start 117.091206 -22.1488)
		(end 117.091206 -22.352)
		(width 0.1524)
		(layer "In4.Cu")
		(net "M_B_DQ31")
	)
	(segment
		(start 102.1969 -28.922472)
		(end 102.412546 -28.706826)
		(width 0.1016)
		(layer "In4.Cu")
		(net "M_B_DQ31")
	)
	(segment
		(start 116.481606 -22.352)
		(end 116.481606 -22.1488)
		(width 0.1524)
		(layer "In4.Cu")
		(net "M_B_DQ31")
	)
	(segment
		(start 147.345654 -9.018524)
		(end 147.345654 -20.917408)
		(width 0.1524)
		(layer "In4.Cu")
		(net "M_B_DQ31")
	)
	(segment
		(start 116.938806 -22.5044)
		(end 116.634006 -22.5044)
		(width 0.1524)
		(layer "In4.Cu")
		(net "M_B_DQ31")
	)
	(segment
		(start 106.6546 -26.6954)
		(end 105.504996 -27.84475)
		(width 0.1524)
		(layer "In4.Cu")
		(net "M_B_DQ31")
	)
	(segment
		(start 99.5934 -29.605478)
		(end 100.063808 -29.605478)
		(width 0.1016)
		(layer "In4.Cu")
		(net "M_B_DQ31")
	)
	(segment
		(start 147.2692 -7.329424)
		(end 147.2692 -8.019542)
		(width 0.1524)
		(layer "In4.Cu")
		(net "M_B_DQ31")
	)
	(segment
		(start 76.858114 -44.198286)
		(end 76.708 -44.3484)
		(width 0.1143)
		(layer "F.Cu")
		(net "XDP_DFX_PORT7")
	)
	(segment
		(start 80.3402 -45.076364)
		(end 80.089756 -45.076364)
		(width 0.1143)
		(layer "F.Cu")
		(net "XDP_DFX_PORT7")
	)
	(segment
		(start 81.03743 -44.818554)
		(end 80.73644 -45.119544)
		(width 0.1143)
		(layer "F.Cu")
		(net "XDP_DFX_PORT7")
	)
	(segment
		(start 81.768188 -44.818554)
		(end 81.03743 -44.818554)
		(width 0.1143)
		(layer "F.Cu")
		(net "XDP_DFX_PORT7")
	)
	(segment
		(start 77.702156 -44.751244)
		(end 77.4446 -45.0088)
		(width 0.1143)
		(layer "F.Cu")
		(net "XDP_DFX_PORT7")
	)
	(segment
		(start 80.089756 -45.076364)
		(end 79.764636 -44.751244)
		(width 0.1143)
		(layer "F.Cu")
		(net "XDP_DFX_PORT7")
	)
	(segment
		(start 40.48252 -28.49372)
		(end 40.20947 -28.49372)
		(width 0.1143)
		(layer "F.Cu")
		(net "XDP_DFX_PORT7")
	)
	(segment
		(start 40.54348 -28.55468)
		(end 40.48252 -28.49372)
		(width 0.1143)
		(layer "F.Cu")
		(net "XDP_DFX_PORT7")
	)
	(segment
		(start 76.708 -44.7548)
		(end 76.962 -45.0088)
		(width 0.1143)
		(layer "F.Cu")
		(net "XDP_DFX_PORT7")
	)
	(segment
		(start 76.858114 -44.172124)
		(end 76.858114 -44.198286)
		(width 0.1143)
		(layer "F.Cu")
		(net "XDP_DFX_PORT7")
	)
	(segment
		(start 80.73644 -45.119544)
		(end 80.38338 -45.119544)
		(width 0.1143)
		(layer "F.Cu")
		(net "XDP_DFX_PORT7")
	)
	(segment
		(start 77.4446 -45.0088)
		(end 76.962 -45.0088)
		(width 0.1143)
		(layer "F.Cu")
		(net "XDP_DFX_PORT7")
	)
	(segment
		(start 80.38338 -45.119544)
		(end 80.3402 -45.076364)
		(width 0.1143)
		(layer "F.Cu")
		(net "XDP_DFX_PORT7")
	)
	(segment
		(start 79.764636 -44.751244)
		(end 77.702156 -44.751244)
		(width 0.1143)
		(layer "F.Cu")
		(net "XDP_DFX_PORT7")
	)
	(segment
		(start 42.10177 -28.55468)
		(end 40.54348 -28.55468)
		(width 0.1143)
		(layer "F.Cu")
		(net "XDP_DFX_PORT7")
	)
	(segment
		(start 76.708 -44.3484)
		(end 76.708 -44.7548)
		(width 0.1143)
		(layer "F.Cu")
		(net "XDP_DFX_PORT7")
	)
	(via
		(at 76.858114 -44.172124)
		(size 0.508)
		(drill 0.254)
		(layers "F.Cu" "B.Cu")
		(net "XDP_DFX_PORT7")
	)
	(via
		(at 40.20947 -28.49372)
		(size 0.508)
		(drill 0.254)
		(layers "F.Cu" "B.Cu")
		(net "XDP_DFX_PORT7")
	)
	(via
		(at 76.962 -45.0088)
		(size 0.7112)
		(drill 0.3556)
		(layers "F.Cu" "B.Cu")
		(net "XDP_DFX_PORT7")
	)
	(segment
		(start 67.215512 -40.12565)
		(end 68.017644 -40.12565)
		(width 0.0889)
		(layer "In7.Cu")
		(net "XDP_DFX_PORT7")
	)
	(segment
		(start 69.17055 -41.665144)
		(end 69.930772 -42.425366)
		(width 0.0889)
		(layer "In7.Cu")
		(net "XDP_DFX_PORT7")
	)
	(segment
		(start 74.179938 -42.425366)
		(end 75.829922 -44.07535)
		(width 0.0889)
		(layer "In7.Cu")
		(net "XDP_DFX_PORT7")
	)
	(segment
		(start 40.8178 -29.10205)
		(end 40.8178 -30.004258)
		(width 0.0889)
		(layer "In7.Cu")
		(net "XDP_DFX_PORT7")
	)
	(segment
		(start 48.521874 -35.1536)
		(end 50.59553 -37.227256)
		(width 0.0889)
		(layer "In7.Cu")
		(net "XDP_DFX_PORT7")
	)
	(segment
		(start 40.8178 -30.004258)
		(end 44.639992 -33.82645)
		(width 0.0889)
		(layer "In7.Cu")
		(net "XDP_DFX_PORT7")
	)
	(segment
		(start 44.639992 -33.82645)
		(end 46.133512 -33.82645)
		(width 0.0889)
		(layer "In7.Cu")
		(net "XDP_DFX_PORT7")
	)
	(segment
		(start 56.130698 -37.227256)
		(end 57.289192 -38.38575)
		(width 0.0889)
		(layer "In7.Cu")
		(net "XDP_DFX_PORT7")
	)
	(segment
		(start 76.76134 -44.07535)
		(end 76.858114 -44.172124)
		(width 0.0889)
		(layer "In7.Cu")
		(net "XDP_DFX_PORT7")
	)
	(segment
		(start 68.017644 -40.12565)
		(end 69.17055 -41.278556)
		(width 0.0889)
		(layer "In7.Cu")
		(net "XDP_DFX_PORT7")
	)
	(segment
		(start 40.20947 -28.49372)
		(end 40.8178 -29.10205)
		(width 0.0889)
		(layer "In7.Cu")
		(net "XDP_DFX_PORT7")
	)
	(segment
		(start 69.930772 -42.425366)
		(end 74.179938 -42.425366)
		(width 0.0889)
		(layer "In7.Cu")
		(net "XDP_DFX_PORT7")
	)
	(segment
		(start 46.133512 -33.82645)
		(end 47.460662 -35.1536)
		(width 0.0889)
		(layer "In7.Cu")
		(net "XDP_DFX_PORT7")
	)
	(segment
		(start 50.59553 -37.227256)
		(end 56.130698 -37.227256)
		(width 0.0889)
		(layer "In7.Cu")
		(net "XDP_DFX_PORT7")
	)
	(segment
		(start 65.475612 -38.38575)
		(end 67.215512 -40.12565)
		(width 0.0889)
		(layer "In7.Cu")
		(net "XDP_DFX_PORT7")
	)
	(segment
		(start 69.17055 -41.278556)
		(end 69.17055 -41.665144)
		(width 0.0889)
		(layer "In7.Cu")
		(net "XDP_DFX_PORT7")
	)
	(segment
		(start 47.460662 -35.1536)
		(end 48.521874 -35.1536)
		(width 0.0889)
		(layer "In7.Cu")
		(net "XDP_DFX_PORT7")
	)
	(segment
		(start 57.289192 -38.38575)
		(end 65.475612 -38.38575)
		(width 0.0889)
		(layer "In7.Cu")
		(net "XDP_DFX_PORT7")
	)
	(segment
		(start 75.829922 -44.07535)
		(end 76.76134 -44.07535)
		(width 0.0889)
		(layer "In7.Cu")
		(net "XDP_DFX_PORT7")
	)
	(segment
		(start 8.151876 -34.948876)
		(end 7.747 -34.544)
		(width 0.254)
		(layer "F.Cu")
		(net "P3V3_STBY_MODE")
	)
	(segment
		(start 6.096 -32.4358)
		(end 6.096 -33.2486)
		(width 0.254)
		(layer "F.Cu")
		(net "P3V3_STBY_MODE")
	)
	(segment
		(start 6.709664 -33.862264)
		(end 6.938264 -33.862264)
		(width 0.254)
		(layer "F.Cu")
		(net "P3V3_STBY_MODE")
	)
	(segment
		(start 6.096 -33.2486)
		(end 6.2992 -33.4518)
		(width 0.254)
		(layer "F.Cu")
		(net "P3V3_STBY_MODE")
	)
	(segment
		(start 7.747 -34.544)
		(end 7.62 -34.544)
		(width 0.254)
		(layer "F.Cu")
		(net "P3V3_STBY_MODE")
	)
	(segment
		(start 6.2992 -33.4518)
		(end 6.709664 -33.862264)
		(width 0.254)
		(layer "F.Cu")
		(net "P3V3_STBY_MODE")
	)
	(segment
		(start 8.726678 -34.948876)
		(end 8.151876 -34.948876)
		(width 0.254)
		(layer "F.Cu")
		(net "P3V3_STBY_MODE")
	)
	(segment
		(start 6.938264 -33.862264)
		(end 7.62 -34.544)
		(width 0.254)
		(layer "F.Cu")
		(net "P3V3_STBY_MODE")
	)
	(via
		(at 7.62 -34.544)
		(size 0.508)
		(drill 0.254)
		(layers "F.Cu" "B.Cu")
		(net "P3V3_STBY_MODE")
	)
	(via
		(at 6.2992 -33.4518)
		(size 0.7112)
		(drill 0.3556)
		(layers "F.Cu" "B.Cu")
		(net "P3V3_STBY_MODE")
	)
	(segment
		(start 7.62 -34.544)
		(end 7.62 -32.893)
		(width 0.254)
		(layer "B.Cu")
		(net "P3V3_STBY_MODE")
	)
	(segment
		(start 7.2898 -32.5628)
		(end 6.604 -32.5628)
		(width 0.254)
		(layer "B.Cu")
		(net "P3V3_STBY_MODE")
	)
	(segment
		(start 7.62 -32.893)
		(end 7.2898 -32.5628)
		(width 0.254)
		(layer "B.Cu")
		(net "P3V3_STBY_MODE")
	)
	(segment
		(start 96.350074 -6.195568)
		(end 96.350074 -9.507474)
		(width 0.7112)
		(layer "F.Cu")
		(net "P12V")
	)
	(segment
		(start 193.4718 -30.988)
		(end 193.4718 -29.4132)
		(width 0.508)
		(layer "F.Cu")
		(net "P12V")
	)
	(segment
		(start 64.897 -23.6982)
		(end 64.897 -23.277576)
		(width 0.3048)
		(layer "F.Cu")
		(net "P12V")
	)
	(segment
		(start 58.59272 -43.64228)
		(end 59.161934 -43.073066)
		(width 0.3048)
		(layer "F.Cu")
		(net "P12V")
	)
	(segment
		(start 62.5348 -21.6408)
		(end 62.8396 -21.9456)
		(width 0.3048)
		(layer "F.Cu")
		(net "P12V")
	)
	(segment
		(start 57.658 -46.273212)
		(end 58.3184 -45.612812)
		(width 0.3048)
		(layer "F.Cu")
		(net "P12V")
	)
	(segment
		(start 64.897 -23.277576)
		(end 64.39408 -22.774656)
		(width 0.3048)
		(layer "F.Cu")
		(net "P12V")
	)
	(segment
		(start 96.52 -9.6774)
		(end 97.1296 -9.6774)
		(width 0.7112)
		(layer "F.Cu")
		(net "P12V")
	)
	(segment
		(start 63.565024 -21.9456)
		(end 64.39408 -22.774656)
		(width 0.3048)
		(layer "F.Cu")
		(net "P12V")
	)
	(segment
		(start 200.152 -22.225)
		(end 197.358 -22.225)
		(width 0.508)
		(layer "F.Cu")
		(net "P12V")
	)
	(segment
		(start 57.6072 -46.609)
		(end 56.0578 -46.609)
		(width 0.3048)
		(layer "F.Cu")
		(net "P12V")
	)
	(segment
		(start 194.564 -25.019)
		(end 194.564 -28.321)
		(width 0.508)
		(layer "F.Cu")
		(net "P12V")
	)
	(segment
		(start 15.349982 -9.652)
		(end 15.349982 -10.269982)
		(width 0.7112)
		(layer "F.Cu")
		(net "P12V")
	)
	(segment
		(start 59.161934 -43.073066)
		(end 59.161934 -42.54627)
		(width 0.3048)
		(layer "F.Cu")
		(net "P12V")
	)
	(segment
		(start 96.350074 -9.507474)
		(end 96.52 -9.6774)
		(width 0.7112)
		(layer "F.Cu")
		(net "P12V")
	)
	(segment
		(start 193.4718 -29.4132)
		(end 194.437 -28.448)
		(width 0.508)
		(layer "F.Cu")
		(net "P12V")
	)
	(segment
		(start 15.349982 -10.269982)
		(end 16.129 -11.049)
		(width 0.7112)
		(layer "F.Cu")
		(net "P12V")
	)
	(segment
		(start 15.349982 -6.195568)
		(end 15.349982 -9.652)
		(width 0.7112)
		(layer "F.Cu")
		(net "P12V")
	)
	(segment
		(start 59.161934 -41.853866)
		(end 59.161934 -42.54627)
		(width 0.3048)
		(layer "F.Cu")
		(net "P12V")
	)
	(segment
		(start 97.350072 -9.456928)
		(end 97.350072 -6.195568)
		(width 0.7112)
		(layer "F.Cu")
		(net "P12V")
	)
	(segment
		(start 16.34998 -6.195568)
		(end 16.34998 -8.652002)
		(width 0.7112)
		(layer "F.Cu")
		(net "P12V")
	)
	(segment
		(start 55.9816 -45.7708)
		(end 55.9816 -45.2374)
		(width 0.3048)
		(layer "F.Cu")
		(net "P12V")
	)
	(segment
		(start 58.3184 -45.593)
		(end 58.59272 -45.31868)
		(width 0.3048)
		(layer "F.Cu")
		(net "P12V")
	)
	(segment
		(start 194.564 -28.321)
		(end 194.437 -28.448)
		(width 0.508)
		(layer "F.Cu")
		(net "P12V")
	)
	(segment
		(start 57.658 -46.5582)
		(end 57.6072 -46.609)
		(width 0.3048)
		(layer "F.Cu")
		(net "P12V")
	)
	(segment
		(start 97.1296 -9.6774)
		(end 97.350072 -9.456928)
		(width 0.7112)
		(layer "F.Cu")
		(net "P12V")
	)
	(segment
		(start 58.3184 -45.612812)
		(end 58.3184 -45.593)
		(width 0.3048)
		(layer "F.Cu")
		(net "P12V")
	)
	(segment
		(start 56.0578 -45.847)
		(end 55.9816 -45.7708)
		(width 0.3048)
		(layer "F.Cu")
		(net "P12V")
	)
	(segment
		(start 59.2328 -41.783)
		(end 59.161934 -41.853866)
		(width 0.3048)
		(layer "F.Cu")
		(net "P12V")
	)
	(segment
		(start 197.358 -22.225)
		(end 194.564 -25.019)
		(width 0.508)
		(layer "F.Cu")
		(net "P12V")
	)
	(segment
		(start 55.9816 -45.2374)
		(end 55.753 -45.0088)
		(width 0.3048)
		(layer "F.Cu")
		(net "P12V")
	)
	(segment
		(start 16.34998 -8.652002)
		(end 15.349982 -9.652)
		(width 0.7112)
		(layer "F.Cu")
		(net "P12V")
	)
	(segment
		(start 56.0578 -46.609)
		(end 56.0578 -45.847)
		(width 0.3048)
		(layer "F.Cu")
		(net "P12V")
	)
	(segment
		(start 58.59272 -45.31868)
		(end 58.59272 -43.64228)
		(width 0.3048)
		(layer "F.Cu")
		(net "P12V")
	)
	(segment
		(start 62.168786 -21.6408)
		(end 62.5348 -21.6408)
		(width 0.3048)
		(layer "F.Cu")
		(net "P12V")
	)
	(segment
		(start 57.658 -46.5582)
		(end 57.658 -46.273212)
		(width 0.3048)
		(layer "F.Cu")
		(net "P12V")
	)
	(segment
		(start 62.8396 -21.9456)
		(end 63.565024 -21.9456)
		(width 0.3048)
		(layer "F.Cu")
		(net "P12V")
	)
	(segment
		(start 16.637 -31.4452)
		(end 15.24 -31.4452)
		(width 0.3048)
		(layer "F.Cu")
		(net "P12V")
	)
	(via
		(at 17.399 -12.065)
		(size 0.7112)
		(drill 0.4064)
		(layers "F.Cu" "B.Cu")
		(net "P12V")
	)
	(via
		(at 202.311 -21.082)
		(size 0.7112)
		(drill 0.4064)
		(layers "F.Cu" "B.Cu")
		(net "P12V")
	)
	(via
		(at 17.4752 -14.8336)
		(size 0.7112)
		(drill 0.3556)
		(layers "F.Cu" "B.Cu")
		(net "P12V")
	)
	(via
		(at 84.201 -70.802754)
		(size 0.7112)
		(drill 0.4064)
		(layers "F.Cu" "B.Cu")
		(net "P12V")
	)
	(via
		(at 64.39408 -22.774656)
		(size 0.7112)
		(drill 0.3556)
		(layers "F.Cu" "B.Cu")
		(net "P12V")
	)
	(via
		(at 2.7686 -29.972)
		(size 0.7112)
		(drill 0.4064)
		(layers "F.Cu" "B.Cu")
		(net "P12V")
	)
	(via
		(at 18.669 -12.192)
		(size 0.7112)
		(drill 0.4064)
		(layers "F.Cu" "B.Cu")
		(net "P12V")
	)
	(via
		(at 96.59493 -11.881866)
		(size 0.7112)
		(drill 0.4064)
		(layers "F.Cu" "B.Cu")
		(net "P12V")
	)
	(via
		(at 2.667 -32.385)
		(size 0.7112)
		(drill 0.4064)
		(layers "F.Cu" "B.Cu")
		(net "P12V")
	)
	(via
		(at 70.6628 -71.4629)
		(size 0.7112)
		(drill 0.4064)
		(layers "F.Cu" "B.Cu")
		(net "P12V")
	)
	(via
		(at 2.921 -40.386)
		(size 0.7112)
		(drill 0.4064)
		(layers "F.Cu" "B.Cu")
		(net "P12V")
	)
	(via
		(at 96.52 -9.6774)
		(size 0.7112)
		(drill 0.4064)
		(layers "F.Cu" "B.Cu")
		(net "P12V")
	)
	(via
		(at 59.161934 -42.54627)
		(size 0.508)
		(drill 0.254)
		(layers "F.Cu" "B.Cu")
		(net "P12V")
	)
	(via
		(at 192.532762 -35.890962)
		(size 0.7112)
		(drill 0.3556)
		(layers "F.Cu" "B.Cu")
		(net "P12V")
	)
	(via
		(at 27.051 -72.5297)
		(size 0.7112)
		(drill 0.4064)
		(layers "F.Cu" "B.Cu")
		(net "P12V")
	)
	(via
		(at 194.437 -28.448)
		(size 0.508)
		(drill 0.254)
		(layers "F.Cu" "B.Cu")
		(net "P12V")
	)
	(via
		(at 201.168 -22.2758)
		(size 0.7112)
		(drill 0.4064)
		(layers "F.Cu" "B.Cu")
		(net "P12V")
	)
	(via
		(at 37.4396 -15.3416)
		(size 0.508)
		(drill 0.254)
		(layers "F.Cu" "B.Cu")
		(net "P12V")
	)
	(via
		(at 3.937 -31.1912)
		(size 0.7112)
		(drill 0.4064)
		(layers "F.Cu" "B.Cu")
		(net "P12V")
	)
	(via
		(at 205.7654 -67.904106)
		(size 0.7112)
		(drill 0.4064)
		(layers "F.Cu" "B.Cu")
		(net "P12V")
	)
	(via
		(at 23.5712 -72.5424)
		(size 0.7112)
		(drill 0.4064)
		(layers "F.Cu" "B.Cu")
		(net "P12V")
	)
	(via
		(at 71.802244 -71.459344)
		(size 0.7112)
		(drill 0.4064)
		(layers "F.Cu" "B.Cu")
		(net "P12V")
	)
	(via
		(at 94.361 -11.938)
		(size 0.7112)
		(drill 0.4064)
		(layers "F.Cu" "B.Cu")
		(net "P12V")
	)
	(via
		(at 205.7654 -69.85)
		(size 0.7112)
		(drill 0.4064)
		(layers "F.Cu" "B.Cu")
		(net "P12V")
	)
	(via
		(at 202.311 -22.2758)
		(size 0.7112)
		(drill 0.4064)
		(layers "F.Cu" "B.Cu")
		(net "P12V")
	)
	(via
		(at 1.778 -40.386)
		(size 0.7112)
		(drill 0.4064)
		(layers "F.Cu" "B.Cu")
		(net "P12V")
	)
	(via
		(at 57.658 -46.5582)
		(size 0.7112)
		(drill 0.3556)
		(layers "F.Cu" "B.Cu")
		(net "P12V")
	)
	(via
		(at 25.908 -72.5043)
		(size 0.7112)
		(drill 0.4064)
		(layers "F.Cu" "B.Cu")
		(net "P12V")
	)
	(via
		(at 72.9615 -68.3895)
		(size 0.508)
		(drill 0.254)
		(layers "F.Cu" "B.Cu")
		(net "P12V")
	)
	(via
		(at 17.272 -13.335)
		(size 0.7112)
		(drill 0.4064)
		(layers "F.Cu" "B.Cu")
		(net "P12V")
	)
	(via
		(at 16.129 -13.335)
		(size 0.7112)
		(drill 0.4064)
		(layers "F.Cu" "B.Cu")
		(net "P12V")
	)
	(via
		(at 16.129 -12.192)
		(size 0.7112)
		(drill 0.4064)
		(layers "F.Cu" "B.Cu")
		(net "P12V")
	)
	(via
		(at 28.1178 -72.5297)
		(size 0.7112)
		(drill 0.4064)
		(layers "F.Cu" "B.Cu")
		(net "P12V")
	)
	(via
		(at 24.765 -72.5043)
		(size 0.7112)
		(drill 0.4064)
		(layers "F.Cu" "B.Cu")
		(net "P12V")
	)
	(via
		(at 206.248 -66.929)
		(size 0.7112)
		(drill 0.4064)
		(layers "F.Cu" "B.Cu")
		(net "P12V")
	)
	(via
		(at 95.4024 -10.795)
		(size 0.7112)
		(drill 0.4064)
		(layers "F.Cu" "B.Cu")
		(net "P12V")
	)
	(via
		(at 2.921 -41.5798)
		(size 0.7112)
		(drill 0.4064)
		(layers "F.Cu" "B.Cu")
		(net "P12V")
	)
	(via
		(at 16.129 -11.049)
		(size 0.7112)
		(drill 0.4064)
		(layers "F.Cu" "B.Cu")
		(net "P12V")
	)
	(via
		(at 2.794 -31.1912)
		(size 0.7112)
		(drill 0.4064)
		(layers "F.Cu" "B.Cu")
		(net "P12V")
	)
	(via
		(at 96.5962 -10.795)
		(size 0.7112)
		(drill 0.4064)
		(layers "F.Cu" "B.Cu")
		(net "P12V")
	)
	(via
		(at 94.3356 -10.795)
		(size 0.7112)
		(drill 0.4064)
		(layers "F.Cu" "B.Cu")
		(net "P12V")
	)
	(via
		(at 3.81 -32.385)
		(size 0.7112)
		(drill 0.4064)
		(layers "F.Cu" "B.Cu")
		(net "P12V")
	)
	(via
		(at 3.9116 -29.972)
		(size 0.7112)
		(drill 0.4064)
		(layers "F.Cu" "B.Cu")
		(net "P12V")
	)
	(via
		(at 62.168786 -21.6408)
		(size 0.508)
		(drill 0.254)
		(layers "F.Cu" "B.Cu")
		(net "P12V")
	)
	(via
		(at 95.4278 -11.938)
		(size 0.7112)
		(drill 0.4064)
		(layers "F.Cu" "B.Cu")
		(net "P12V")
	)
	(via
		(at 85.2678 -70.802754)
		(size 0.7112)
		(drill 0.4064)
		(layers "F.Cu" "B.Cu")
		(net "P12V")
	)
	(via
		(at 1.778 -41.5798)
		(size 0.7112)
		(drill 0.4064)
		(layers "F.Cu" "B.Cu")
		(net "P12V")
	)
	(via
		(at 5.0292 -40.9956)
		(size 0.7112)
		(drill 0.3556)
		(layers "F.Cu" "B.Cu")
		(net "P12V")
	)
	(via
		(at 61.035438 -16.1036)
		(size 0.508)
		(drill 0.254)
		(layers "F.Cu" "B.Cu")
		(net "P12V")
	)
	(via
		(at 16.129 -14.605)
		(size 0.7112)
		(drill 0.4064)
		(layers "F.Cu" "B.Cu")
		(net "P12V")
	)
	(via
		(at 201.168 -21.082)
		(size 0.7112)
		(drill 0.4064)
		(layers "F.Cu" "B.Cu")
		(net "P12V")
	)
	(via
		(at 16.637 -31.4452)
		(size 0.508)
		(drill 0.254)
		(layers "F.Cu" "B.Cu")
		(net "P12V")
	)
	(via
		(at 206.25689 -68.851018)
		(size 0.7112)
		(drill 0.4064)
		(layers "F.Cu" "B.Cu")
		(net "P12V")
	)
	(segment
		(start 97.350072 -5.814568)
		(end 97.350072 -9.339072)
		(width 0.7112)
		(layer "B.Cu")
		(net "P12V")
	)
	(segment
		(start 97.917 -10.541)
		(end 98.35007 -10.10793)
		(width 0.7112)
		(layer "B.Cu")
		(net "P12V")
	)
	(segment
		(start 98.35007 -10.10793)
		(end 98.35007 -5.814568)
		(width 0.7112)
		(layer "B.Cu")
		(net "P12V")
	)
	(segment
		(start 96.350074 -5.814568)
		(end 96.350074 -9.507474)
		(width 0.7112)
		(layer "B.Cu")
		(net "P12V")
	)
	(segment
		(start 69.088 -63.978282)
		(end 69.088 -63.1698)
		(width 0.3048)
		(layer "B.Cu")
		(net "P12V")
	)
	(segment
		(start 204.47 -70.993)
		(end 205.613 -69.85)
		(width 0.508)
		(layer "B.Cu")
		(net "P12V")
	)
	(segment
		(start 192.532762 -35.890962)
		(end 191.643 -35.0012)
		(width 0.508)
		(layer "B.Cu")
		(net "P12V")
	)
	(segment
		(start 191.643 -35.0012)
		(end 191.643 -30.099)
		(width 0.508)
		(layer "B.Cu")
		(net "P12V")
	)
	(segment
		(start 193.548 -36.6776)
		(end 195.2498 -36.6776)
		(width 0.508)
		(layer "B.Cu")
		(net "P12V")
	)
	(segment
		(start 193.3194 -36.6776)
		(end 192.532762 -35.890962)
		(width 0.508)
		(layer "B.Cu")
		(net "P12V")
	)
	(segment
		(start 72.9615 -68.3895)
		(end 70.398386 -68.3895)
		(width 0.3048)
		(layer "B.Cu")
		(net "P12V")
	)
	(segment
		(start 70.398386 -68.3895)
		(end 68.9356 -66.926714)
		(width 0.3048)
		(layer "B.Cu")
		(net "P12V")
	)
	(segment
		(start 205.613 -69.85)
		(end 205.7654 -69.85)
		(width 0.508)
		(layer "B.Cu")
		(net "P12V")
	)
	(segment
		(start 69.088 -63.1698)
		(end 68.7832 -62.865)
		(width 0.3048)
		(layer "B.Cu")
		(net "P12V")
	)
	(segment
		(start 193.294 -28.448)
		(end 194.437 -28.448)
		(width 0.508)
		(layer "B.Cu")
		(net "P12V")
	)
	(segment
		(start 68.9356 -64.130682)
		(end 69.088 -63.978282)
		(width 0.3048)
		(layer "B.Cu")
		(net "P12V")
	)
	(segment
		(start 68.9356 -66.926714)
		(end 68.9356 -64.130682)
		(width 0.3048)
		(layer "B.Cu")
		(net "P12V")
	)
	(segment
		(start 204.0382 -70.993)
		(end 204.47 -70.993)
		(width 0.508)
		(layer "B.Cu")
		(net "P12V")
	)
	(segment
		(start 191.643 -30.099)
		(end 193.294 -28.448)
		(width 0.508)
		(layer "B.Cu")
		(net "P12V")
	)
	(segment
		(start 96.350074 -9.507474)
		(end 96.52 -9.6774)
		(width 0.7112)
		(layer "B.Cu")
		(net "P12V")
	)
	(segment
		(start 193.548 -36.6776)
		(end 193.3194 -36.6776)
		(width 0.508)
		(layer "B.Cu")
		(net "P12V")
	)
	(segment
		(start 62.168786 -21.6408)
		(end 61.381386 -20.8534)
		(width 0.3048)
		(layer "In2.Cu")
		(net "P12V")
	)
	(segment
		(start 60.066682 -20.8534)
		(end 58.83402 -19.620738)
		(width 0.3048)
		(layer "In2.Cu")
		(net "P12V")
	)
	(segment
		(start 58.83402 -19.620738)
		(end 58.83402 -18.00098)
		(width 0.3048)
		(layer "In2.Cu")
		(net "P12V")
	)
	(segment
		(start 58.83402 -18.00098)
		(end 60.7314 -16.1036)
		(width 0.3048)
		(layer "In2.Cu")
		(net "P12V")
	)
	(segment
		(start 60.7314 -16.1036)
		(end 61.035438 -16.1036)
		(width 0.3048)
		(layer "In2.Cu")
		(net "P12V")
	)
	(segment
		(start 61.381386 -20.8534)
		(end 60.066682 -20.8534)
		(width 0.3048)
		(layer "In2.Cu")
		(net "P12V")
	)
	(segment
		(start 11.094212 -31.4452)
		(end 16.637 -31.4452)
		(width 0.508)
		(layer "In7.Cu")
		(net "P12V")
	)
	(segment
		(start 9.4488 -30.9118)
		(end 10.560812 -30.9118)
		(width 0.508)
		(layer "In7.Cu")
		(net "P12V")
	)
	(segment
		(start 10.560812 -30.9118)
		(end 11.094212 -31.4452)
		(width 0.508)
		(layer "In7.Cu")
		(net "P12V")
	)
	(segment
		(start 7.9756 -32.385)
		(end 9.4488 -30.9118)
		(width 0.508)
		(layer "In7.Cu")
		(net "P12V")
	)
	(segment
		(start 3.81 -32.385)
		(end 7.9756 -32.385)
		(width 0.508)
		(layer "In7.Cu")
		(net "P12V")
	)
	(segment
		(start 55.0037 -33.668716)
		(end 55.0037 -35.25139)
		(width 0.3048)
		(layer "In9.Cu")
		(net "P12V")
	)
	(segment
		(start 56.960008 -37.645848)
		(end 58.21045 -38.89629)
		(width 0.3048)
		(layer "In9.Cu")
		(net "P12V")
	)
	(segment
		(start 53.618384 -32.2834)
		(end 55.0037 -33.668716)
		(width 0.3048)
		(layer "In9.Cu")
		(net "P12V")
	)
	(segment
		(start 55.0037 -35.25139)
		(end 56.960008 -37.207698)
		(width 0.3048)
		(layer "In9.Cu")
		(net "P12V")
	)
	(segment
		(start 56.960008 -37.207698)
		(end 56.960008 -37.645848)
		(width 0.3048)
		(layer "In9.Cu")
		(net "P12V")
	)
	(segment
		(start 58.21045 -41.594786)
		(end 59.161934 -42.54627)
		(width 0.3048)
		(layer "In9.Cu")
		(net "P12V")
	)
	(segment
		(start 46.434756 -27.572462)
		(end 46.800262 -27.572462)
		(width 0.3048)
		(layer "In9.Cu")
		(net "P12V")
	)
	(segment
		(start 58.21045 -38.89629)
		(end 58.21045 -41.594786)
		(width 0.3048)
		(layer "In9.Cu")
		(net "P12V")
	)
	(segment
		(start 46.107604 -26.422604)
		(end 46.107604 -27.24531)
		(width 0.3048)
		(layer "In9.Cu")
		(net "P12V")
	)
	(segment
		(start 46.800262 -27.572462)
		(end 51.5112 -32.2834)
		(width 0.3048)
		(layer "In9.Cu")
		(net "P12V")
	)
	(segment
		(start 44.6532 -21.893276)
		(end 44.6532 -24.9682)
		(width 0.3048)
		(layer "In9.Cu")
		(net "P12V")
	)
	(segment
		(start 38.101524 -15.3416)
		(end 44.6532 -21.893276)
		(width 0.3048)
		(layer "In9.Cu")
		(net "P12V")
	)
	(segment
		(start 46.107604 -27.24531)
		(end 46.434756 -27.572462)
		(width 0.3048)
		(layer "In9.Cu")
		(net "P12V")
	)
	(segment
		(start 51.5112 -32.2834)
		(end 53.618384 -32.2834)
		(width 0.3048)
		(layer "In9.Cu")
		(net "P12V")
	)
	(segment
		(start 44.6532 -24.9682)
		(end 46.107604 -26.422604)
		(width 0.3048)
		(layer "In9.Cu")
		(net "P12V")
	)
	(segment
		(start 37.4396 -15.3416)
		(end 38.101524 -15.3416)
		(width 0.3048)
		(layer "In9.Cu")
		(net "P12V")
	)
	(segment
		(start 201.422 -44.323)
		(end 201.3966 -44.3484)
		(width 0.2032)
		(layer "F.Cu")
		(net "VR_PVDDR_A_VSW")
	)
	(segment
		(start 201.3966 -44.3484)
		(end 201.3966 -45.6565)
		(width 0.2032)
		(layer "F.Cu")
		(net "VR_PVDDR_A_VSW")
	)
	(via
		(at 201.199242 -45.10913)
		(size 0.7112)
		(drill 0.3556)
		(layers "F.Cu" "B.Cu")
		(net "VR_PVDDR_A_VSW")
	)
	(via
		(at 201.422 -44.323)
		(size 0.508)
		(drill 0.254)
		(layers "F.Cu" "B.Cu")
		(net "VR_PVDDR_A_VSW")
	)
	(segment
		(start 201.422 -44.323)
		(end 201.7014 -44.0436)
		(width 0.508)
		(layer "B.Cu")
		(net "VR_PVDDR_A_VSW")
	)
	(segment
		(start 201.422 -44.323)
		(end 201.199242 -44.545758)
		(width 0.3048)
		(layer "B.Cu")
		(net "VR_PVDDR_A_VSW")
	)
	(segment
		(start 201.199242 -44.545758)
		(end 201.199242 -45.10913)
		(width 0.3048)
		(layer "B.Cu")
		(net "VR_PVDDR_A_VSW")
	)
	(segment
		(start 201.7014 -44.0436)
		(end 202.438 -44.0436)
		(width 0.508)
		(layer "B.Cu")
		(net "VR_PVDDR_A_VSW")
	)
	(segment
		(start 111.0996 -30.8864)
		(end 111.007906 -30.978094)
		(width 0.1778)
		(layer "F.Cu")
		(net "M_B_ODT3")
	)
	(segment
		(start 168.850056 -8.953754)
		(end 168.35628 -8.459978)
		(width 0.1778)
		(layer "F.Cu")
		(net "M_B_ODT3")
	)
	(segment
		(start 168.35628 -8.459978)
		(end 168.301162 -8.459978)
		(width 0.1778)
		(layer "F.Cu")
		(net "M_B_ODT3")
	)
	(segment
		(start 168.850056 -9.897364)
		(end 168.850056 -8.953754)
		(width 0.1778)
		(layer "F.Cu")
		(net "M_B_ODT3")
	)
	(segment
		(start 111.007906 -30.978094)
		(end 110.602268 -30.978094)
		(width 0.1778)
		(layer "F.Cu")
		(net "M_B_ODT3")
	)
	(segment
		(start 168.301162 -8.459978)
		(end 168.275762 -8.434578)
		(width 0.1778)
		(layer "F.Cu")
		(net "M_B_ODT3")
	)
	(via
		(at 111.0996 -30.8864)
		(size 0.4318)
		(drill 0.2032)
		(layers "F.Cu" "B.Cu")
		(net "M_B_ODT3")
	)
	(via
		(at 168.275762 -8.434578)
		(size 0.4318)
		(drill 0.2032)
		(layers "F.Cu" "B.Cu")
		(net "M_B_ODT3")
	)
	(segment
		(start 114.808254 -26.085546)
		(end 114.3762 -26.5176)
		(width 0.1524)
		(layer "In9.Cu")
		(net "M_B_ODT3")
	)
	(segment
		(start 110.109 -30.6324)
		(end 110.2614 -30.7848)
		(width 0.1524)
		(layer "In9.Cu")
		(net "M_B_ODT3")
	)
	(segment
		(start 158.775146 -20.345654)
		(end 158.775146 -20.561046)
		(width 0.1524)
		(layer "In9.Cu")
		(net "M_B_ODT3")
	)
	(segment
		(start 159.690054 -21.475954)
		(end 159.690054 -21.691346)
		(width 0.1524)
		(layer "In9.Cu")
		(net "M_B_ODT3")
	)
	(segment
		(start 157.0228 -22.86)
		(end 157.0228 -23.115778)
		(width 0.1524)
		(layer "In9.Cu")
		(net "M_B_ODT3")
	)
	(segment
		(start 157.26156 -22.08276)
		(end 157.032706 -22.08276)
		(width 0.1524)
		(layer "In9.Cu")
		(net "M_B_ODT3")
	)
	(segment
		(start 159.0167 -20.1041)
		(end 158.775146 -20.345654)
		(width 0.1524)
		(layer "In9.Cu")
		(net "M_B_ODT3")
	)
	(segment
		(start 110.998 -30.7848)
		(end 111.0996 -30.8864)
		(width 0.1524)
		(layer "In9.Cu")
		(net "M_B_ODT3")
	)
	(segment
		(start 110.109 -29.9466)
		(end 110.109 -30.6324)
		(width 0.1524)
		(layer "In9.Cu")
		(net "M_B_ODT3")
	)
	(segment
		(start 157.0228 -23.115778)
		(end 154.053032 -26.085546)
		(width 0.1524)
		(layer "In9.Cu")
		(net "M_B_ODT3")
	)
	(segment
		(start 168.275762 -10.949686)
		(end 169.392854 -12.066778)
		(width 0.1524)
		(layer "In9.Cu")
		(net "M_B_ODT3")
	)
	(segment
		(start 110.69955 -29.8196)
		(end 110.54715 -29.6672)
		(width 0.1524)
		(layer "In9.Cu")
		(net "M_B_ODT3")
	)
	(segment
		(start 158.343854 -20.992338)
		(end 158.128462 -20.992338)
		(width 0.1524)
		(layer "In9.Cu")
		(net "M_B_ODT3")
	)
	(segment
		(start 110.2614 -30.7848)
		(end 110.998 -30.7848)
		(width 0.1524)
		(layer "In9.Cu")
		(net "M_B_ODT3")
	)
	(segment
		(start 114.3762 -26.5176)
		(end 114.3762 -27.230578)
		(width 0.1524)
		(layer "In9.Cu")
		(net "M_B_ODT3")
	)
	(segment
		(start 159.6644 -20.1041)
		(end 159.0167 -20.1041)
		(width 0.1524)
		(layer "In9.Cu")
		(net "M_B_ODT3")
	)
	(segment
		(start 157.714696 -21.621496)
		(end 158.604204 -22.511004)
		(width 0.1524)
		(layer "In9.Cu")
		(net "M_B_ODT3")
	)
	(segment
		(start 157.032706 -22.08276)
		(end 156.795978 -22.319488)
		(width 0.1524)
		(layer "In9.Cu")
		(net "M_B_ODT3")
	)
	(segment
		(start 157.714696 -21.406104)
		(end 157.714696 -21.621496)
		(width 0.1524)
		(layer "In9.Cu")
		(net "M_B_ODT3")
	)
	(segment
		(start 169.392854 -12.066778)
		(end 169.392854 -13.86967)
		(width 0.1524)
		(layer "In9.Cu")
		(net "M_B_ODT3")
	)
	(segment
		(start 159.8168 -19.9517)
		(end 159.6644 -20.1041)
		(width 0.1524)
		(layer "In9.Cu")
		(net "M_B_ODT3")
	)
	(segment
		(start 158.775146 -20.561046)
		(end 159.690054 -21.475954)
		(width 0.1524)
		(layer "In9.Cu")
		(net "M_B_ODT3")
	)
	(segment
		(start 156.795978 -22.633178)
		(end 157.0228 -22.86)
		(width 0.1524)
		(layer "In9.Cu")
		(net "M_B_ODT3")
	)
	(segment
		(start 110.54715 -29.6672)
		(end 110.3884 -29.6672)
		(width 0.1524)
		(layer "In9.Cu")
		(net "M_B_ODT3")
	)
	(segment
		(start 158.604204 -22.511004)
		(end 158.604204 -22.726396)
		(width 0.1524)
		(layer "In9.Cu")
		(net "M_B_ODT3")
	)
	(segment
		(start 114.3762 -27.230578)
		(end 111.481362 -30.125416)
		(width 0.1524)
		(layer "In9.Cu")
		(net "M_B_ODT3")
	)
	(segment
		(start 158.362396 -22.968204)
		(end 158.147004 -22.968204)
		(width 0.1524)
		(layer "In9.Cu")
		(net "M_B_ODT3")
	)
	(segment
		(start 159.8168 -19.298666)
		(end 159.8168 -19.9517)
		(width 0.1524)
		(layer "In9.Cu")
		(net "M_B_ODT3")
	)
	(segment
		(start 168.275762 -8.434578)
		(end 168.275762 -10.949686)
		(width 0.1524)
		(layer "In9.Cu")
		(net "M_B_ODT3")
	)
	(segment
		(start 159.258762 -21.907246)
		(end 158.343854 -20.992338)
		(width 0.1524)
		(layer "In9.Cu")
		(net "M_B_ODT3")
	)
	(segment
		(start 110.69955 -29.973016)
		(end 110.69955 -29.8196)
		(width 0.1524)
		(layer "In9.Cu")
		(net "M_B_ODT3")
	)
	(segment
		(start 156.795978 -22.319488)
		(end 156.795978 -22.633178)
		(width 0.1524)
		(layer "In9.Cu")
		(net "M_B_ODT3")
	)
	(segment
		(start 159.690054 -21.691346)
		(end 159.474154 -21.907246)
		(width 0.1524)
		(layer "In9.Cu")
		(net "M_B_ODT3")
	)
	(segment
		(start 160.636966 -18.4785)
		(end 159.8168 -19.298666)
		(width 0.1524)
		(layer "In9.Cu")
		(net "M_B_ODT3")
	)
	(segment
		(start 169.392854 -13.86967)
		(end 164.784024 -18.4785)
		(width 0.1524)
		(layer "In9.Cu")
		(net "M_B_ODT3")
	)
	(segment
		(start 158.128462 -20.992338)
		(end 157.714696 -21.406104)
		(width 0.1524)
		(layer "In9.Cu")
		(net "M_B_ODT3")
	)
	(segment
		(start 110.3884 -29.6672)
		(end 110.109 -29.9466)
		(width 0.1524)
		(layer "In9.Cu")
		(net "M_B_ODT3")
	)
	(segment
		(start 110.85195 -30.125416)
		(end 110.69955 -29.973016)
		(width 0.1524)
		(layer "In9.Cu")
		(net "M_B_ODT3")
	)
	(segment
		(start 159.474154 -21.907246)
		(end 159.258762 -21.907246)
		(width 0.1524)
		(layer "In9.Cu")
		(net "M_B_ODT3")
	)
	(segment
		(start 158.147004 -22.968204)
		(end 157.26156 -22.08276)
		(width 0.1524)
		(layer "In9.Cu")
		(net "M_B_ODT3")
	)
	(segment
		(start 111.481362 -30.125416)
		(end 110.85195 -30.125416)
		(width 0.1524)
		(layer "In9.Cu")
		(net "M_B_ODT3")
	)
	(segment
		(start 154.053032 -26.085546)
		(end 114.808254 -26.085546)
		(width 0.1524)
		(layer "In9.Cu")
		(net "M_B_ODT3")
	)
	(segment
		(start 164.784024 -18.4785)
		(end 160.636966 -18.4785)
		(width 0.1524)
		(layer "In9.Cu")
		(net "M_B_ODT3")
	)
	(segment
		(start 158.604204 -22.726396)
		(end 158.362396 -22.968204)
		(width 0.1524)
		(layer "In9.Cu")
		(net "M_B_ODT3")
	)
	(segment
		(start 75.517502 -29.718762)
		(end 75.15987 -29.36113)
		(width 0.1397)
		(layer "F.Cu")
		(net "SATA3_TX_DP0")
	)
	(segment
		(start 69.6722 -27.813)
		(end 69.430392 -27.813)
		(width 0.1397)
		(layer "F.Cu")
		(net "SATA3_TX_DP0")
	)
	(segment
		(start 71.374 -26.77668)
		(end 71.374 -26.29916)
		(width 0.1397)
		(layer "F.Cu")
		(net "SATA3_TX_DP0")
	)
	(segment
		(start 74.66457 -28.23337)
		(end 74.24547 -28.23337)
		(width 0.1397)
		(layer "F.Cu")
		(net "SATA3_TX_DP0")
	)
	(segment
		(start 71.374 -27.5971)
		(end 71.57466 -27.39644)
		(width 0.1397)
		(layer "F.Cu")
		(net "SATA3_TX_DP0")
	)
	(segment
		(start 76.394056 -30.595316)
		(end 76.097638 -30.298898)
		(width 0.1397)
		(layer "F.Cu")
		(net "SATA3_TX_DP0")
	)
	(segment
		(start 71.57466 -26.97734)
		(end 71.374 -26.77668)
		(width 0.1397)
		(layer "F.Cu")
		(net "SATA3_TX_DP0")
	)
	(segment
		(start 76.974192 -30.89148)
		(end 76.677774 -30.595316)
		(width 0.1397)
		(layer "F.Cu")
		(net "SATA3_TX_DP0")
	)
	(segment
		(start 77.850492 -31.768034)
		(end 77.554328 -31.471616)
		(width 0.1397)
		(layer "F.Cu")
		(net "SATA3_TX_DP0")
	)
	(segment
		(start 73.00595 -28.23337)
		(end 72.80529 -28.03271)
		(width 0.1397)
		(layer "F.Cu")
		(net "SATA3_TX_DP0")
	)
	(segment
		(start 77.850492 -32.051752)
		(end 77.850492 -31.768034)
		(width 0.1397)
		(layer "F.Cu")
		(net "SATA3_TX_DP0")
	)
	(segment
		(start 79.357474 -33.154874)
		(end 78.55077 -32.34817)
		(width 0.1397)
		(layer "F.Cu")
		(net "SATA3_TX_DP0")
	)
	(segment
		(start 71.57466 -27.39644)
		(end 71.57466 -26.97734)
		(width 0.1397)
		(layer "F.Cu")
		(net "SATA3_TX_DP0")
	)
	(segment
		(start 74.04481 -28.03271)
		(end 73.62571 -28.03271)
		(width 0.1397)
		(layer "F.Cu")
		(net "SATA3_TX_DP0")
	)
	(segment
		(start 69.8246 -27.6606)
		(end 69.6722 -27.813)
		(width 0.1397)
		(layer "F.Cu")
		(net "SATA3_TX_DP0")
	)
	(segment
		(start 73.62571 -28.03271)
		(end 73.42505 -28.23337)
		(width 0.1397)
		(layer "F.Cu")
		(net "SATA3_TX_DP0")
	)
	(segment
		(start 72.38619 -28.03271)
		(end 72.18553 -28.23337)
		(width 0.1397)
		(layer "F.Cu")
		(net "SATA3_TX_DP0")
	)
	(segment
		(start 79.601568 -33.154874)
		(end 79.357474 -33.154874)
		(width 0.1397)
		(layer "F.Cu")
		(net "SATA3_TX_DP0")
	)
	(segment
		(start 72.18553 -28.23337)
		(end 71.59117 -28.23337)
		(width 0.1397)
		(layer "F.Cu")
		(net "SATA3_TX_DP0")
	)
	(segment
		(start 72.80529 -28.03271)
		(end 72.38619 -28.03271)
		(width 0.1397)
		(layer "F.Cu")
		(net "SATA3_TX_DP0")
	)
	(segment
		(start 75.801474 -29.718762)
		(end 75.517502 -29.718762)
		(width 0.1397)
		(layer "F.Cu")
		(net "SATA3_TX_DP0")
	)
	(segment
		(start 78.14691 -32.34817)
		(end 77.850492 -32.051752)
		(width 0.1397)
		(layer "F.Cu")
		(net "SATA3_TX_DP0")
	)
	(segment
		(start 76.097638 -30.01518)
		(end 75.801474 -29.718762)
		(width 0.1397)
		(layer "F.Cu")
		(net "SATA3_TX_DP0")
	)
	(segment
		(start 69.8246 -26.29916)
		(end 69.8246 -27.6606)
		(width 0.1397)
		(layer "F.Cu")
		(net "SATA3_TX_DP0")
	)
	(segment
		(start 71.374 -26.29916)
		(end 71.02094 -25.9461)
		(width 0.1397)
		(layer "F.Cu")
		(net "SATA3_TX_DP0")
	)
	(segment
		(start 76.974192 -31.175452)
		(end 76.974192 -30.89148)
		(width 0.1397)
		(layer "F.Cu")
		(net "SATA3_TX_DP0")
	)
	(segment
		(start 78.55077 -32.34817)
		(end 78.14691 -32.34817)
		(width 0.1397)
		(layer "F.Cu")
		(net "SATA3_TX_DP0")
	)
	(segment
		(start 75.15987 -28.72867)
		(end 74.66457 -28.23337)
		(width 0.1397)
		(layer "F.Cu")
		(net "SATA3_TX_DP0")
	)
	(segment
		(start 69.430392 -27.813)
		(end 69.1388 -27.521408)
		(width 0.1397)
		(layer "F.Cu")
		(net "SATA3_TX_DP0")
	)
	(segment
		(start 75.15987 -29.36113)
		(end 75.15987 -28.72867)
		(width 0.1397)
		(layer "F.Cu")
		(net "SATA3_TX_DP0")
	)
	(segment
		(start 76.677774 -30.595316)
		(end 76.394056 -30.595316)
		(width 0.1397)
		(layer "F.Cu")
		(net "SATA3_TX_DP0")
	)
	(segment
		(start 71.02094 -25.9461)
		(end 70.17766 -25.9461)
		(width 0.1397)
		(layer "F.Cu")
		(net "SATA3_TX_DP0")
	)
	(segment
		(start 71.374 -28.0162)
		(end 71.374 -27.5971)
		(width 0.1397)
		(layer "F.Cu")
		(net "SATA3_TX_DP0")
	)
	(segment
		(start 73.42505 -28.23337)
		(end 73.00595 -28.23337)
		(width 0.1397)
		(layer "F.Cu")
		(net "SATA3_TX_DP0")
	)
	(segment
		(start 76.097638 -30.298898)
		(end 76.097638 -30.01518)
		(width 0.1397)
		(layer "F.Cu")
		(net "SATA3_TX_DP0")
	)
	(segment
		(start 77.554328 -31.471616)
		(end 77.270356 -31.471616)
		(width 0.1397)
		(layer "F.Cu")
		(net "SATA3_TX_DP0")
	)
	(segment
		(start 77.270356 -31.471616)
		(end 76.974192 -31.175452)
		(width 0.1397)
		(layer "F.Cu")
		(net "SATA3_TX_DP0")
	)
	(segment
		(start 70.17766 -25.9461)
		(end 69.8246 -26.29916)
		(width 0.1397)
		(layer "F.Cu")
		(net "SATA3_TX_DP0")
	)
	(segment
		(start 71.59117 -28.23337)
		(end 71.374 -28.0162)
		(width 0.1397)
		(layer "F.Cu")
		(net "SATA3_TX_DP0")
	)
	(segment
		(start 74.24547 -28.23337)
		(end 74.04481 -28.03271)
		(width 0.1397)
		(layer "F.Cu")
		(net "SATA3_TX_DP0")
	)
	(via
		(at 69.1388 -27.521408)
		(size 0.508)
		(drill 0.254)
		(layers "F.Cu" "B.Cu")
		(net "SATA3_TX_DP0")
	)
	(segment
		(start 67.8561 -27.7749)
		(end 68.885308 -27.7749)
		(width 0.1397)
		(layer "B.Cu")
		(net "SATA3_TX_DP0")
	)
	(segment
		(start 67.6402 -27.559)
		(end 67.8561 -27.7749)
		(width 0.1397)
		(layer "B.Cu")
		(net "SATA3_TX_DP0")
	)
	(segment
		(start 68.885308 -27.7749)
		(end 69.1388 -27.521408)
		(width 0.1397)
		(layer "B.Cu")
		(net "SATA3_TX_DP0")
	)
	(segment
		(start 82.885788 -45.390054)
		(end 82.514948 -45.390054)
		(width 0.1143)
		(layer "F.Cu")
		(net "XDP_DFX_PORT8")
	)
	(segment
		(start 35.095688 -22.05482)
		(end 36.37788 -22.05482)
		(width 0.1143)
		(layer "F.Cu")
		(net "XDP_DFX_PORT8")
	)
	(segment
		(start 34.0868 -21.8694)
		(end 34.910268 -21.8694)
		(width 0.1143)
		(layer "F.Cu")
		(net "XDP_DFX_PORT8")
	)
	(segment
		(start 82.514948 -45.390054)
		(end 82.169 -45.736002)
		(width 0.1143)
		(layer "F.Cu")
		(net "XDP_DFX_PORT8")
	)
	(segment
		(start 34.910268 -21.8694)
		(end 35.095688 -22.05482)
		(width 0.1143)
		(layer "F.Cu")
		(net "XDP_DFX_PORT8")
	)
	(via
		(at 33.740344 -21.210778)
		(size 0.7112)
		(drill 0.3556)
		(layers "F.Cu" "B.Cu")
		(net "XDP_DFX_PORT8")
	)
	(via
		(at 82.169 -45.736002)
		(size 0.4318)
		(drill 0.2032)
		(layers "F.Cu" "B.Cu")
		(net "XDP_DFX_PORT8")
	)
	(via
		(at 34.0868 -21.8694)
		(size 0.508)
		(drill 0.254)
		(layers "F.Cu" "B.Cu")
		(net "XDP_DFX_PORT8")
	)
	(segment
		(start 33.740344 -21.210778)
		(end 33.740344 -21.522944)
		(width 0.1143)
		(layer "B.Cu")
		(net "XDP_DFX_PORT8")
	)
	(segment
		(start 33.740344 -21.522944)
		(end 34.0868 -21.8694)
		(width 0.1143)
		(layer "B.Cu")
		(net "XDP_DFX_PORT8")
	)
	(segment
		(start 82.083402 -45.8216)
		(end 82.169 -45.736002)
		(width 0.0889)
		(layer "In7.Cu")
		(net "XDP_DFX_PORT8")
	)
	(segment
		(start 57.288938 -39.122604)
		(end 57.289192 -39.12235)
		(width 0.0889)
		(layer "In7.Cu")
		(net "XDP_DFX_PORT8")
	)
	(segment
		(start 39.1033 -28.092146)
		(end 39.1033 -30.0863)
		(width 0.0889)
		(layer "In7.Cu")
		(net "XDP_DFX_PORT8")
	)
	(segment
		(start 80.24241 -46.215046)
		(end 81.431638 -46.215046)
		(width 0.0889)
		(layer "In7.Cu")
		(net "XDP_DFX_PORT8")
	)
	(segment
		(start 48.648366 -36.322)
		(end 50.290222 -37.963856)
		(width 0.0889)
		(layer "In7.Cu")
		(net "XDP_DFX_PORT8")
	)
	(segment
		(start 35.521138 -21.7424)
		(end 38.82517 -25.046432)
		(width 0.0889)
		(layer "In7.Cu")
		(net "XDP_DFX_PORT8")
	)
	(segment
		(start 38.80485 -27.793696)
		(end 39.1033 -28.092146)
		(width 0.0889)
		(layer "In7.Cu")
		(net "XDP_DFX_PORT8")
	)
	(segment
		(start 34.2138 -21.7424)
		(end 35.521138 -21.7424)
		(width 0.0889)
		(layer "In7.Cu")
		(net "XDP_DFX_PORT8")
	)
	(segment
		(start 73.87463 -43.161966)
		(end 75.499214 -44.78655)
		(width 0.0889)
		(layer "In7.Cu")
		(net "XDP_DFX_PORT8")
	)
	(segment
		(start 57.289192 -39.12235)
		(end 65.170304 -39.12235)
		(width 0.0889)
		(layer "In7.Cu")
		(net "XDP_DFX_PORT8")
	)
	(segment
		(start 39.1033 -30.0863)
		(end 43.58005 -34.56305)
		(width 0.0889)
		(layer "In7.Cu")
		(net "XDP_DFX_PORT8")
	)
	(segment
		(start 50.290222 -37.963856)
		(end 55.82539 -37.963856)
		(width 0.0889)
		(layer "In7.Cu")
		(net "XDP_DFX_PORT8")
	)
	(segment
		(start 38.80485 -25.44064)
		(end 38.80485 -27.793696)
		(width 0.0889)
		(layer "In7.Cu")
		(net "XDP_DFX_PORT8")
	)
	(segment
		(start 69.20992 -43.161966)
		(end 73.87463 -43.161966)
		(width 0.0889)
		(layer "In7.Cu")
		(net "XDP_DFX_PORT8")
	)
	(segment
		(start 75.499214 -44.78655)
		(end 78.813914 -44.78655)
		(width 0.0889)
		(layer "In7.Cu")
		(net "XDP_DFX_PORT8")
	)
	(segment
		(start 38.82517 -25.42032)
		(end 38.80485 -25.44064)
		(width 0.0889)
		(layer "In7.Cu")
		(net "XDP_DFX_PORT8")
	)
	(segment
		(start 43.58005 -34.56305)
		(end 45.828204 -34.56305)
		(width 0.0889)
		(layer "In7.Cu")
		(net "XDP_DFX_PORT8")
	)
	(segment
		(start 81.825084 -45.8216)
		(end 82.083402 -45.8216)
		(width 0.0889)
		(layer "In7.Cu")
		(net "XDP_DFX_PORT8")
	)
	(segment
		(start 81.431638 -46.215046)
		(end 81.825084 -45.8216)
		(width 0.0889)
		(layer "In7.Cu")
		(net "XDP_DFX_PORT8")
	)
	(segment
		(start 45.828204 -34.56305)
		(end 47.587154 -36.322)
		(width 0.0889)
		(layer "In7.Cu")
		(net "XDP_DFX_PORT8")
	)
	(segment
		(start 78.813914 -44.78655)
		(end 80.24241 -46.215046)
		(width 0.0889)
		(layer "In7.Cu")
		(net "XDP_DFX_PORT8")
	)
	(segment
		(start 55.82539 -37.963856)
		(end 56.984138 -39.122604)
		(width 0.0889)
		(layer "In7.Cu")
		(net "XDP_DFX_PORT8")
	)
	(segment
		(start 47.587154 -36.322)
		(end 48.648366 -36.322)
		(width 0.0889)
		(layer "In7.Cu")
		(net "XDP_DFX_PORT8")
	)
	(segment
		(start 56.984138 -39.122604)
		(end 57.288938 -39.122604)
		(width 0.0889)
		(layer "In7.Cu")
		(net "XDP_DFX_PORT8")
	)
	(segment
		(start 38.82517 -25.046432)
		(end 38.82517 -25.42032)
		(width 0.0889)
		(layer "In7.Cu")
		(net "XDP_DFX_PORT8")
	)
	(segment
		(start 65.170304 -39.12235)
		(end 69.20992 -43.161966)
		(width 0.0889)
		(layer "In7.Cu")
		(net "XDP_DFX_PORT8")
	)
	(segment
		(start 34.0868 -21.8694)
		(end 34.2138 -21.7424)
		(width 0.0889)
		(layer "In7.Cu")
		(net "XDP_DFX_PORT8")
	)
	(segment
		(start 128.35001 -1.68402)
		(end 128.35001 -2.842768)
		(width 0.1778)
		(layer "F.Cu")
		(net "DDR3_M_B_VREF_DQ1")
	)
	(segment
		(start 179.631086 -24.765)
		(end 179.631086 -39.43731)
		(width 0.1778)
		(layer "F.Cu")
		(net "DDR3_M_B_VREF_DQ1")
	)
	(segment
		(start 179.631086 -39.43731)
		(end 182.648098 -42.454322)
		(width 0.1778)
		(layer "F.Cu")
		(net "DDR3_M_B_VREF_DQ1")
	)
	(segment
		(start 128.35001 -2.842768)
		(end 128.016 -3.176778)
		(width 0.1778)
		(layer "F.Cu")
		(net "DDR3_M_B_VREF_DQ1")
	)
	(segment
		(start 183.119776 -42.926)
		(end 182.648098 -42.454322)
		(width 0.1778)
		(layer "F.Cu")
		(net "DDR3_M_B_VREF_DQ1")
	)
	(segment
		(start 184.6072 -42.926)
		(end 183.119776 -42.926)
		(width 0.1778)
		(layer "F.Cu")
		(net "DDR3_M_B_VREF_DQ1")
	)
	(via
		(at 128.016 -3.176778)
		(size 0.4318)
		(drill 0.2032)
		(layers "F.Cu" "B.Cu")
		(net "DDR3_M_B_VREF_DQ1")
	)
	(via
		(at 179.631086 -24.765)
		(size 0.508)
		(drill 0.254)
		(layers "F.Cu" "B.Cu")
		(net "DDR3_M_B_VREF_DQ1")
	)
	(via
		(at 182.648098 -42.454322)
		(size 0.7112)
		(drill 0.3556)
		(layers "F.Cu" "B.Cu")
		(net "DDR3_M_B_VREF_DQ1")
	)
	(segment
		(start 145.1991 -14.276578)
		(end 131.318 -14.276578)
		(width 0.1778)
		(layer "B.Cu")
		(net "DDR3_M_B_VREF_DQ1")
	)
	(segment
		(start 130.175 -14.327378)
		(end 131.2672 -14.327378)
		(width 0.1778)
		(layer "B.Cu")
		(net "DDR3_M_B_VREF_DQ1")
	)
	(segment
		(start 130.175 -14.327378)
		(end 129.5146 -14.327378)
		(width 0.1778)
		(layer "B.Cu")
		(net "DDR3_M_B_VREF_DQ1")
	)
	(segment
		(start 131.2672 -14.327378)
		(end 131.318 -14.276578)
		(width 0.1778)
		(layer "B.Cu")
		(net "DDR3_M_B_VREF_DQ1")
	)
	(segment
		(start 128.016 -8.795512)
		(end 128.016 -3.176778)
		(width 0.1778)
		(layer "B.Cu")
		(net "DDR3_M_B_VREF_DQ1")
	)
	(segment
		(start 127.68961 -12.502388)
		(end 127.68961 -9.121902)
		(width 0.1778)
		(layer "B.Cu")
		(net "DDR3_M_B_VREF_DQ1")
	)
	(segment
		(start 174.343822 -16.283178)
		(end 147.2057 -16.283178)
		(width 0.1778)
		(layer "B.Cu")
		(net "DDR3_M_B_VREF_DQ1")
	)
	(segment
		(start 129.5146 -14.327378)
		(end 127.68961 -12.502388)
		(width 0.1778)
		(layer "B.Cu")
		(net "DDR3_M_B_VREF_DQ1")
	)
	(segment
		(start 179.324 -24.765)
		(end 178.44643 -23.88743)
		(width 0.1778)
		(layer "B.Cu")
		(net "DDR3_M_B_VREF_DQ1")
	)
	(segment
		(start 178.44643 -20.385786)
		(end 174.343822 -16.283178)
		(width 0.1778)
		(layer "B.Cu")
		(net "DDR3_M_B_VREF_DQ1")
	)
	(segment
		(start 127.68961 -9.121902)
		(end 128.016 -8.795512)
		(width 0.1778)
		(layer "B.Cu")
		(net "DDR3_M_B_VREF_DQ1")
	)
	(segment
		(start 179.631086 -24.765)
		(end 179.324 -24.765)
		(width 0.1778)
		(layer "B.Cu")
		(net "DDR3_M_B_VREF_DQ1")
	)
	(segment
		(start 147.2057 -16.283178)
		(end 145.1991 -14.276578)
		(width 0.1778)
		(layer "B.Cu")
		(net "DDR3_M_B_VREF_DQ1")
	)
	(segment
		(start 178.44643 -23.88743)
		(end 178.44643 -20.385786)
		(width 0.1778)
		(layer "B.Cu")
		(net "DDR3_M_B_VREF_DQ1")
	)
	(segment
		(start 8.4836 -32.4358)
		(end 8.6106 -32.3088)
		(width 0.254)
		(layer "F.Cu")
		(net "P3V3_STBY_RF")
	)
	(segment
		(start 8.726678 -33.948878)
		(end 8.726678 -33.618678)
		(width 0.254)
		(layer "F.Cu")
		(net "P3V3_STBY_RF")
	)
	(segment
		(start 7.6708 -32.5628)
		(end 7.6708 -32.4358)
		(width 0.254)
		(layer "F.Cu")
		(net "P3V3_STBY_RF")
	)
	(segment
		(start 8.726678 -33.618678)
		(end 7.6708 -32.5628)
		(width 0.254)
		(layer "F.Cu")
		(net "P3V3_STBY_RF")
	)
	(segment
		(start 9.525 -32.4358)
		(end 9.398 -32.3088)
		(width 0.254)
		(layer "F.Cu")
		(net "P3V3_STBY_RF")
	)
	(segment
		(start 7.6708 -32.4358)
		(end 8.4836 -32.4358)
		(width 0.254)
		(layer "F.Cu")
		(net "P3V3_STBY_RF")
	)
	(segment
		(start 9.398 -32.3088)
		(end 8.6106 -32.3088)
		(width 0.254)
		(layer "F.Cu")
		(net "P3V3_STBY_RF")
	)
	(via
		(at 8.6106 -32.3088)
		(size 0.7112)
		(drill 0.3556)
		(layers "F.Cu" "B.Cu")
		(net "P3V3_STBY_RF")
	)
	(segment
		(start 204.597 -33.3502)
		(end 204.597 -32.512)
		(width 0.2032)
		(layer "F.Cu")
		(net "VR_PVDDR_A_NTC_R")
	)
	(via
		(at 188.468 -31.5468)
		(size 0.7112)
		(drill 0.3556)
		(layers "F.Cu" "B.Cu")
		(net "VR_PVDDR_A_NTC_R")
	)
	(via
		(at 185.928 -31.1658)
		(size 0.508)
		(drill 0.254)
		(layers "F.Cu" "B.Cu")
		(net "VR_PVDDR_A_NTC_R")
	)
	(via
		(at 204.597 -32.512)
		(size 0.508)
		(drill 0.254)
		(layers "F.Cu" "B.Cu")
		(net "VR_PVDDR_A_NTC_R")
	)
	(segment
		(start 187.5282 -31.2928)
		(end 188.214 -31.2928)
		(width 0.2032)
		(layer "B.Cu")
		(net "VR_PVDDR_A_NTC_R")
	)
	(segment
		(start 188.214 -31.2928)
		(end 188.468 -31.5468)
		(width 0.2032)
		(layer "B.Cu")
		(net "VR_PVDDR_A_NTC_R")
	)
	(segment
		(start 187.5028 -31.2674)
		(end 187.5282 -31.2928)
		(width 0.2032)
		(layer "B.Cu")
		(net "VR_PVDDR_A_NTC_R")
	)
	(segment
		(start 186.69 -31.2674)
		(end 187.5028 -31.2674)
		(width 0.2032)
		(layer "B.Cu")
		(net "VR_PVDDR_A_NTC_R")
	)
	(segment
		(start 185.928 -31.1658)
		(end 186.0296 -31.2674)
		(width 0.2032)
		(layer "B.Cu")
		(net "VR_PVDDR_A_NTC_R")
	)
	(segment
		(start 186.0296 -31.2674)
		(end 186.69 -31.2674)
		(width 0.2032)
		(layer "B.Cu")
		(net "VR_PVDDR_A_NTC_R")
	)
	(segment
		(start 205.105 -28.321)
		(end 204.597 -27.813)
		(width 0.2032)
		(layer "In4.Cu")
		(net "VR_PVDDR_A_NTC_R")
	)
	(segment
		(start 205.105 -32.004)
		(end 205.105 -28.321)
		(width 0.2032)
		(layer "In4.Cu")
		(net "VR_PVDDR_A_NTC_R")
	)
	(segment
		(start 196.0626 -29.8704)
		(end 191.7446 -29.8704)
		(width 0.2032)
		(layer "In4.Cu")
		(net "VR_PVDDR_A_NTC_R")
	)
	(segment
		(start 198.12 -27.813)
		(end 196.0626 -29.8704)
		(width 0.2032)
		(layer "In4.Cu")
		(net "VR_PVDDR_A_NTC_R")
	)
	(segment
		(start 191.7446 -29.8704)
		(end 191.008 -30.607)
		(width 0.2032)
		(layer "In4.Cu")
		(net "VR_PVDDR_A_NTC_R")
	)
	(segment
		(start 186.4868 -30.607)
		(end 185.928 -31.1658)
		(width 0.2032)
		(layer "In4.Cu")
		(net "VR_PVDDR_A_NTC_R")
	)
	(segment
		(start 204.597 -32.512)
		(end 205.105 -32.004)
		(width 0.2032)
		(layer "In4.Cu")
		(net "VR_PVDDR_A_NTC_R")
	)
	(segment
		(start 204.597 -27.813)
		(end 198.12 -27.813)
		(width 0.2032)
		(layer "In4.Cu")
		(net "VR_PVDDR_A_NTC_R")
	)
	(segment
		(start 191.008 -30.607)
		(end 186.4868 -30.607)
		(width 0.2032)
		(layer "In4.Cu")
		(net "VR_PVDDR_A_NTC_R")
	)
	(segment
		(start 34.855404 -22.371558)
		(end 35.039046 -22.5552)
		(width 0.1143)
		(layer "F.Cu")
		(net "XDP_DFX_PORT9")
	)
	(segment
		(start 32.004 -21.8948)
		(end 32.480758 -22.371558)
		(width 0.1143)
		(layer "F.Cu")
		(net "XDP_DFX_PORT9")
	)
	(segment
		(start 82.504788 -43.403774)
		(end 83.2104 -44.109386)
		(width 0.1143)
		(layer "F.Cu")
		(net "XDP_DFX_PORT9")
	)
	(segment
		(start 32.480758 -22.371558)
		(end 34.855404 -22.371558)
		(width 0.1143)
		(layer "F.Cu")
		(net "XDP_DFX_PORT9")
	)
	(segment
		(start 83.2104 -44.109386)
		(end 83.2104 -44.240196)
		(width 0.1143)
		(layer "F.Cu")
		(net "XDP_DFX_PORT9")
	)
	(segment
		(start 35.039046 -22.5552)
		(end 36.37788 -22.5552)
		(width 0.1143)
		(layer "F.Cu")
		(net "XDP_DFX_PORT9")
	)
	(via
		(at 83.2104 -44.240196)
		(size 0.4318)
		(drill 0.2032)
		(layers "F.Cu" "B.Cu")
		(net "XDP_DFX_PORT9")
	)
	(via
		(at 31.517336 -21.338286)
		(size 0.7112)
		(drill 0.3556)
		(layers "F.Cu" "B.Cu")
		(net "XDP_DFX_PORT9")
	)
	(via
		(at 32.004 -21.8948)
		(size 0.508)
		(drill 0.254)
		(layers "F.Cu" "B.Cu")
		(net "XDP_DFX_PORT9")
	)
	(segment
		(start 31.5214 -21.4122)
		(end 32.004 -21.8948)
		(width 0.1143)
		(layer "B.Cu")
		(net "XDP_DFX_PORT9")
	)
	(segment
		(start 31.5214 -21.34235)
		(end 31.5214 -21.4122)
		(width 0.1143)
		(layer "B.Cu")
		(net "XDP_DFX_PORT9")
	)
	(segment
		(start 31.517336 -21.338286)
		(end 31.5214 -21.34235)
		(width 0.1143)
		(layer "B.Cu")
		(net "XDP_DFX_PORT9")
	)
	(segment
		(start 61.481208 -34.6837)
		(end 65.54724 -34.6837)
		(width 0.0889)
		(layer "In7.Cu")
		(net "XDP_DFX_PORT9")
	)
	(segment
		(start 67.65798 -35.1917)
		(end 71.764398 -35.1917)
		(width 0.0889)
		(layer "In7.Cu")
		(net "XDP_DFX_PORT9")
	)
	(segment
		(start 34.538412 -18.979388)
		(end 40.612568 -18.979388)
		(width 0.0889)
		(layer "In7.Cu")
		(net "XDP_DFX_PORT9")
	)
	(segment
		(start 46.778164 -30.3911)
		(end 49.03089 -30.3911)
		(width 0.0889)
		(layer "In7.Cu")
		(net "XDP_DFX_PORT9")
	)
	(segment
		(start 77.563472 -41.270174)
		(end 78.506574 -41.270174)
		(width 0.0889)
		(layer "In7.Cu")
		(net "XDP_DFX_PORT9")
	)
	(segment
		(start 44.39285 -25.387046)
		(end 44.5897 -25.583896)
		(width 0.0889)
		(layer "In7.Cu")
		(net "XDP_DFX_PORT9")
	)
	(segment
		(start 66.055494 -35.191954)
		(end 67.657726 -35.191954)
		(width 0.0889)
		(layer "In7.Cu")
		(net "XDP_DFX_PORT9")
	)
	(segment
		(start 44.39285 -24.07031)
		(end 44.39285 -25.387046)
		(width 0.0889)
		(layer "In7.Cu")
		(net "XDP_DFX_PORT9")
	)
	(segment
		(start 72.70242 -35.80765)
		(end 76.287122 -39.392352)
		(width 0.0889)
		(layer "In7.Cu")
		(net "XDP_DFX_PORT9")
	)
	(segment
		(start 65.54724 -34.6837)
		(end 66.055494 -35.191954)
		(width 0.0889)
		(layer "In7.Cu")
		(net "XDP_DFX_PORT9")
	)
	(segment
		(start 32.004 -21.8948)
		(end 32.004 -21.5138)
		(width 0.0889)
		(layer "In7.Cu")
		(net "XDP_DFX_PORT9")
	)
	(segment
		(start 81.31302 -44.07662)
		(end 82.635852 -44.07662)
		(width 0.0889)
		(layer "In7.Cu")
		(net "XDP_DFX_PORT9")
	)
	(segment
		(start 72.380348 -35.80765)
		(end 72.70242 -35.80765)
		(width 0.0889)
		(layer "In7.Cu")
		(net "XDP_DFX_PORT9")
	)
	(segment
		(start 60.008008 -33.2105)
		(end 61.481208 -34.6837)
		(width 0.0889)
		(layer "In7.Cu")
		(net "XDP_DFX_PORT9")
	)
	(segment
		(start 44.557696 -22.924516)
		(end 44.557696 -23.905464)
		(width 0.0889)
		(layer "In7.Cu")
		(net "XDP_DFX_PORT9")
	)
	(segment
		(start 44.5897 -28.202636)
		(end 46.778164 -30.3911)
		(width 0.0889)
		(layer "In7.Cu")
		(net "XDP_DFX_PORT9")
	)
	(segment
		(start 82.635852 -44.07662)
		(end 82.799428 -44.240196)
		(width 0.0889)
		(layer "In7.Cu")
		(net "XDP_DFX_PORT9")
	)
	(segment
		(start 44.557696 -23.905464)
		(end 44.39285 -24.07031)
		(width 0.0889)
		(layer "In7.Cu")
		(net "XDP_DFX_PORT9")
	)
	(segment
		(start 40.612568 -18.979388)
		(end 44.557696 -22.924516)
		(width 0.0889)
		(layer "In7.Cu")
		(net "XDP_DFX_PORT9")
	)
	(segment
		(start 76.287122 -39.993824)
		(end 77.563472 -41.270174)
		(width 0.0889)
		(layer "In7.Cu")
		(net "XDP_DFX_PORT9")
	)
	(segment
		(start 82.799428 -44.240196)
		(end 83.2104 -44.240196)
		(width 0.0889)
		(layer "In7.Cu")
		(net "XDP_DFX_PORT9")
	)
	(segment
		(start 71.764398 -35.1917)
		(end 72.380348 -35.80765)
		(width 0.0889)
		(layer "In7.Cu")
		(net "XDP_DFX_PORT9")
	)
	(segment
		(start 76.287122 -39.392352)
		(end 76.287122 -39.993824)
		(width 0.0889)
		(layer "In7.Cu")
		(net "XDP_DFX_PORT9")
	)
	(segment
		(start 49.03089 -30.3911)
		(end 51.85029 -33.2105)
		(width 0.0889)
		(layer "In7.Cu")
		(net "XDP_DFX_PORT9")
	)
	(segment
		(start 44.5897 -25.583896)
		(end 44.5897 -28.202636)
		(width 0.0889)
		(layer "In7.Cu")
		(net "XDP_DFX_PORT9")
	)
	(segment
		(start 78.506574 -41.270174)
		(end 81.31302 -44.07662)
		(width 0.0889)
		(layer "In7.Cu")
		(net "XDP_DFX_PORT9")
	)
	(segment
		(start 67.657726 -35.191954)
		(end 67.65798 -35.1917)
		(width 0.0889)
		(layer "In7.Cu")
		(net "XDP_DFX_PORT9")
	)
	(segment
		(start 51.85029 -33.2105)
		(end 60.008008 -33.2105)
		(width 0.0889)
		(layer "In7.Cu")
		(net "XDP_DFX_PORT9")
	)
	(segment
		(start 32.004 -21.5138)
		(end 34.538412 -18.979388)
		(width 0.0889)
		(layer "In7.Cu")
		(net "XDP_DFX_PORT9")
	)
	(via
		(at 24.384 -41.021)
		(size 0.7112)
		(drill 0.3556)
		(layers "F.Cu" "B.Cu")
		(net "P3V3_STBY_OUT")
	)
	(segment
		(start 188.34989 -1.68402)
		(end 188.34989 -2.982468)
		(width 0.1778)
		(layer "F.Cu")
		(net "M_B_DQ63")
	)
	(segment
		(start 188.34989 -2.982468)
		(end 188.5188 -3.151378)
		(width 0.1778)
		(layer "F.Cu")
		(net "M_B_DQ63")
	)
	(segment
		(start 105.3846 -37.338)
		(end 105.359454 -37.338)
		(width 0.1016)
		(layer "F.Cu")
		(net "M_B_DQ63")
	)
	(segment
		(start 105.359454 -37.338)
		(end 105.004108 -36.982654)
		(width 0.1016)
		(layer "F.Cu")
		(net "M_B_DQ63")
	)
	(via
		(at 188.5188 -3.151378)
		(size 0.4318)
		(drill 0.2032)
		(layers "F.Cu" "B.Cu")
		(net "M_B_DQ63")
	)
	(via
		(at 105.3846 -37.338)
		(size 0.4318)
		(drill 0.2032)
		(layers "F.Cu" "B.Cu")
		(net "M_B_DQ63")
	)
	(segment
		(start 188.649864 -1.690624)
		(end 188.649864 -3.020314)
		(width 0.1778)
		(layer "B.Cu")
		(net "M_B_DQ63")
	)
	(segment
		(start 188.649864 -3.020314)
		(end 188.5188 -3.151378)
		(width 0.1778)
		(layer "B.Cu")
		(net "M_B_DQ63")
	)
	(segment
		(start 183.114188 -12.451588)
		(end 158.209742 -37.356034)
		(width 0.1524)
		(layer "In2.Cu")
		(net "M_B_DQ63")
	)
	(segment
		(start 112.594898 -38.2778)
		(end 111.0234 -38.2778)
		(width 0.1524)
		(layer "In2.Cu")
		(net "M_B_DQ63")
	)
	(segment
		(start 158.209742 -37.356034)
		(end 155.35148 -37.907214)
		(width 0.1524)
		(layer "In2.Cu")
		(net "M_B_DQ63")
	)
	(segment
		(start 106.6038 -38.6334)
		(end 109.27842 -38.6334)
		(width 0.1016)
		(layer "In2.Cu")
		(net "M_B_DQ63")
	)
	(segment
		(start 188.154564 -5.064506)
		(end 187.485274 -7.577328)
		(width 0.1524)
		(layer "In2.Cu")
		(net "M_B_DQ63")
	)
	(segment
		(start 187.1472 -8.231378)
		(end 186.96813 -8.857488)
		(width 0.1524)
		(layer "In2.Cu")
		(net "M_B_DQ63")
	)
	(segment
		(start 188.5188 -3.151378)
		(end 188.154564 -5.064506)
		(width 0.1524)
		(layer "In2.Cu")
		(net "M_B_DQ63")
	)
	(segment
		(start 185.238898 -10.730738)
		(end 183.114188 -12.451588)
		(width 0.1524)
		(layer "In2.Cu")
		(net "M_B_DQ63")
	)
	(segment
		(start 187.485274 -7.577328)
		(end 187.1472 -8.231378)
		(width 0.1524)
		(layer "In2.Cu")
		(net "M_B_DQ63")
	)
	(segment
		(start 114.9858 -37.907214)
		(end 113.516156 -38.064948)
		(width 0.1524)
		(layer "In2.Cu")
		(net "M_B_DQ63")
	)
	(segment
		(start 109.429296 -38.596824)
		(end 111.0234 -38.2778)
		(width 0.1016)
		(layer "In2.Cu")
		(net "M_B_DQ63")
	)
	(segment
		(start 155.35148 -37.907214)
		(end 114.9858 -37.907214)
		(width 0.1524)
		(layer "In2.Cu")
		(net "M_B_DQ63")
	)
	(segment
		(start 106.1339 -38.1635)
		(end 106.6038 -38.6334)
		(width 0.1016)
		(layer "In2.Cu")
		(net "M_B_DQ63")
	)
	(segment
		(start 109.27842 -38.6334)
		(end 109.429296 -38.596824)
		(width 0.1016)
		(layer "In2.Cu")
		(net "M_B_DQ63")
	)
	(segment
		(start 105.3846 -37.338)
		(end 106.1339 -38.1635)
		(width 0.1016)
		(layer "In2.Cu")
		(net "M_B_DQ63")
	)
	(segment
		(start 186.96813 -8.857488)
		(end 185.238898 -10.730738)
		(width 0.1524)
		(layer "In2.Cu")
		(net "M_B_DQ63")
	)
	(segment
		(start 113.516156 -38.064948)
		(end 112.594898 -38.2778)
		(width 0.1524)
		(layer "In2.Cu")
		(net "M_B_DQ63")
	)
	(segment
		(start 80.449674 -31.1404)
		(end 80.28178 -31.1404)
		(width 0.1397)
		(layer "F.Cu")
		(net "SATA3_RX_DN0")
	)
	(segment
		(start 80.607408 -31.298134)
		(end 80.449674 -31.1404)
		(width 0.1397)
		(layer "F.Cu")
		(net "SATA3_RX_DN0")
	)
	(segment
		(start 80.28178 -31.1404)
		(end 80.124554 -31.297626)
		(width 0.1397)
		(layer "F.Cu")
		(net "SATA3_RX_DN0")
	)
	(via
		(at 80.124554 -31.297626)
		(size 0.4318)
		(drill 0.2032)
		(layers "F.Cu" "B.Cu")
		(net "SATA3_RX_DN0")
	)
	(segment
		(start 77.23505 -29.464)
		(end 77.23505 -29.4386)
		(width 0.1016)
		(layer "B.Cu")
		(net "SATA3_RX_DN0")
	)
	(segment
		(start 77.23505 -28.92552)
		(end 75.373484 -27.063954)
		(width 0.1397)
		(layer "B.Cu")
		(net "SATA3_RX_DN0")
	)
	(segment
		(start 77.1652 -30.8864)
		(end 77.1652 -30.5816)
		(width 0.1016)
		(layer "B.Cu")
		(net "SATA3_RX_DN0")
	)
	(segment
		(start 77.1652 -29.53385)
		(end 77.23505 -29.464)
		(width 0.1016)
		(layer "B.Cu")
		(net "SATA3_RX_DN0")
	)
	(segment
		(start 77.26426 -30.48254)
		(end 77.26426 -30.17774)
		(width 0.1016)
		(layer "B.Cu")
		(net "SATA3_RX_DN0")
	)
	(segment
		(start 75.373484 -27.063954)
		(end 73.170288 -27.063954)
		(width 0.1397)
		(layer "B.Cu")
		(net "SATA3_RX_DN0")
	)
	(segment
		(start 77.23505 -29.4386)
		(end 77.23505 -28.92552)
		(width 0.1397)
		(layer "B.Cu")
		(net "SATA3_RX_DN0")
	)
	(segment
		(start 80.246474 -32.004)
		(end 79.738728 -32.004)
		(width 0.1016)
		(layer "B.Cu")
		(net "SATA3_RX_DN0")
	)
	(segment
		(start 77.1652 -30.5816)
		(end 77.26426 -30.48254)
		(width 0.1016)
		(layer "B.Cu")
		(net "SATA3_RX_DN0")
	)
	(segment
		(start 69.9643 -28.7655)
		(end 68.75145 -29.97835)
		(width 0.1397)
		(layer "B.Cu")
		(net "SATA3_RX_DN0")
	)
	(segment
		(start 67.84975 -29.97835)
		(end 67.6402 -29.7688)
		(width 0.1397)
		(layer "B.Cu")
		(net "SATA3_RX_DN0")
	)
	(segment
		(start 80.525874 -31.7246)
		(end 80.246474 -32.004)
		(width 0.1016)
		(layer "B.Cu")
		(net "SATA3_RX_DN0")
	)
	(segment
		(start 73.170288 -27.063954)
		(end 71.468742 -28.7655)
		(width 0.1397)
		(layer "B.Cu")
		(net "SATA3_RX_DN0")
	)
	(segment
		(start 77.978 -31.6992)
		(end 77.1652 -30.8864)
		(width 0.1016)
		(layer "B.Cu")
		(net "SATA3_RX_DN0")
	)
	(segment
		(start 80.124554 -31.297626)
		(end 80.404208 -31.297626)
		(width 0.1016)
		(layer "B.Cu")
		(net "SATA3_RX_DN0")
	)
	(segment
		(start 77.1652 -30.07868)
		(end 77.1652 -29.53385)
		(width 0.1016)
		(layer "B.Cu")
		(net "SATA3_RX_DN0")
	)
	(segment
		(start 79.433928 -31.6992)
		(end 77.978 -31.6992)
		(width 0.1016)
		(layer "B.Cu")
		(net "SATA3_RX_DN0")
	)
	(segment
		(start 79.738728 -32.004)
		(end 79.433928 -31.6992)
		(width 0.1016)
		(layer "B.Cu")
		(net "SATA3_RX_DN0")
	)
	(segment
		(start 80.525874 -31.419292)
		(end 80.525874 -31.7246)
		(width 0.1016)
		(layer "B.Cu")
		(net "SATA3_RX_DN0")
	)
	(segment
		(start 68.75145 -29.97835)
		(end 67.84975 -29.97835)
		(width 0.1397)
		(layer "B.Cu")
		(net "SATA3_RX_DN0")
	)
	(segment
		(start 77.26426 -30.17774)
		(end 77.1652 -30.07868)
		(width 0.1016)
		(layer "B.Cu")
		(net "SATA3_RX_DN0")
	)
	(segment
		(start 71.468742 -28.7655)
		(end 69.9643 -28.7655)
		(width 0.1397)
		(layer "B.Cu")
		(net "SATA3_RX_DN0")
	)
	(segment
		(start 80.404208 -31.297626)
		(end 80.525874 -31.419292)
		(width 0.1016)
		(layer "B.Cu")
		(net "SATA3_RX_DN0")
	)
	(segment
		(start 17.0688 -45.085)
		(end 16.9926 -45.0088)
		(width 0.508)
		(layer "F.Cu")
		(net "P3V3_STBY_SNB")
	)
	(segment
		(start 16.9926 -45.0088)
		(end 16.9926 -43.6626)
		(width 0.508)
		(layer "F.Cu")
		(net "P3V3_STBY_SNB")
	)
	(segment
		(start 17.0688 -45.085)
		(end 17.7546 -45.085)
		(width 0.508)
		(layer "F.Cu")
		(net "P3V3_STBY_SNB")
	)
	(segment
		(start 17.7546 -45.085)
		(end 18.2372 -44.6024)
		(width 0.508)
		(layer "F.Cu")
		(net "P3V3_STBY_SNB")
	)
	(via
		(at 17.0688 -45.085)
		(size 0.7112)
		(drill 0.3556)
		(layers "F.Cu" "B.Cu")
		(net "P3V3_STBY_SNB")
	)
	(segment
		(start 189.056518 -37.291518)
		(end 189.682628 -37.917628)
		(width 0.2032)
		(layer "F.Cu")
		(net "VR_PVDDR_A_PSI")
	)
	(segment
		(start 189.056518 -36.376102)
		(end 189.056518 -37.291518)
		(width 0.2032)
		(layer "F.Cu")
		(net "VR_PVDDR_A_PSI")
	)
	(segment
		(start 190.881 -39.116)
		(end 189.682628 -37.917628)
		(width 0.2032)
		(layer "F.Cu")
		(net "VR_PVDDR_A_PSI")
	)
	(segment
		(start 190.881 -39.4462)
		(end 190.881 -39.116)
		(width 0.2032)
		(layer "F.Cu")
		(net "VR_PVDDR_A_PSI")
	)
	(via
		(at 189.682628 -37.917628)
		(size 0.7112)
		(drill 0.3556)
		(layers "F.Cu" "B.Cu")
		(net "VR_PVDDR_A_PSI")
	)
	(segment
		(start 112.412272 -33.053528)
		(end 111.894874 -33.053528)
		(width 0.1016)
		(layer "F.Cu")
		(net "M_B_DQ44")
	)
	(segment
		(start 113.7158 -31.0134)
		(end 113.7158 -31.75)
		(width 0.1016)
		(layer "F.Cu")
		(net "M_B_DQ44")
	)
	(segment
		(start 113.7158 -31.75)
		(end 112.412272 -33.053528)
		(width 0.1016)
		(layer "F.Cu")
		(net "M_B_DQ44")
	)
	(segment
		(start 111.357156 -33.591246)
		(end 111.092996 -33.591246)
		(width 0.1016)
		(layer "F.Cu")
		(net "M_B_DQ44")
	)
	(segment
		(start 114.5794 -30.1498)
		(end 113.7158 -31.0134)
		(width 0.1016)
		(layer "F.Cu")
		(net "M_B_DQ44")
	)
	(segment
		(start 175.749966 -2.585212)
		(end 175.3108 -3.024378)
		(width 0.1778)
		(layer "F.Cu")
		(net "M_B_DQ44")
	)
	(segment
		(start 175.749966 -1.68402)
		(end 175.749966 -2.585212)
		(width 0.1778)
		(layer "F.Cu")
		(net "M_B_DQ44")
	)
	(segment
		(start 175.3108 -3.024378)
		(end 175.3108 -3.150616)
		(width 0.1778)
		(layer "F.Cu")
		(net "M_B_DQ44")
	)
	(segment
		(start 175.3108 -3.150616)
		(end 175.285908 -3.175508)
		(width 0.1778)
		(layer "F.Cu")
		(net "M_B_DQ44")
	)
	(segment
		(start 111.092996 -33.591246)
		(end 111.092488 -33.591754)
		(width 0.1016)
		(layer "F.Cu")
		(net "M_B_DQ44")
	)
	(segment
		(start 115.062 -30.1498)
		(end 114.5794 -30.1498)
		(width 0.1016)
		(layer "F.Cu")
		(net "M_B_DQ44")
	)
	(segment
		(start 111.894874 -33.053528)
		(end 111.357156 -33.591246)
		(width 0.1016)
		(layer "F.Cu")
		(net "M_B_DQ44")
	)
	(via
		(at 175.285908 -3.175508)
		(size 0.4318)
		(drill 0.2032)
		(layers "F.Cu" "B.Cu")
		(net "M_B_DQ44")
	)
	(via
		(at 115.062 -30.1498)
		(size 0.4318)
		(drill 0.2032)
		(layers "F.Cu" "B.Cu")
		(net "M_B_DQ44")
	)
	(segment
		(start 175.285908 -3.101086)
		(end 175.285908 -3.175508)
		(width 0.1778)
		(layer "B.Cu")
		(net "M_B_DQ44")
	)
	(segment
		(start 174.850044 -1.690624)
		(end 174.850044 -2.665222)
		(width 0.1778)
		(layer "B.Cu")
		(net "M_B_DQ44")
	)
	(segment
		(start 174.850044 -2.665222)
		(end 175.285908 -3.101086)
		(width 0.1778)
		(layer "B.Cu")
		(net "M_B_DQ44")
	)
	(segment
		(start 151.544782 -26.02738)
		(end 125.113542 -26.02738)
		(width 0.1524)
		(layer "In2.Cu")
		(net "M_B_DQ44")
	)
	(segment
		(start 162.509962 -15.0622)
		(end 151.544782 -26.02738)
		(width 0.1524)
		(layer "In2.Cu")
		(net "M_B_DQ44")
	)
	(segment
		(start 171.97324 -6.986778)
		(end 172.12564 -7.139178)
		(width 0.1524)
		(layer "In2.Cu")
		(net "M_B_DQ44")
	)
	(segment
		(start 171.477432 -10.54481)
		(end 171.26204 -10.54481)
		(width 0.1524)
		(layer "In2.Cu")
		(net "M_B_DQ44")
	)
	(segment
		(start 170.399456 -11.407394)
		(end 170.053508 -11.060938)
		(width 0.1524)
		(layer "In2.Cu")
		(net "M_B_DQ44")
	)
	(segment
		(start 170.614848 -11.407394)
		(end 170.399456 -11.407394)
		(width 0.1524)
		(layer "In2.Cu")
		(net "M_B_DQ44")
	)
	(segment
		(start 170.830748 -10.976102)
		(end 170.830748 -11.191494)
		(width 0.1524)
		(layer "In2.Cu")
		(net "M_B_DQ44")
	)
	(segment
		(start 166.960042 -15.0622)
		(end 162.509962 -15.0622)
		(width 0.1524)
		(layer "In2.Cu")
		(net "M_B_DQ44")
	)
	(segment
		(start 172.12564 -7.139178)
		(end 172.12564 -9.896602)
		(width 0.1524)
		(layer "In2.Cu")
		(net "M_B_DQ44")
	)
	(segment
		(start 172.12564 -9.896602)
		(end 171.477432 -10.54481)
		(width 0.1524)
		(layer "In2.Cu")
		(net "M_B_DQ44")
	)
	(segment
		(start 170.830748 -11.191494)
		(end 170.614848 -11.407394)
		(width 0.1524)
		(layer "In2.Cu")
		(net "M_B_DQ44")
	)
	(segment
		(start 169.838116 -11.060938)
		(end 169.621962 -11.276838)
		(width 0.1524)
		(layer "In2.Cu")
		(net "M_B_DQ44")
	)
	(segment
		(start 116.931186 -28.280614)
		(end 115.062 -30.1498)
		(width 0.1524)
		(layer "In2.Cu")
		(net "M_B_DQ44")
	)
	(segment
		(start 171.017692 -10.300208)
		(end 170.802046 -10.300208)
		(width 0.1524)
		(layer "In2.Cu")
		(net "M_B_DQ44")
	)
	(segment
		(start 122.860308 -28.280614)
		(end 116.931186 -28.280614)
		(width 0.1524)
		(layer "In2.Cu")
		(net "M_B_DQ44")
	)
	(segment
		(start 169.968164 -12.054078)
		(end 166.960042 -15.0622)
		(width 0.1524)
		(layer "In2.Cu")
		(net "M_B_DQ44")
	)
	(segment
		(start 171.5262 -4.548378)
		(end 171.3738 -4.700778)
		(width 0.1524)
		(layer "In2.Cu")
		(net "M_B_DQ44")
	)
	(segment
		(start 170.053508 -11.060938)
		(end 169.838116 -11.060938)
		(width 0.1524)
		(layer "In2.Cu")
		(net "M_B_DQ44")
	)
	(segment
		(start 169.621962 -11.276838)
		(end 169.621962 -11.49223)
		(width 0.1524)
		(layer "In2.Cu")
		(net "M_B_DQ44")
	)
	(segment
		(start 171.3738 -4.700778)
		(end 171.3738 -6.834378)
		(width 0.1524)
		(layer "In2.Cu")
		(net "M_B_DQ44")
	)
	(segment
		(start 170.585892 -10.731246)
		(end 170.830748 -10.976102)
		(width 0.1524)
		(layer "In2.Cu")
		(net "M_B_DQ44")
	)
	(segment
		(start 169.621962 -11.49223)
		(end 169.968164 -11.838686)
		(width 0.1524)
		(layer "In2.Cu")
		(net "M_B_DQ44")
	)
	(segment
		(start 169.968164 -11.838686)
		(end 169.968164 -12.054078)
		(width 0.1524)
		(layer "In2.Cu")
		(net "M_B_DQ44")
	)
	(segment
		(start 175.23587 -3.175508)
		(end 173.863 -4.548378)
		(width 0.1524)
		(layer "In2.Cu")
		(net "M_B_DQ44")
	)
	(segment
		(start 125.113542 -26.02738)
		(end 122.860308 -28.280614)
		(width 0.1524)
		(layer "In2.Cu")
		(net "M_B_DQ44")
	)
	(segment
		(start 173.863 -4.548378)
		(end 171.5262 -4.548378)
		(width 0.1524)
		(layer "In2.Cu")
		(net "M_B_DQ44")
	)
	(segment
		(start 175.285908 -3.175508)
		(end 175.23587 -3.175508)
		(width 0.1524)
		(layer "In2.Cu")
		(net "M_B_DQ44")
	)
	(segment
		(start 170.802046 -10.300208)
		(end 170.585892 -10.515854)
		(width 0.1524)
		(layer "In2.Cu")
		(net "M_B_DQ44")
	)
	(segment
		(start 171.3738 -6.834378)
		(end 171.5262 -6.986778)
		(width 0.1524)
		(layer "In2.Cu")
		(net "M_B_DQ44")
	)
	(segment
		(start 171.5262 -6.986778)
		(end 171.97324 -6.986778)
		(width 0.1524)
		(layer "In2.Cu")
		(net "M_B_DQ44")
	)
	(segment
		(start 170.585892 -10.515854)
		(end 170.585892 -10.731246)
		(width 0.1524)
		(layer "In2.Cu")
		(net "M_B_DQ44")
	)
	(segment
		(start 171.26204 -10.54481)
		(end 171.017692 -10.300208)
		(width 0.1524)
		(layer "In2.Cu")
		(net "M_B_DQ44")
	)
	(segment
		(start 13.371322 -35.948874)
		(end 14.676374 -35.948874)
		(width 0.254)
		(layer "F.Cu")
		(net "P3V3_STBY_ROVP")
	)
	(segment
		(start 14.676374 -35.948874)
		(end 14.732 -36.0045)
		(width 0.254)
		(layer "F.Cu")
		(net "P3V3_STBY_ROVP")
	)
	(via
		(at 14.732 -36.0045)
		(size 0.508)
		(drill 0.254)
		(layers "F.Cu" "B.Cu")
		(net "P3V3_STBY_ROVP")
	)
	(via
		(at 15.748 -36.195)
		(size 0.7112)
		(drill 0.3556)
		(layers "F.Cu" "B.Cu")
		(net "P3V3_STBY_ROVP")
	)
	(segment
		(start 14.732 -36.0045)
		(end 14.9225 -36.195)
		(width 0.254)
		(layer "B.Cu")
		(net "P3V3_STBY_ROVP")
	)
	(segment
		(start 14.9225 -36.195)
		(end 15.748 -36.195)
		(width 0.254)
		(layer "B.Cu")
		(net "P3V3_STBY_ROVP")
	)
	(segment
		(start 16.3068 -33.655)
		(end 16.3068 -34.3916)
		(width 0.254)
		(layer "B.Cu")
		(net "P3V3_STBY_ROVP")
	)
	(segment
		(start 16.3068 -34.3916)
		(end 16.3322 -34.417)
		(width 0.254)
		(layer "B.Cu")
		(net "P3V3_STBY_ROVP")
	)
	(segment
		(start 15.748 -36.195)
		(end 15.875 -36.195)
		(width 0.254)
		(layer "B.Cu")
		(net "P3V3_STBY_ROVP")
	)
	(segment
		(start 16.3322 -35.7378)
		(end 16.3322 -35.179)
		(width 0.254)
		(layer "B.Cu")
		(net "P3V3_STBY_ROVP")
	)
	(segment
		(start 16.3322 -34.417)
		(end 16.3322 -35.179)
		(width 0.254)
		(layer "B.Cu")
		(net "P3V3_STBY_ROVP")
	)
	(segment
		(start 15.875 -36.195)
		(end 16.3322 -35.7378)
		(width 0.254)
		(layer "B.Cu")
		(net "P3V3_STBY_ROVP")
	)
	(segment
		(start 195.9864 -38.6588)
		(end 196.5706 -39.243)
		(width 0.508)
		(layer "F.Cu")
		(net "VR_PVDDR_A_GL1")
	)
	(segment
		(start 195.4276 -34.7472)
		(end 195.980558 -34.7472)
		(width 0.508)
		(layer "F.Cu")
		(net "VR_PVDDR_A_GL1")
	)
	(segment
		(start 193.189098 -35.1028)
		(end 192.700656 -35.1028)
		(width 0.2032)
		(layer "F.Cu")
		(net "VR_PVDDR_A_GL1")
	)
	(segment
		(start 195.980558 -34.7472)
		(end 196.6976 -35.464242)
		(width 0.508)
		(layer "F.Cu")
		(net "VR_PVDDR_A_GL1")
	)
	(segment
		(start 195.9864 -37.243766)
		(end 195.9864 -38.6588)
		(width 0.508)
		(layer "F.Cu")
		(net "VR_PVDDR_A_GL1")
	)
	(segment
		(start 193.973196 -35.1028)
		(end 193.189098 -35.1028)
		(width 0.508)
		(layer "F.Cu")
		(net "VR_PVDDR_A_GL1")
	)
	(segment
		(start 196.6976 -35.464242)
		(end 196.6976 -36.532566)
		(width 0.508)
		(layer "F.Cu")
		(net "VR_PVDDR_A_GL1")
	)
	(segment
		(start 192.173606 -34.57575)
		(end 191.656716 -34.57575)
		(width 0.2032)
		(layer "F.Cu")
		(net "VR_PVDDR_A_GL1")
	)
	(segment
		(start 192.700656 -35.1028)
		(end 192.173606 -34.57575)
		(width 0.2032)
		(layer "F.Cu")
		(net "VR_PVDDR_A_GL1")
	)
	(segment
		(start 194.328796 -34.7472)
		(end 193.973196 -35.1028)
		(width 0.508)
		(layer "F.Cu")
		(net "VR_PVDDR_A_GL1")
	)
	(segment
		(start 196.6976 -36.532566)
		(end 195.9864 -37.243766)
		(width 0.508)
		(layer "F.Cu")
		(net "VR_PVDDR_A_GL1")
	)
	(segment
		(start 195.4276 -34.7472)
		(end 194.328796 -34.7472)
		(width 0.508)
		(layer "F.Cu")
		(net "VR_PVDDR_A_GL1")
	)
	(via
		(at 195.4276 -34.7472)
		(size 0.7112)
		(drill 0.3556)
		(layers "F.Cu" "B.Cu")
		(net "VR_PVDDR_A_GL1")
	)
	(segment
		(start 34.6964 -23.6982)
		(end 34.83991 -23.55469)
		(width 0.1143)
		(layer "F.Cu")
		(net "XDP_DFX_PORT10")
	)
	(segment
		(start 79.614014 -45.83811)
		(end 79.779368 -46.003464)
		(width 0.1143)
		(layer "F.Cu")
		(net "XDP_DFX_PORT10")
	)
	(segment
		(start 78.887066 -46.20006)
		(end 79.249016 -45.83811)
		(width 0.1143)
		(layer "F.Cu")
		(net "XDP_DFX_PORT10")
	)
	(segment
		(start 78.887066 -46.4312)
		(end 78.887066 -46.20006)
		(width 0.1143)
		(layer "F.Cu")
		(net "XDP_DFX_PORT10")
	)
	(segment
		(start 80.64119 -46.306994)
		(end 80.950308 -46.306994)
		(width 0.1143)
		(layer "F.Cu")
		(net "XDP_DFX_PORT10")
	)
	(segment
		(start 79.779368 -46.003464)
		(end 80.33766 -46.003464)
		(width 0.1143)
		(layer "F.Cu")
		(net "XDP_DFX_PORT10")
	)
	(segment
		(start 80.33766 -46.003464)
		(end 80.64119 -46.306994)
		(width 0.1143)
		(layer "F.Cu")
		(net "XDP_DFX_PORT10")
	)
	(segment
		(start 34.83991 -23.55469)
		(end 36.37788 -23.55469)
		(width 0.1143)
		(layer "F.Cu")
		(net "XDP_DFX_PORT10")
	)
	(segment
		(start 79.249016 -45.83811)
		(end 79.614014 -45.83811)
		(width 0.1143)
		(layer "F.Cu")
		(net "XDP_DFX_PORT10")
	)
	(via
		(at 34.6964 -23.6982)
		(size 0.508)
		(drill 0.254)
		(layers "F.Cu" "B.Cu")
		(net "XDP_DFX_PORT10")
	)
	(via
		(at 79.26578 -45.541184)
		(size 0.7112)
		(drill 0.3556)
		(layers "F.Cu" "B.Cu")
		(net "XDP_DFX_PORT10")
	)
	(via
		(at 78.887066 -46.4312)
		(size 0.508)
		(drill 0.254)
		(layers "F.Cu" "B.Cu")
		(net "XDP_DFX_PORT10")
	)
	(segment
		(start 78.887066 -46.254162)
		(end 79.303118 -45.83811)
		(width 0.1143)
		(layer "B.Cu")
		(net "XDP_DFX_PORT10")
	)
	(segment
		(start 78.887066 -46.4312)
		(end 78.887066 -46.254162)
		(width 0.1143)
		(layer "B.Cu")
		(net "XDP_DFX_PORT10")
	)
	(segment
		(start 79.303118 -45.83811)
		(end 79.303118 -45.578522)
		(width 0.1143)
		(layer "B.Cu")
		(net "XDP_DFX_PORT10")
	)
	(segment
		(start 79.303118 -45.578522)
		(end 79.26578 -45.541184)
		(width 0.1143)
		(layer "B.Cu")
		(net "XDP_DFX_PORT10")
	)
	(segment
		(start 69.153786 -46.41215)
		(end 64.620394 -46.41215)
		(width 0.0889)
		(layer "In7.Cu")
		(net "XDP_DFX_PORT10")
	)
	(segment
		(start 58.97499 -42.99712)
		(end 58.68289 -42.70502)
		(width 0.0889)
		(layer "In7.Cu")
		(net "XDP_DFX_PORT10")
	)
	(segment
		(start 34.91865 -23.92045)
		(end 34.6964 -23.6982)
		(width 0.0889)
		(layer "In7.Cu")
		(net "XDP_DFX_PORT10")
	)
	(segment
		(start 78.887066 -46.4312)
		(end 78.553564 -46.764702)
		(width 0.0889)
		(layer "In7.Cu")
		(net "XDP_DFX_PORT10")
	)
	(segment
		(start 73.970642 -46.866302)
		(end 73.68794 -46.5836)
		(width 0.0889)
		(layer "In7.Cu")
		(net "XDP_DFX_PORT10")
	)
	(segment
		(start 74.894948 -46.866302)
		(end 73.970642 -46.866302)
		(width 0.0889)
		(layer "In7.Cu")
		(net "XDP_DFX_PORT10")
	)
	(segment
		(start 48.09998 -41.78935)
		(end 46.638464 -40.327834)
		(width 0.0889)
		(layer "In7.Cu")
		(net "XDP_DFX_PORT10")
	)
	(segment
		(start 59.673998 -42.672)
		(end 59.348878 -42.99712)
		(width 0.0889)
		(layer "In7.Cu")
		(net "XDP_DFX_PORT10")
	)
	(segment
		(start 45.052234 -40.327834)
		(end 39.40175 -34.67735)
		(width 0.0889)
		(layer "In7.Cu")
		(net "XDP_DFX_PORT10")
	)
	(segment
		(start 74.996802 -46.764702)
		(end 74.894948 -46.866302)
		(width 0.0889)
		(layer "In7.Cu")
		(net "XDP_DFX_PORT10")
	)
	(segment
		(start 34.91865 -24.901398)
		(end 34.91865 -23.92045)
		(width 0.0889)
		(layer "In7.Cu")
		(net "XDP_DFX_PORT10")
	)
	(segment
		(start 38.105842 -34.67735)
		(end 34.22015 -30.791658)
		(width 0.0889)
		(layer "In7.Cu")
		(net "XDP_DFX_PORT10")
	)
	(segment
		(start 34.22015 -25.599898)
		(end 34.91865 -24.901398)
		(width 0.0889)
		(layer "In7.Cu")
		(net "XDP_DFX_PORT10")
	)
	(segment
		(start 64.620394 -46.41215)
		(end 63.652654 -45.44441)
		(width 0.0889)
		(layer "In7.Cu")
		(net "XDP_DFX_PORT10")
	)
	(segment
		(start 58.68289 -42.70502)
		(end 57.74436 -42.70502)
		(width 0.0889)
		(layer "In7.Cu")
		(net "XDP_DFX_PORT10")
	)
	(segment
		(start 63.652654 -45.44441)
		(end 62.89421 -45.44441)
		(width 0.0889)
		(layer "In7.Cu")
		(net "XDP_DFX_PORT10")
	)
	(segment
		(start 49.149508 -41.78935)
		(end 48.09998 -41.78935)
		(width 0.0889)
		(layer "In7.Cu")
		(net "XDP_DFX_PORT10")
	)
	(segment
		(start 50.159158 -42.799)
		(end 49.149508 -41.78935)
		(width 0.0889)
		(layer "In7.Cu")
		(net "XDP_DFX_PORT10")
	)
	(segment
		(start 46.638464 -40.327834)
		(end 45.052234 -40.327834)
		(width 0.0889)
		(layer "In7.Cu")
		(net "XDP_DFX_PORT10")
	)
	(segment
		(start 39.40175 -34.67735)
		(end 38.105842 -34.67735)
		(width 0.0889)
		(layer "In7.Cu")
		(net "XDP_DFX_PORT10")
	)
	(segment
		(start 57.65038 -42.799)
		(end 50.159158 -42.799)
		(width 0.0889)
		(layer "In7.Cu")
		(net "XDP_DFX_PORT10")
	)
	(segment
		(start 73.68794 -46.5836)
		(end 69.325236 -46.5836)
		(width 0.0889)
		(layer "In7.Cu")
		(net "XDP_DFX_PORT10")
	)
	(segment
		(start 62.89421 -45.44441)
		(end 60.1218 -42.672)
		(width 0.0889)
		(layer "In7.Cu")
		(net "XDP_DFX_PORT10")
	)
	(segment
		(start 69.325236 -46.5836)
		(end 69.153786 -46.41215)
		(width 0.0889)
		(layer "In7.Cu")
		(net "XDP_DFX_PORT10")
	)
	(segment
		(start 78.553564 -46.764702)
		(end 74.996802 -46.764702)
		(width 0.0889)
		(layer "In7.Cu")
		(net "XDP_DFX_PORT10")
	)
	(segment
		(start 34.22015 -30.791658)
		(end 34.22015 -25.599898)
		(width 0.0889)
		(layer "In7.Cu")
		(net "XDP_DFX_PORT10")
	)
	(segment
		(start 60.1218 -42.672)
		(end 59.673998 -42.672)
		(width 0.0889)
		(layer "In7.Cu")
		(net "XDP_DFX_PORT10")
	)
	(segment
		(start 59.348878 -42.99712)
		(end 58.97499 -42.99712)
		(width 0.0889)
		(layer "In7.Cu")
		(net "XDP_DFX_PORT10")
	)
	(segment
		(start 57.74436 -42.70502)
		(end 57.65038 -42.799)
		(width 0.0889)
		(layer "In7.Cu")
		(net "XDP_DFX_PORT10")
	)
	(segment
		(start 78.944724 -39.445184)
		(end 79.700882 -39.445184)
		(width 0.1143)
		(layer "F.Cu")
		(net "XDP_SOC_CPU_TDO")
	)
	(segment
		(start 80.0862 -39.059866)
		(end 80.0862 -38.733984)
		(width 0.1143)
		(layer "F.Cu")
		(net "XDP_SOC_CPU_TDO")
	)
	(segment
		(start 32.3596 -34.29)
		(end 33.0962 -34.29)
		(width 0.1143)
		(layer "F.Cu")
		(net "XDP_SOC_CPU_TDO")
	)
	(segment
		(start 33.1724 -34.2138)
		(end 33.0962 -34.29)
		(width 0.1143)
		(layer "F.Cu")
		(net "XDP_SOC_CPU_TDO")
	)
	(segment
		(start 75.3872 -38.481)
		(end 75.692 -38.481)
		(width 0.1143)
		(layer "F.Cu")
		(net "XDP_SOC_CPU_TDO")
	)
	(segment
		(start 32.3088 -34.2392)
		(end 32.3596 -34.29)
		(width 0.1143)
		(layer "F.Cu")
		(net "XDP_SOC_CPU_TDO")
	)
	(segment
		(start 78.149196 -38.64737)
		(end 78.541118 -39.039292)
		(width 0.1143)
		(layer "F.Cu")
		(net "XDP_SOC_CPU_TDO")
	)
	(segment
		(start 80.992218 -38.312344)
		(end 81.097628 -38.417754)
		(width 0.1143)
		(layer "F.Cu")
		(net "XDP_SOC_CPU_TDO")
	)
	(segment
		(start 77.372718 -39.086028)
		(end 77.81163 -38.64737)
		(width 0.1143)
		(layer "F.Cu")
		(net "XDP_SOC_CPU_TDO")
	)
	(segment
		(start 78.5495 -39.04996)
		(end 78.944724 -39.445184)
		(width 0.1143)
		(layer "F.Cu")
		(net "XDP_SOC_CPU_TDO")
	)
	(segment
		(start 75.692 -38.481)
		(end 76.297028 -39.086028)
		(width 0.1143)
		(layer "F.Cu")
		(net "XDP_SOC_CPU_TDO")
	)
	(segment
		(start 80.50784 -38.312344)
		(end 80.992218 -38.312344)
		(width 0.1143)
		(layer "F.Cu")
		(net "XDP_SOC_CPU_TDO")
	)
	(segment
		(start 76.297028 -39.086028)
		(end 77.372718 -39.086028)
		(width 0.1143)
		(layer "F.Cu")
		(net "XDP_SOC_CPU_TDO")
	)
	(segment
		(start 159.9438 -49.53)
		(end 159.9438 -50.3682)
		(width 0.1143)
		(layer "F.Cu")
		(net "XDP_SOC_CPU_TDO")
	)
	(segment
		(start 78.541118 -39.039292)
		(end 78.54188 -39.039292)
		(width 0.1143)
		(layer "F.Cu")
		(net "XDP_SOC_CPU_TDO")
	)
	(segment
		(start 78.54188 -39.039292)
		(end 78.5495 -39.046912)
		(width 0.1143)
		(layer "F.Cu")
		(net "XDP_SOC_CPU_TDO")
	)
	(segment
		(start 77.81163 -38.64737)
		(end 78.149196 -38.64737)
		(width 0.1143)
		(layer "F.Cu")
		(net "XDP_SOC_CPU_TDO")
	)
	(segment
		(start 33.1724 -33.4772)
		(end 33.1724 -34.2138)
		(width 0.1143)
		(layer "F.Cu")
		(net "XDP_SOC_CPU_TDO")
	)
	(segment
		(start 78.5495 -39.046912)
		(end 78.5495 -39.04996)
		(width 0.1143)
		(layer "F.Cu")
		(net "XDP_SOC_CPU_TDO")
	)
	(segment
		(start 160.7058 -48.768)
		(end 159.9438 -49.53)
		(width 0.1143)
		(layer "F.Cu")
		(net "XDP_SOC_CPU_TDO")
	)
	(segment
		(start 80.0862 -38.733984)
		(end 80.50784 -38.312344)
		(width 0.1143)
		(layer "F.Cu")
		(net "XDP_SOC_CPU_TDO")
	)
	(segment
		(start 79.700882 -39.445184)
		(end 80.0862 -39.059866)
		(width 0.1143)
		(layer "F.Cu")
		(net "XDP_SOC_CPU_TDO")
	)
	(via
		(at 33.0962 -34.29)
		(size 0.508)
		(drill 0.254)
		(layers "F.Cu" "B.Cu")
		(net "XDP_SOC_CPU_TDO")
	)
	(via
		(at 67.88785 -64.3636)
		(size 0.508)
		(drill 0.254)
		(layers "F.Cu" "B.Cu")
		(net "XDP_SOC_CPU_TDO")
	)
	(via
		(at 53.3146 -30.7086)
		(size 0.508)
		(drill 0.254)
		(layers "F.Cu" "B.Cu")
		(net "XDP_SOC_CPU_TDO")
	)
	(via
		(at 78.54188 -39.039292)
		(size 0.4318)
		(drill 0.2032)
		(layers "F.Cu" "B.Cu")
		(net "XDP_SOC_CPU_TDO")
	)
	(via
		(at 188.9252 -54.8386)
		(size 0.508)
		(drill 0.254)
		(layers "F.Cu" "B.Cu")
		(net "XDP_SOC_CPU_TDO")
	)
	(via
		(at 159.9438 -50.3682)
		(size 0.508)
		(drill 0.254)
		(layers "F.Cu" "B.Cu")
		(net "XDP_SOC_CPU_TDO")
	)
	(segment
		(start 32.4866 -33.6804)
		(end 33.0962 -34.29)
		(width 0.1143)
		(layer "B.Cu")
		(net "XDP_SOC_CPU_TDO")
	)
	(segment
		(start 31.877 -33.6804)
		(end 32.4866 -33.6804)
		(width 0.1143)
		(layer "B.Cu")
		(net "XDP_SOC_CPU_TDO")
	)
	(segment
		(start 37.944298 -34.6075)
		(end 40.92575 -37.588952)
		(width 0.0889)
		(layer "In2.Cu")
		(net "XDP_SOC_CPU_TDO")
	)
	(segment
		(start 49.621694 -48.0822)
		(end 50.510694 -48.9712)
		(width 0.0889)
		(layer "In2.Cu")
		(net "XDP_SOC_CPU_TDO")
	)
	(segment
		(start 33.47085 -34.66465)
		(end 34.168588 -34.66465)
		(width 0.0889)
		(layer "In2.Cu")
		(net "XDP_SOC_CPU_TDO")
	)
	(segment
		(start 63.9318 -59.1058)
		(end 67.88785 -63.06185)
		(width 0.0889)
		(layer "In2.Cu")
		(net "XDP_SOC_CPU_TDO")
	)
	(segment
		(start 41.5798 -39.6494)
		(end 41.5798 -42.2148)
		(width 0.0889)
		(layer "In2.Cu")
		(net "XDP_SOC_CPU_TDO")
	)
	(segment
		(start 55.65394 -52.959)
		(end 61.80074 -59.1058)
		(width 0.0889)
		(layer "In2.Cu")
		(net "XDP_SOC_CPU_TDO")
	)
	(segment
		(start 51.043586 -48.9712)
		(end 53.862986 -51.7906)
		(width 0.0889)
		(layer "In2.Cu")
		(net "XDP_SOC_CPU_TDO")
	)
	(segment
		(start 61.80074 -59.1058)
		(end 63.9318 -59.1058)
		(width 0.0889)
		(layer "In2.Cu")
		(net "XDP_SOC_CPU_TDO")
	)
	(segment
		(start 34.225738 -34.6075)
		(end 37.944298 -34.6075)
		(width 0.0889)
		(layer "In2.Cu")
		(net "XDP_SOC_CPU_TDO")
	)
	(segment
		(start 43.848528 -43.434)
		(end 46.090078 -43.434)
		(width 0.0889)
		(layer "In2.Cu")
		(net "XDP_SOC_CPU_TDO")
	)
	(segment
		(start 40.92575 -38.99535)
		(end 41.5798 -39.6494)
		(width 0.0889)
		(layer "In2.Cu")
		(net "XDP_SOC_CPU_TDO")
	)
	(segment
		(start 42.5577 -43.1927)
		(end 43.607228 -43.1927)
		(width 0.0889)
		(layer "In2.Cu")
		(net "XDP_SOC_CPU_TDO")
	)
	(segment
		(start 40.92575 -37.588952)
		(end 40.92575 -38.99535)
		(width 0.0889)
		(layer "In2.Cu")
		(net "XDP_SOC_CPU_TDO")
	)
	(segment
		(start 34.168588 -34.66465)
		(end 34.225738 -34.6075)
		(width 0.0889)
		(layer "In2.Cu")
		(net "XDP_SOC_CPU_TDO")
	)
	(segment
		(start 53.862986 -51.7906)
		(end 53.862986 -51.908202)
		(width 0.0889)
		(layer "In2.Cu")
		(net "XDP_SOC_CPU_TDO")
	)
	(segment
		(start 43.607228 -43.1927)
		(end 43.848528 -43.434)
		(width 0.0889)
		(layer "In2.Cu")
		(net "XDP_SOC_CPU_TDO")
	)
	(segment
		(start 46.407324 -43.751246)
		(end 46.407324 -45.619924)
		(width 0.0889)
		(layer "In2.Cu")
		(net "XDP_SOC_CPU_TDO")
	)
	(segment
		(start 33.0962 -34.29)
		(end 33.47085 -34.66465)
		(width 0.0889)
		(layer "In2.Cu")
		(net "XDP_SOC_CPU_TDO")
	)
	(segment
		(start 46.090078 -43.434)
		(end 46.407324 -43.751246)
		(width 0.0889)
		(layer "In2.Cu")
		(net "XDP_SOC_CPU_TDO")
	)
	(segment
		(start 46.407324 -45.619924)
		(end 48.8696 -48.0822)
		(width 0.0889)
		(layer "In2.Cu")
		(net "XDP_SOC_CPU_TDO")
	)
	(segment
		(start 50.510694 -48.9712)
		(end 51.043586 -48.9712)
		(width 0.0889)
		(layer "In2.Cu")
		(net "XDP_SOC_CPU_TDO")
	)
	(segment
		(start 54.913784 -52.959)
		(end 55.65394 -52.959)
		(width 0.0889)
		(layer "In2.Cu")
		(net "XDP_SOC_CPU_TDO")
	)
	(segment
		(start 67.88785 -63.06185)
		(end 67.88785 -64.3636)
		(width 0.0889)
		(layer "In2.Cu")
		(net "XDP_SOC_CPU_TDO")
	)
	(segment
		(start 41.5798 -42.2148)
		(end 42.5577 -43.1927)
		(width 0.0889)
		(layer "In2.Cu")
		(net "XDP_SOC_CPU_TDO")
	)
	(segment
		(start 48.8696 -48.0822)
		(end 49.621694 -48.0822)
		(width 0.0889)
		(layer "In2.Cu")
		(net "XDP_SOC_CPU_TDO")
	)
	(segment
		(start 53.862986 -51.908202)
		(end 54.913784 -52.959)
		(width 0.0889)
		(layer "In2.Cu")
		(net "XDP_SOC_CPU_TDO")
	)
	(segment
		(start 45.7835 -35.187128)
		(end 45.7835 -37.632894)
		(width 0.0889)
		(layer "In4.Cu")
		(net "XDP_SOC_CPU_TDO")
	)
	(segment
		(start 69.00545 -65.4812)
		(end 86.081108 -65.4812)
		(width 0.0889)
		(layer "In4.Cu")
		(net "XDP_SOC_CPU_TDO")
	)
	(segment
		(start 91.485212 -70.885304)
		(end 190.387478 -70.885304)
		(width 0.0889)
		(layer "In4.Cu")
		(net "XDP_SOC_CPU_TDO")
	)
	(segment
		(start 86.081108 -65.4812)
		(end 91.485212 -70.885304)
		(width 0.0889)
		(layer "In4.Cu")
		(net "XDP_SOC_CPU_TDO")
	)
	(segment
		(start 49.8729 -32.6517)
		(end 48.318928 -32.6517)
		(width 0.0889)
		(layer "In4.Cu")
		(net "XDP_SOC_CPU_TDO")
	)
	(segment
		(start 34.92246 -36.804346)
		(end 33.545018 -36.804346)
		(width 0.0889)
		(layer "In4.Cu")
		(net "XDP_SOC_CPU_TDO")
	)
	(segment
		(start 52.0573 -30.4673)
		(end 49.8729 -32.6517)
		(width 0.0889)
		(layer "In4.Cu")
		(net "XDP_SOC_CPU_TDO")
	)
	(segment
		(start 188.1124 -55.9816)
		(end 188.9252 -55.1688)
		(width 0.0889)
		(layer "In4.Cu")
		(net "XDP_SOC_CPU_TDO")
	)
	(segment
		(start 188.9252 -55.1688)
		(end 188.9252 -54.8386)
		(width 0.0889)
		(layer "In4.Cu")
		(net "XDP_SOC_CPU_TDO")
	)
	(segment
		(start 190.7286 -65.6844)
		(end 192.499488 -63.913512)
		(width 0.0889)
		(layer "In4.Cu")
		(net "XDP_SOC_CPU_TDO")
	)
	(segment
		(start 192.499488 -61.054488)
		(end 188.1124 -56.6674)
		(width 0.0889)
		(layer "In4.Cu")
		(net "XDP_SOC_CPU_TDO")
	)
	(segment
		(start 45.7835 -37.632894)
		(end 45.195744 -38.22065)
		(width 0.0889)
		(layer "In4.Cu")
		(net "XDP_SOC_CPU_TDO")
	)
	(segment
		(start 35.704526 -36.02228)
		(end 34.92246 -36.804346)
		(width 0.0889)
		(layer "In4.Cu")
		(net "XDP_SOC_CPU_TDO")
	)
	(segment
		(start 192.499488 -63.913512)
		(end 192.499488 -61.054488)
		(width 0.0889)
		(layer "In4.Cu")
		(net "XDP_SOC_CPU_TDO")
	)
	(segment
		(start 45.195744 -38.22065)
		(end 44.821856 -38.22065)
		(width 0.0889)
		(layer "In4.Cu")
		(net "XDP_SOC_CPU_TDO")
	)
	(segment
		(start 53.3146 -30.7086)
		(end 53.0733 -30.4673)
		(width 0.0889)
		(layer "In4.Cu")
		(net "XDP_SOC_CPU_TDO")
	)
	(segment
		(start 33.545018 -36.804346)
		(end 33.013396 -36.272724)
		(width 0.0889)
		(layer "In4.Cu")
		(net "XDP_SOC_CPU_TDO")
	)
	(segment
		(start 42.623486 -36.02228)
		(end 35.704526 -36.02228)
		(width 0.0889)
		(layer "In4.Cu")
		(net "XDP_SOC_CPU_TDO")
	)
	(segment
		(start 190.387478 -70.885304)
		(end 190.7286 -70.544182)
		(width 0.0889)
		(layer "In4.Cu")
		(net "XDP_SOC_CPU_TDO")
	)
	(segment
		(start 188.1124 -56.6674)
		(end 188.1124 -55.9816)
		(width 0.0889)
		(layer "In4.Cu")
		(net "XDP_SOC_CPU_TDO")
	)
	(segment
		(start 48.318928 -32.6517)
		(end 45.7835 -35.187128)
		(width 0.0889)
		(layer "In4.Cu")
		(net "XDP_SOC_CPU_TDO")
	)
	(segment
		(start 33.013396 -36.272724)
		(end 33.013396 -34.372804)
		(width 0.0889)
		(layer "In4.Cu")
		(net "XDP_SOC_CPU_TDO")
	)
	(segment
		(start 44.821856 -38.22065)
		(end 42.623486 -36.02228)
		(width 0.0889)
		(layer "In4.Cu")
		(net "XDP_SOC_CPU_TDO")
	)
	(segment
		(start 67.88785 -64.3636)
		(end 69.00545 -65.4812)
		(width 0.0889)
		(layer "In4.Cu")
		(net "XDP_SOC_CPU_TDO")
	)
	(segment
		(start 190.7286 -70.544182)
		(end 190.7286 -65.6844)
		(width 0.0889)
		(layer "In4.Cu")
		(net "XDP_SOC_CPU_TDO")
	)
	(segment
		(start 53.0733 -30.4673)
		(end 52.0573 -30.4673)
		(width 0.0889)
		(layer "In4.Cu")
		(net "XDP_SOC_CPU_TDO")
	)
	(segment
		(start 33.013396 -34.372804)
		(end 33.0962 -34.29)
		(width 0.0889)
		(layer "In4.Cu")
		(net "XDP_SOC_CPU_TDO")
	)
	(segment
		(start 54.090316 -30.7086)
		(end 53.3146 -30.7086)
		(width 0.0889)
		(layer "In7.Cu")
		(net "XDP_SOC_CPU_TDO")
	)
	(segment
		(start 66.437764 -32.3723)
		(end 65.066164 -31.0007)
		(width 0.0889)
		(layer "In7.Cu")
		(net "XDP_SOC_CPU_TDO")
	)
	(segment
		(start 74.9046 -34.83864)
		(end 74.9046 -34.39668)
		(width 0.0889)
		(layer "In7.Cu")
		(net "XDP_SOC_CPU_TDO")
	)
	(segment
		(start 54.382416 -31.0007)
		(end 54.090316 -30.7086)
		(width 0.0889)
		(layer "In7.Cu")
		(net "XDP_SOC_CPU_TDO")
	)
	(segment
		(start 73.5457 -33.03778)
		(end 73.5457 -32.792162)
		(width 0.0889)
		(layer "In7.Cu")
		(net "XDP_SOC_CPU_TDO")
	)
	(segment
		(start 78.566518 -39.014654)
		(end 78.566518 -38.642544)
		(width 0.0889)
		(layer "In7.Cu")
		(net "XDP_SOC_CPU_TDO")
	)
	(segment
		(start 74.9046 -34.39668)
		(end 73.5457 -33.03778)
		(width 0.0889)
		(layer "In7.Cu")
		(net "XDP_SOC_CPU_TDO")
	)
	(segment
		(start 73.125838 -32.3723)
		(end 66.437764 -32.3723)
		(width 0.0889)
		(layer "In7.Cu")
		(net "XDP_SOC_CPU_TDO")
	)
	(segment
		(start 76.211938 -36.68395)
		(end 75.78725 -36.259262)
		(width 0.0889)
		(layer "In7.Cu")
		(net "XDP_SOC_CPU_TDO")
	)
	(segment
		(start 78.566518 -38.642544)
		(end 76.607924 -36.68395)
		(width 0.0889)
		(layer "In7.Cu")
		(net "XDP_SOC_CPU_TDO")
	)
	(segment
		(start 75.78725 -36.259262)
		(end 75.78725 -35.72129)
		(width 0.0889)
		(layer "In7.Cu")
		(net "XDP_SOC_CPU_TDO")
	)
	(segment
		(start 75.78725 -35.72129)
		(end 74.9046 -34.83864)
		(width 0.0889)
		(layer "In7.Cu")
		(net "XDP_SOC_CPU_TDO")
	)
	(segment
		(start 76.607924 -36.68395)
		(end 76.211938 -36.68395)
		(width 0.0889)
		(layer "In7.Cu")
		(net "XDP_SOC_CPU_TDO")
	)
	(segment
		(start 73.5457 -32.792162)
		(end 73.125838 -32.3723)
		(width 0.0889)
		(layer "In7.Cu")
		(net "XDP_SOC_CPU_TDO")
	)
	(segment
		(start 65.066164 -31.0007)
		(end 54.382416 -31.0007)
		(width 0.0889)
		(layer "In7.Cu")
		(net "XDP_SOC_CPU_TDO")
	)
	(segment
		(start 78.54188 -39.039292)
		(end 78.566518 -39.014654)
		(width 0.0889)
		(layer "In7.Cu")
		(net "XDP_SOC_CPU_TDO")
	)
	(segment
		(start 159.9438 -50.3682)
		(end 164.5793 -55.0037)
		(width 0.0889)
		(layer "In9.Cu")
		(net "XDP_SOC_CPU_TDO")
	)
	(segment
		(start 187.722256 -55.39105)
		(end 188.14415 -55.39105)
		(width 0.0889)
		(layer "In9.Cu")
		(net "XDP_SOC_CPU_TDO")
	)
	(segment
		(start 188.6966 -54.8386)
		(end 188.9252 -54.8386)
		(width 0.0889)
		(layer "In9.Cu")
		(net "XDP_SOC_CPU_TDO")
	)
	(segment
		(start 188.14415 -55.39105)
		(end 188.6966 -54.8386)
		(width 0.0889)
		(layer "In9.Cu")
		(net "XDP_SOC_CPU_TDO")
	)
	(segment
		(start 187.334906 -55.0037)
		(end 187.722256 -55.39105)
		(width 0.0889)
		(layer "In9.Cu")
		(net "XDP_SOC_CPU_TDO")
	)
	(segment
		(start 164.5793 -55.0037)
		(end 187.334906 -55.0037)
		(width 0.0889)
		(layer "In9.Cu")
		(net "XDP_SOC_CPU_TDO")
	)
	(segment
		(start 9.525 -31.5722)
		(end 10.287 -31.5722)
		(width 0.508)
		(layer "F.Cu")
		(net "P3V3_STBY_VREG")
	)
	(segment
		(start 8.00608 -35.948874)
		(end 7.922006 -35.8648)
		(width 0.3048)
		(layer "F.Cu")
		(net "P3V3_STBY_VREG")
	)
	(segment
		(start 7.922006 -35.8648)
		(end 7.5438 -35.8648)
		(width 0.3048)
		(layer "F.Cu")
		(net "P3V3_STBY_VREG")
	)
	(segment
		(start 8.726678 -35.948874)
		(end 8.00608 -35.948874)
		(width 0.3048)
		(layer "F.Cu")
		(net "P3V3_STBY_VREG")
	)
	(via
		(at 7.5438 -35.8648)
		(size 0.508)
		(drill 0.254)
		(layers "F.Cu" "B.Cu")
		(net "P3V3_STBY_VREG")
	)
	(via
		(at 6.5278 -34.29)
		(size 0.7112)
		(drill 0.3556)
		(layers "F.Cu" "B.Cu")
		(net "P3V3_STBY_VREG")
	)
	(via
		(at 10.287 -31.5722)
		(size 0.508)
		(drill 0.254)
		(layers "F.Cu" "B.Cu")
		(net "P3V3_STBY_VREG")
	)
	(segment
		(start 6.5278 -33.401)
		(end 6.5278 -34.29)
		(width 0.3048)
		(layer "B.Cu")
		(net "P3V3_STBY_VREG")
	)
	(segment
		(start 7.366 -35.8648)
		(end 7.5438 -35.8648)
		(width 0.3048)
		(layer "B.Cu")
		(net "P3V3_STBY_VREG")
	)
	(segment
		(start 7.5438 -35.8648)
		(end 8.89 -34.5186)
		(width 0.3048)
		(layer "B.Cu")
		(net "P3V3_STBY_VREG")
	)
	(segment
		(start 8.89 -34.5186)
		(end 8.89 -32.9692)
		(width 0.3048)
		(layer "B.Cu")
		(net "P3V3_STBY_VREG")
	)
	(segment
		(start 6.5278 -34.29)
		(end 6.6802 -34.4424)
		(width 0.3048)
		(layer "B.Cu")
		(net "P3V3_STBY_VREG")
	)
	(segment
		(start 6.6802 -34.4424)
		(end 6.6802 -35.179)
		(width 0.3048)
		(layer "B.Cu")
		(net "P3V3_STBY_VREG")
	)
	(segment
		(start 6.6802 -35.179)
		(end 7.366 -35.8648)
		(width 0.3048)
		(layer "B.Cu")
		(net "P3V3_STBY_VREG")
	)
	(segment
		(start 8.89 -32.9692)
		(end 10.287 -31.5722)
		(width 0.3048)
		(layer "B.Cu")
		(net "P3V3_STBY_VREG")
	)
	(segment
		(start 188.45276 -30.991302)
		(end 188.656468 -31.19501)
		(width 0.2032)
		(layer "F.Cu")
		(net "VR_PVDDR_A_ISEN2")
	)
	(segment
		(start 185.293 -29.0576)
		(end 187.226702 -30.991302)
		(width 0.2032)
		(layer "F.Cu")
		(net "VR_PVDDR_A_ISEN2")
	)
	(segment
		(start 184.912 -27.94)
		(end 185.293 -28.321)
		(width 0.2032)
		(layer "F.Cu")
		(net "VR_PVDDR_A_ISEN2")
	)
	(segment
		(start 184.912 -27.3558)
		(end 184.912 -27.94)
		(width 0.2032)
		(layer "F.Cu")
		(net "VR_PVDDR_A_ISEN2")
	)
	(segment
		(start 185.293 -28.321)
		(end 185.293 -29.0576)
		(width 0.2032)
		(layer "F.Cu")
		(net "VR_PVDDR_A_ISEN2")
	)
	(segment
		(start 188.656468 -31.19501)
		(end 188.656468 -31.575502)
		(width 0.2032)
		(layer "F.Cu")
		(net "VR_PVDDR_A_ISEN2")
	)
	(segment
		(start 187.226702 -30.991302)
		(end 188.45276 -30.991302)
		(width 0.2032)
		(layer "F.Cu")
		(net "VR_PVDDR_A_ISEN2")
	)
	(via
		(at 185.293 -28.321)
		(size 0.7112)
		(drill 0.3556)
		(layers "F.Cu" "B.Cu")
		(net "VR_PVDDR_A_ISEN2")
	)
	(segment
		(start 144.249902 -9.897364)
		(end 144.249902 -8.050276)
		(width 0.1778)
		(layer "F.Cu")
		(net "M_B_DQ24")
	)
	(segment
		(start 97.605088 -29.235654)
		(end 97.8408 -28.999942)
		(width 0.1016)
		(layer "F.Cu")
		(net "M_B_DQ24")
	)
	(segment
		(start 97.8408 -28.999942)
		(end 97.8408 -28.736798)
		(width 0.1016)
		(layer "F.Cu")
		(net "M_B_DQ24")
	)
	(segment
		(start 144.249902 -8.050276)
		(end 144.7292 -7.570978)
		(width 0.1778)
		(layer "F.Cu")
		(net "M_B_DQ24")
	)
	(via
		(at 97.8408 -28.736798)
		(size 0.4318)
		(drill 0.2032)
		(layers "F.Cu" "B.Cu")
		(net "M_B_DQ24")
	)
	(via
		(at 144.7292 -7.570978)
		(size 0.4318)
		(drill 0.2032)
		(layers "F.Cu" "B.Cu")
		(net "M_B_DQ24")
	)
	(segment
		(start 144.549876 -9.89076)
		(end 144.549876 -8.763254)
		(width 0.1778)
		(layer "B.Cu")
		(net "M_B_DQ24")
	)
	(segment
		(start 144.549876 -8.763254)
		(end 144.399 -8.612378)
		(width 0.1778)
		(layer "B.Cu")
		(net "M_B_DQ24")
	)
	(segment
		(start 144.7292 -7.614158)
		(end 144.7292 -7.570978)
		(width 0.1778)
		(layer "B.Cu")
		(net "M_B_DQ24")
	)
	(segment
		(start 144.399 -7.944358)
		(end 144.7292 -7.614158)
		(width 0.1778)
		(layer "B.Cu")
		(net "M_B_DQ24")
	)
	(segment
		(start 144.399 -8.612378)
		(end 144.399 -7.944358)
		(width 0.1778)
		(layer "B.Cu")
		(net "M_B_DQ24")
	)
	(segment
		(start 111.820452 -21.844)
		(end 105.6894 -21.844)
		(width 0.1524)
		(layer "In4.Cu")
		(net "M_B_DQ24")
	)
	(segment
		(start 104.8766 -22.6568)
		(end 104.8766 -24.6634)
		(width 0.1524)
		(layer "In4.Cu")
		(net "M_B_DQ24")
	)
	(segment
		(start 126.746 -18.2626)
		(end 126.5936 -18.1102)
		(width 0.1524)
		(layer "In4.Cu")
		(net "M_B_DQ24")
	)
	(segment
		(start 144.55648 -7.786878)
		(end 144.55648 -8.604758)
		(width 0.1524)
		(layer "In4.Cu")
		(net "M_B_DQ24")
	)
	(segment
		(start 128.1176 -18.9738)
		(end 127.9652 -18.8214)
		(width 0.1524)
		(layer "In4.Cu")
		(net "M_B_DQ24")
	)
	(segment
		(start 123.6218 -18.8976)
		(end 123.4694 -19.05)
		(width 0.1524)
		(layer "In4.Cu")
		(net "M_B_DQ24")
	)
	(segment
		(start 122.4026 -19.2278)
		(end 122.2502 -19.3802)
		(width 0.1524)
		(layer "In4.Cu")
		(net "M_B_DQ24")
	)
	(segment
		(start 124.3838 -18.9738)
		(end 124.2314 -18.8214)
		(width 0.1524)
		(layer "In4.Cu")
		(net "M_B_DQ24")
	)
	(segment
		(start 126.5936 -18.1102)
		(end 124.968 -18.1102)
		(width 0.1524)
		(layer "In4.Cu")
		(net "M_B_DQ24")
	)
	(segment
		(start 122.4026 -18.3388)
		(end 122.4026 -19.2278)
		(width 0.1524)
		(layer "In4.Cu")
		(net "M_B_DQ24")
	)
	(segment
		(start 127.508 -18.1102)
		(end 127.3556 -18.2626)
		(width 0.1524)
		(layer "In4.Cu")
		(net "M_B_DQ24")
	)
	(segment
		(start 128.4224 -18.9738)
		(end 128.1176 -18.9738)
		(width 0.1524)
		(layer "In4.Cu")
		(net "M_B_DQ24")
	)
	(segment
		(start 114.284252 -19.3802)
		(end 111.820452 -21.844)
		(width 0.1524)
		(layer "In4.Cu")
		(net "M_B_DQ24")
	)
	(segment
		(start 98.659696 -27.730704)
		(end 97.8408 -28.5496)
		(width 0.1016)
		(layer "In4.Cu")
		(net "M_B_DQ24")
	)
	(segment
		(start 99.1108 -26.924)
		(end 98.659696 -27.375104)
		(width 0.1016)
		(layer "In4.Cu")
		(net "M_B_DQ24")
	)
	(segment
		(start 129.032 -18.1102)
		(end 128.7272 -18.1102)
		(width 0.1524)
		(layer "In4.Cu")
		(net "M_B_DQ24")
	)
	(segment
		(start 144.729454 -8.777732)
		(end 144.729454 -18.922746)
		(width 0.1524)
		(layer "In4.Cu")
		(net "M_B_DQ24")
	)
	(segment
		(start 144.272 -19.3802)
		(end 137.6426 -19.3802)
		(width 0.1524)
		(layer "In4.Cu")
		(net "M_B_DQ24")
	)
	(segment
		(start 105.6894 -21.844)
		(end 104.8766 -22.6568)
		(width 0.1524)
		(layer "In4.Cu")
		(net "M_B_DQ24")
	)
	(segment
		(start 127.9652 -18.2626)
		(end 127.8128 -18.1102)
		(width 0.1524)
		(layer "In4.Cu")
		(net "M_B_DQ24")
	)
	(segment
		(start 129.3368 -18.9738)
		(end 129.1844 -18.8214)
		(width 0.1524)
		(layer "In4.Cu")
		(net "M_B_DQ24")
	)
	(segment
		(start 127.2032 -18.9738)
		(end 126.8984 -18.9738)
		(width 0.1524)
		(layer "In4.Cu")
		(net "M_B_DQ24")
	)
	(segment
		(start 137.4902 -18.2626)
		(end 137.3378 -18.1102)
		(width 0.1524)
		(layer "In4.Cu")
		(net "M_B_DQ24")
	)
	(segment
		(start 144.7292 -7.570978)
		(end 144.7292 -7.614158)
		(width 0.1524)
		(layer "In4.Cu")
		(net "M_B_DQ24")
	)
	(segment
		(start 123.0122 -18.8976)
		(end 123.0122 -18.3388)
		(width 0.1524)
		(layer "In4.Cu")
		(net "M_B_DQ24")
	)
	(segment
		(start 100.584 -26.2382)
		(end 99.8982 -26.924)
		(width 0.1016)
		(layer "In4.Cu")
		(net "M_B_DQ24")
	)
	(segment
		(start 128.7272 -18.1102)
		(end 128.5748 -18.2626)
		(width 0.1524)
		(layer "In4.Cu")
		(net "M_B_DQ24")
	)
	(segment
		(start 122.555 -18.1864)
		(end 122.4026 -18.3388)
		(width 0.1524)
		(layer "In4.Cu")
		(net "M_B_DQ24")
	)
	(segment
		(start 124.968 -18.1102)
		(end 124.8156 -18.2626)
		(width 0.1524)
		(layer "In4.Cu")
		(net "M_B_DQ24")
	)
	(segment
		(start 97.8408 -28.5496)
		(end 97.8408 -28.736798)
		(width 0.1016)
		(layer "In4.Cu")
		(net "M_B_DQ24")
	)
	(segment
		(start 129.1844 -18.8214)
		(end 129.1844 -18.2626)
		(width 0.1524)
		(layer "In4.Cu")
		(net "M_B_DQ24")
	)
	(segment
		(start 123.6218 -18.3388)
		(end 123.6218 -18.8976)
		(width 0.1524)
		(layer "In4.Cu")
		(net "M_B_DQ24")
	)
	(segment
		(start 99.8982 -26.924)
		(end 99.1108 -26.924)
		(width 0.1016)
		(layer "In4.Cu")
		(net "M_B_DQ24")
	)
	(segment
		(start 129.794 -18.8214)
		(end 129.6416 -18.9738)
		(width 0.1524)
		(layer "In4.Cu")
		(net "M_B_DQ24")
	)
	(segment
		(start 124.8156 -18.8214)
		(end 124.6632 -18.9738)
		(width 0.1524)
		(layer "In4.Cu")
		(net "M_B_DQ24")
	)
	(segment
		(start 124.6632 -18.9738)
		(end 124.3838 -18.9738)
		(width 0.1524)
		(layer "In4.Cu")
		(net "M_B_DQ24")
	)
	(segment
		(start 129.6416 -18.9738)
		(end 129.3368 -18.9738)
		(width 0.1524)
		(layer "In4.Cu")
		(net "M_B_DQ24")
	)
	(segment
		(start 123.7742 -18.1864)
		(end 123.6218 -18.3388)
		(width 0.1524)
		(layer "In4.Cu")
		(net "M_B_DQ24")
	)
	(segment
		(start 144.729454 -18.922746)
		(end 144.272 -19.3802)
		(width 0.1524)
		(layer "In4.Cu")
		(net "M_B_DQ24")
	)
	(segment
		(start 137.4902 -19.2278)
		(end 137.4902 -18.2626)
		(width 0.1524)
		(layer "In4.Cu")
		(net "M_B_DQ24")
	)
	(segment
		(start 129.1844 -18.2626)
		(end 129.032 -18.1102)
		(width 0.1524)
		(layer "In4.Cu")
		(net "M_B_DQ24")
	)
	(segment
		(start 127.9652 -18.8214)
		(end 127.9652 -18.2626)
		(width 0.1524)
		(layer "In4.Cu")
		(net "M_B_DQ24")
	)
	(segment
		(start 126.8984 -18.9738)
		(end 126.746 -18.8214)
		(width 0.1524)
		(layer "In4.Cu")
		(net "M_B_DQ24")
	)
	(segment
		(start 127.3556 -18.8214)
		(end 127.2032 -18.9738)
		(width 0.1524)
		(layer "In4.Cu")
		(net "M_B_DQ24")
	)
	(segment
		(start 104.8766 -24.6634)
		(end 103.4796 -26.0604)
		(width 0.1524)
		(layer "In4.Cu")
		(net "M_B_DQ24")
	)
	(segment
		(start 124.2314 -18.3388)
		(end 124.079 -18.1864)
		(width 0.1524)
		(layer "In4.Cu")
		(net "M_B_DQ24")
	)
	(segment
		(start 124.079 -18.1864)
		(end 123.7742 -18.1864)
		(width 0.1524)
		(layer "In4.Cu")
		(net "M_B_DQ24")
	)
	(segment
		(start 127.8128 -18.1102)
		(end 127.508 -18.1102)
		(width 0.1524)
		(layer "In4.Cu")
		(net "M_B_DQ24")
	)
	(segment
		(start 123.4694 -19.05)
		(end 123.1646 -19.05)
		(width 0.1524)
		(layer "In4.Cu")
		(net "M_B_DQ24")
	)
	(segment
		(start 129.794 -18.2626)
		(end 129.794 -18.8214)
		(width 0.1524)
		(layer "In4.Cu")
		(net "M_B_DQ24")
	)
	(segment
		(start 124.8156 -18.2626)
		(end 124.8156 -18.8214)
		(width 0.1524)
		(layer "In4.Cu")
		(net "M_B_DQ24")
	)
	(segment
		(start 103.4796 -26.0604)
		(end 103.3018 -26.2382)
		(width 0.1016)
		(layer "In4.Cu")
		(net "M_B_DQ24")
	)
	(segment
		(start 137.6426 -19.3802)
		(end 137.4902 -19.2278)
		(width 0.1524)
		(layer "In4.Cu")
		(net "M_B_DQ24")
	)
	(segment
		(start 128.5748 -18.2626)
		(end 128.5748 -18.8214)
		(width 0.1524)
		(layer "In4.Cu")
		(net "M_B_DQ24")
	)
	(segment
		(start 128.5748 -18.8214)
		(end 128.4224 -18.9738)
		(width 0.1524)
		(layer "In4.Cu")
		(net "M_B_DQ24")
	)
	(segment
		(start 137.3378 -18.1102)
		(end 129.9464 -18.1102)
		(width 0.1524)
		(layer "In4.Cu")
		(net "M_B_DQ24")
	)
	(segment
		(start 126.746 -18.8214)
		(end 126.746 -18.2626)
		(width 0.1524)
		(layer "In4.Cu")
		(net "M_B_DQ24")
	)
	(segment
		(start 127.3556 -18.2626)
		(end 127.3556 -18.8214)
		(width 0.1524)
		(layer "In4.Cu")
		(net "M_B_DQ24")
	)
	(segment
		(start 103.3018 -26.2382)
		(end 100.584 -26.2382)
		(width 0.1016)
		(layer "In4.Cu")
		(net "M_B_DQ24")
	)
	(segment
		(start 124.2314 -18.8214)
		(end 124.2314 -18.3388)
		(width 0.1524)
		(layer "In4.Cu")
		(net "M_B_DQ24")
	)
	(segment
		(start 144.55648 -8.604758)
		(end 144.729454 -8.777732)
		(width 0.1524)
		(layer "In4.Cu")
		(net "M_B_DQ24")
	)
	(segment
		(start 123.1646 -19.05)
		(end 123.0122 -18.8976)
		(width 0.1524)
		(layer "In4.Cu")
		(net "M_B_DQ24")
	)
	(segment
		(start 123.0122 -18.3388)
		(end 122.8598 -18.1864)
		(width 0.1524)
		(layer "In4.Cu")
		(net "M_B_DQ24")
	)
	(segment
		(start 122.2502 -19.3802)
		(end 114.284252 -19.3802)
		(width 0.1524)
		(layer "In4.Cu")
		(net "M_B_DQ24")
	)
	(segment
		(start 122.8598 -18.1864)
		(end 122.555 -18.1864)
		(width 0.1524)
		(layer "In4.Cu")
		(net "M_B_DQ24")
	)
	(segment
		(start 144.7292 -7.614158)
		(end 144.55648 -7.786878)
		(width 0.1524)
		(layer "In4.Cu")
		(net "M_B_DQ24")
	)
	(segment
		(start 98.659696 -27.375104)
		(end 98.659696 -27.730704)
		(width 0.1016)
		(layer "In4.Cu")
		(net "M_B_DQ24")
	)
	(segment
		(start 129.9464 -18.1102)
		(end 129.794 -18.2626)
		(width 0.1524)
		(layer "In4.Cu")
		(net "M_B_DQ24")
	)
	(segment
		(start 185.550556 -34.1757)
		(end 185.029856 -34.6964)
		(width 0.2032)
		(layer "F.Cu")
		(net "PWRGD_PVDDR_PG")
	)
	(segment
		(start 183.1848 -34.798)
		(end 184.7596 -34.798)
		(width 0.254)
		(layer "F.Cu")
		(net "PWRGD_PVDDR_PG")
	)
	(segment
		(start 70.9422 -30.734)
		(end 70.9422 -29.8958)
		(width 0.254)
		(layer "F.Cu")
		(net "PWRGD_PVDDR_PG")
	)
	(segment
		(start 70.9422 -29.8958)
		(end 70.63105 -29.58465)
		(width 0.254)
		(layer "F.Cu")
		(net "PWRGD_PVDDR_PG")
	)
	(segment
		(start 178.37658 -22.0472)
		(end 163.703 -22.0472)
		(width 0.254)
		(layer "F.Cu")
		(net "PWRGD_PVDDR_PG")
	)
	(segment
		(start 186.856116 -34.1757)
		(end 185.550556 -34.1757)
		(width 0.2032)
		(layer "F.Cu")
		(net "PWRGD_PVDDR_PG")
	)
	(segment
		(start 163.703 -22.0472)
		(end 163.277042 -22.473158)
		(width 0.254)
		(layer "F.Cu")
		(net "PWRGD_PVDDR_PG")
	)
	(segment
		(start 180.467 -29.21)
		(end 180.467 -24.13762)
		(width 0.254)
		(layer "F.Cu")
		(net "PWRGD_PVDDR_PG")
	)
	(segment
		(start 184.7596 -34.798)
		(end 184.8612 -34.6964)
		(width 0.254)
		(layer "F.Cu")
		(net "PWRGD_PVDDR_PG")
	)
	(segment
		(start 181.356 -30.099)
		(end 180.467 -29.21)
		(width 0.254)
		(layer "F.Cu")
		(net "PWRGD_PVDDR_PG")
	)
	(segment
		(start 185.029856 -34.6964)
		(end 184.8612 -34.6964)
		(width 0.2032)
		(layer "F.Cu")
		(net "PWRGD_PVDDR_PG")
	)
	(segment
		(start 180.467 -24.13762)
		(end 178.37658 -22.0472)
		(width 0.254)
		(layer "F.Cu")
		(net "PWRGD_PVDDR_PG")
	)
	(via
		(at 163.277042 -22.473158)
		(size 0.508)
		(drill 0.254)
		(layers "F.Cu" "B.Cu")
		(net "PWRGD_PVDDR_PG")
	)
	(via
		(at 183.6166 -32.3596)
		(size 0.7112)
		(drill 0.3556)
		(layers "F.Cu" "B.Cu")
		(net "PWRGD_PVDDR_PG")
	)
	(via
		(at 76.6064 -23.6982)
		(size 0.508)
		(drill 0.254)
		(layers "F.Cu" "B.Cu")
		(net "PWRGD_PVDDR_PG")
	)
	(via
		(at 114.232436 -4.744974)
		(size 0.508)
		(drill 0.254)
		(layers "F.Cu" "B.Cu")
		(net "PWRGD_PVDDR_PG")
	)
	(via
		(at 181.356 -30.099)
		(size 0.508)
		(drill 0.254)
		(layers "F.Cu" "B.Cu")
		(net "PWRGD_PVDDR_PG")
	)
	(via
		(at 70.63105 -29.58465)
		(size 0.508)
		(drill 0.254)
		(layers "F.Cu" "B.Cu")
		(net "PWRGD_PVDDR_PG")
	)
	(via
		(at 184.8612 -34.6964)
		(size 0.508)
		(drill 0.254)
		(layers "F.Cu" "B.Cu")
		(net "PWRGD_PVDDR_PG")
	)
	(segment
		(start 129.3622 -21.768816)
		(end 130.480816 -20.6502)
		(width 0.254)
		(layer "B.Cu")
		(net "PWRGD_PVDDR_PG")
	)
	(segment
		(start 114.232436 -4.744974)
		(end 114.237262 -4.7498)
		(width 0.254)
		(layer "B.Cu")
		(net "PWRGD_PVDDR_PG")
	)
	(segment
		(start 181.356 -30.099)
		(end 183.6166 -32.3596)
		(width 0.254)
		(layer "B.Cu")
		(net "PWRGD_PVDDR_PG")
	)
	(segment
		(start 161.454084 -20.6502)
		(end 163.277042 -22.473158)
		(width 0.254)
		(layer "B.Cu")
		(net "PWRGD_PVDDR_PG")
	)
	(segment
		(start 117.983 -22.516338)
		(end 119.939054 -24.472392)
		(width 0.254)
		(layer "B.Cu")
		(net "PWRGD_PVDDR_PG")
	)
	(segment
		(start 116.07038 -5.981954)
		(end 116.07038 -6.576314)
		(width 0.254)
		(layer "B.Cu")
		(net "PWRGD_PVDDR_PG")
	)
	(segment
		(start 128.303274 -24.472392)
		(end 129.3622 -23.413466)
		(width 0.254)
		(layer "B.Cu")
		(net "PWRGD_PVDDR_PG")
	)
	(segment
		(start 184.4548 -34.29)
		(end 184.4548 -33.1978)
		(width 0.254)
		(layer "B.Cu")
		(net "PWRGD_PVDDR_PG")
	)
	(segment
		(start 116.07038 -6.576314)
		(end 117.983 -8.488934)
		(width 0.254)
		(layer "B.Cu")
		(net "PWRGD_PVDDR_PG")
	)
	(segment
		(start 119.939054 -24.472392)
		(end 128.303274 -24.472392)
		(width 0.254)
		(layer "B.Cu")
		(net "PWRGD_PVDDR_PG")
	)
	(segment
		(start 184.8612 -34.6964)
		(end 184.4548 -34.29)
		(width 0.254)
		(layer "B.Cu")
		(net "PWRGD_PVDDR_PG")
	)
	(segment
		(start 130.480816 -20.6502)
		(end 161.454084 -20.6502)
		(width 0.254)
		(layer "B.Cu")
		(net "PWRGD_PVDDR_PG")
	)
	(segment
		(start 184.4548 -33.1978)
		(end 183.6166 -32.3596)
		(width 0.254)
		(layer "B.Cu")
		(net "PWRGD_PVDDR_PG")
	)
	(segment
		(start 117.983 -8.488934)
		(end 117.983 -22.516338)
		(width 0.254)
		(layer "B.Cu")
		(net "PWRGD_PVDDR_PG")
	)
	(segment
		(start 129.3622 -23.413466)
		(end 129.3622 -21.768816)
		(width 0.254)
		(layer "B.Cu")
		(net "PWRGD_PVDDR_PG")
	)
	(segment
		(start 114.237262 -4.7498)
		(end 114.838226 -4.7498)
		(width 0.254)
		(layer "B.Cu")
		(net "PWRGD_PVDDR_PG")
	)
	(segment
		(start 114.838226 -4.7498)
		(end 116.07038 -5.981954)
		(width 0.254)
		(layer "B.Cu")
		(net "PWRGD_PVDDR_PG")
	)
	(segment
		(start 70.63105 -26.80335)
		(end 72.771 -24.6634)
		(width 0.254)
		(layer "In2.Cu")
		(net "PWRGD_PVDDR_PG")
	)
	(segment
		(start 72.771 -24.6634)
		(end 75.3364 -24.6634)
		(width 0.254)
		(layer "In2.Cu")
		(net "PWRGD_PVDDR_PG")
	)
	(segment
		(start 75.3364 -24.6634)
		(end 76.3016 -23.6982)
		(width 0.254)
		(layer "In2.Cu")
		(net "PWRGD_PVDDR_PG")
	)
	(segment
		(start 70.63105 -29.58465)
		(end 70.63105 -26.80335)
		(width 0.254)
		(layer "In2.Cu")
		(net "PWRGD_PVDDR_PG")
	)
	(segment
		(start 76.3016 -23.6982)
		(end 76.6064 -23.6982)
		(width 0.254)
		(layer "In2.Cu")
		(net "PWRGD_PVDDR_PG")
	)
	(segment
		(start 84.4169 -22.9489)
		(end 83.1977 -22.9489)
		(width 0.254)
		(layer "In4.Cu")
		(net "PWRGD_PVDDR_PG")
	)
	(segment
		(start 107.50296 -13.452856)
		(end 100.26904 -13.452856)
		(width 0.254)
		(layer "In4.Cu")
		(net "PWRGD_PVDDR_PG")
	)
	(segment
		(start 82.205322 -22.780752)
		(end 81.999074 -22.987)
		(width 0.254)
		(layer "In4.Cu")
		(net "PWRGD_PVDDR_PG")
	)
	(segment
		(start 113.881408 -5.096002)
		(end 113.881408 -7.074408)
		(width 0.254)
		(layer "In4.Cu")
		(net "PWRGD_PVDDR_PG")
	)
	(segment
		(start 81.999074 -22.987)
		(end 81.3308 -22.987)
		(width 0.254)
		(layer "In4.Cu")
		(net "PWRGD_PVDDR_PG")
	)
	(segment
		(start 79.246476 -22.658324)
		(end 78.3082 -23.5966)
		(width 0.254)
		(layer "In4.Cu")
		(net "PWRGD_PVDDR_PG")
	)
	(segment
		(start 81.3308 -22.987)
		(end 81.002124 -22.658324)
		(width 0.254)
		(layer "In4.Cu")
		(net "PWRGD_PVDDR_PG")
	)
	(segment
		(start 90.938096 -22.7838)
		(end 84.582 -22.7838)
		(width 0.254)
		(layer "In4.Cu")
		(net "PWRGD_PVDDR_PG")
	)
	(segment
		(start 83.1977 -22.9489)
		(end 83.029552 -22.780752)
		(width 0.254)
		(layer "In4.Cu")
		(net "PWRGD_PVDDR_PG")
	)
	(segment
		(start 113.881408 -7.074408)
		(end 107.50296 -13.452856)
		(width 0.254)
		(layer "In4.Cu")
		(net "PWRGD_PVDDR_PG")
	)
	(segment
		(start 84.582 -22.7838)
		(end 84.4169 -22.9489)
		(width 0.254)
		(layer "In4.Cu")
		(net "PWRGD_PVDDR_PG")
	)
	(segment
		(start 78.3082 -23.5966)
		(end 76.708 -23.5966)
		(width 0.254)
		(layer "In4.Cu")
		(net "PWRGD_PVDDR_PG")
	)
	(segment
		(start 81.002124 -22.658324)
		(end 79.246476 -22.658324)
		(width 0.254)
		(layer "In4.Cu")
		(net "PWRGD_PVDDR_PG")
	)
	(segment
		(start 114.232436 -4.744974)
		(end 113.881408 -5.096002)
		(width 0.254)
		(layer "In4.Cu")
		(net "PWRGD_PVDDR_PG")
	)
	(segment
		(start 100.26904 -13.452856)
		(end 90.938096 -22.7838)
		(width 0.254)
		(layer "In4.Cu")
		(net "PWRGD_PVDDR_PG")
	)
	(segment
		(start 83.029552 -22.780752)
		(end 82.205322 -22.780752)
		(width 0.254)
		(layer "In4.Cu")
		(net "PWRGD_PVDDR_PG")
	)
	(segment
		(start 76.708 -23.5966)
		(end 76.6064 -23.6982)
		(width 0.254)
		(layer "In4.Cu")
		(net "PWRGD_PVDDR_PG")
	)
	(segment
		(start 133.0198 -8.491728)
		(end 132.8674 -8.339328)
		(width 0.1778)
		(layer "F.Cu")
		(net "M_B_DQ2")
	)
	(segment
		(start 95.232728 -25.943052)
		(end 95.232728 -26.446734)
		(width 0.1016)
		(layer "F.Cu")
		(net "M_B_DQ2")
	)
	(segment
		(start 132.8674 -8.339328)
		(end 132.774182 -8.339328)
		(width 0.1778)
		(layer "F.Cu")
		(net "M_B_DQ2")
	)
	(segment
		(start 93.6244 -23.0378)
		(end 93.6244 -23.0886)
		(width 0.1016)
		(layer "F.Cu")
		(net "M_B_DQ2")
	)
	(segment
		(start 132.849874 -9.112504)
		(end 133.0198 -8.942578)
		(width 0.1778)
		(layer "F.Cu")
		(net "M_B_DQ2")
	)
	(segment
		(start 94.71406 -25.424384)
		(end 95.232728 -25.943052)
		(width 0.1016)
		(layer "F.Cu")
		(net "M_B_DQ2")
	)
	(segment
		(start 94.291912 -25.424384)
		(end 94.71406 -25.424384)
		(width 0.1016)
		(layer "F.Cu")
		(net "M_B_DQ2")
	)
	(segment
		(start 132.849874 -9.897364)
		(end 132.849874 -9.112504)
		(width 0.1778)
		(layer "F.Cu")
		(net "M_B_DQ2")
	)
	(segment
		(start 94.0562 -23.5204)
		(end 94.0562 -25.188672)
		(width 0.1016)
		(layer "F.Cu")
		(net "M_B_DQ2")
	)
	(segment
		(start 133.0198 -8.942578)
		(end 133.0198 -8.491728)
		(width 0.1778)
		(layer "F.Cu")
		(net "M_B_DQ2")
	)
	(segment
		(start 93.6244 -23.0886)
		(end 94.0562 -23.5204)
		(width 0.1016)
		(layer "F.Cu")
		(net "M_B_DQ2")
	)
	(segment
		(start 94.0562 -25.188672)
		(end 94.291912 -25.424384)
		(width 0.1016)
		(layer "F.Cu")
		(net "M_B_DQ2")
	)
	(via
		(at 132.774182 -8.339328)
		(size 0.4318)
		(drill 0.2032)
		(layers "F.Cu" "B.Cu")
		(net "M_B_DQ2")
	)
	(via
		(at 93.6244 -23.0378)
		(size 0.4318)
		(drill 0.2032)
		(layers "F.Cu" "B.Cu")
		(net "M_B_DQ2")
	)
	(segment
		(start 131.949952 -9.89076)
		(end 131.949952 -9.163558)
		(width 0.1778)
		(layer "B.Cu")
		(net "M_B_DQ2")
	)
	(segment
		(start 131.949952 -9.163558)
		(end 132.774182 -8.339328)
		(width 0.1778)
		(layer "B.Cu")
		(net "M_B_DQ2")
	)
	(segment
		(start 97.7138 -19.5326)
		(end 96.8756 -20.3708)
		(width 0.1524)
		(layer "In7.Cu")
		(net "M_B_DQ2")
	)
	(segment
		(start 99.568 -19.5326)
		(end 97.7138 -19.5326)
		(width 0.1524)
		(layer "In7.Cu")
		(net "M_B_DQ2")
	)
	(segment
		(start 117.7798 -10.795)
		(end 117.5766 -10.9982)
		(width 0.1524)
		(layer "In7.Cu")
		(net "M_B_DQ2")
	)
	(segment
		(start 130.567176 -11.87958)
		(end 130.567176 -12.6238)
		(width 0.1524)
		(layer "In7.Cu")
		(net "M_B_DQ2")
	)
	(segment
		(start 119.8118 -10.795)
		(end 117.7798 -10.795)
		(width 0.1524)
		(layer "In7.Cu")
		(net "M_B_DQ2")
	)
	(segment
		(start 114.537744 -12.065762)
		(end 114.537744 -12.6238)
		(width 0.1524)
		(layer "In7.Cu")
		(net "M_B_DQ2")
	)
	(segment
		(start 120.2182 -12.7762)
		(end 120.015 -12.573)
		(width 0.1524)
		(layer "In7.Cu")
		(net "M_B_DQ2")
	)
	(segment
		(start 117.5766 -12.573)
		(end 117.3734 -12.7762)
		(width 0.1524)
		(layer "In7.Cu")
		(net "M_B_DQ2")
	)
	(segment
		(start 96.647 -24.7142)
		(end 94.3102 -24.7142)
		(width 0.1524)
		(layer "In7.Cu")
		(net "M_B_DQ2")
	)
	(segment
		(start 132.301742 -11.004042)
		(end 132.041392 -10.743692)
		(width 0.1524)
		(layer "In7.Cu")
		(net "M_B_DQ2")
	)
	(segment
		(start 96.8756 -24.4856)
		(end 96.647 -24.7142)
		(width 0.1524)
		(layer "In7.Cu")
		(net "M_B_DQ2")
	)
	(segment
		(start 114.385344 -12.7762)
		(end 113.621058 -12.7762)
		(width 0.1524)
		(layer "In7.Cu")
		(net "M_B_DQ2")
	)
	(segment
		(start 94.1578 -24.5618)
		(end 94.1578 -23.8252)
		(width 0.1524)
		(layer "In7.Cu")
		(net "M_B_DQ2")
	)
	(segment
		(start 122.6058 -12.7762)
		(end 120.2182 -12.7762)
		(width 0.1524)
		(layer "In7.Cu")
		(net "M_B_DQ2")
	)
	(segment
		(start 113.621058 -12.7762)
		(end 107.601258 -18.796)
		(width 0.1524)
		(layer "In7.Cu")
		(net "M_B_DQ2")
	)
	(segment
		(start 130.719576 -11.72718)
		(end 130.567176 -11.87958)
		(width 0.1524)
		(layer "In7.Cu")
		(net "M_B_DQ2")
	)
	(segment
		(start 120.015 -12.573)
		(end 120.015 -10.9982)
		(width 0.1524)
		(layer "In7.Cu")
		(net "M_B_DQ2")
	)
	(segment
		(start 130.414776 -12.7762)
		(end 129.8956 -12.7762)
		(width 0.1524)
		(layer "In7.Cu")
		(net "M_B_DQ2")
	)
	(segment
		(start 114.537744 -12.6238)
		(end 114.385344 -12.7762)
		(width 0.1524)
		(layer "In7.Cu")
		(net "M_B_DQ2")
	)
	(segment
		(start 114.716306 -11.8872)
		(end 114.537744 -12.065762)
		(width 0.1524)
		(layer "In7.Cu")
		(net "M_B_DQ2")
	)
	(segment
		(start 93.6244 -23.2918)
		(end 94.1578 -23.8252)
		(width 0.1016)
		(layer "In7.Cu")
		(net "M_B_DQ2")
	)
	(segment
		(start 107.601258 -18.796)
		(end 100.3046 -18.796)
		(width 0.1524)
		(layer "In7.Cu")
		(net "M_B_DQ2")
	)
	(segment
		(start 131.30022 -11.72718)
		(end 130.719576 -11.72718)
		(width 0.1524)
		(layer "In7.Cu")
		(net "M_B_DQ2")
	)
	(segment
		(start 96.8756 -20.3708)
		(end 96.8756 -24.4856)
		(width 0.1524)
		(layer "In7.Cu")
		(net "M_B_DQ2")
	)
	(segment
		(start 131.610354 -10.959592)
		(end 131.610354 -11.174984)
		(width 0.1524)
		(layer "In7.Cu")
		(net "M_B_DQ2")
	)
	(segment
		(start 115.147344 -12.065762)
		(end 114.968782 -11.8872)
		(width 0.1524)
		(layer "In7.Cu")
		(net "M_B_DQ2")
	)
	(segment
		(start 129.5908 -11.72718)
		(end 129.0066 -11.72718)
		(width 0.1524)
		(layer "In7.Cu")
		(net "M_B_DQ2")
	)
	(segment
		(start 131.941316 -11.721084)
		(end 131.725416 -11.936984)
		(width 0.1524)
		(layer "In7.Cu")
		(net "M_B_DQ2")
	)
	(segment
		(start 117.5766 -10.9982)
		(end 117.5766 -12.573)
		(width 0.1524)
		(layer "In7.Cu")
		(net "M_B_DQ2")
	)
	(segment
		(start 132.774182 -8.339328)
		(end 132.774182 -8.898382)
		(width 0.1524)
		(layer "In7.Cu")
		(net "M_B_DQ2")
	)
	(segment
		(start 129.7432 -11.87958)
		(end 129.5908 -11.72718)
		(width 0.1524)
		(layer "In7.Cu")
		(net "M_B_DQ2")
	)
	(segment
		(start 129.0066 -11.72718)
		(end 128.54178 -12.192)
		(width 0.1524)
		(layer "In7.Cu")
		(net "M_B_DQ2")
	)
	(segment
		(start 132.041392 -10.743692)
		(end 131.826 -10.743692)
		(width 0.1524)
		(layer "In7.Cu")
		(net "M_B_DQ2")
	)
	(segment
		(start 129.7432 -12.6238)
		(end 129.7432 -11.87958)
		(width 0.1524)
		(layer "In7.Cu")
		(net "M_B_DQ2")
	)
	(segment
		(start 131.826 -10.743692)
		(end 131.610354 -10.959592)
		(width 0.1524)
		(layer "In7.Cu")
		(net "M_B_DQ2")
	)
	(segment
		(start 115.299744 -12.7762)
		(end 115.147344 -12.6238)
		(width 0.1524)
		(layer "In7.Cu")
		(net "M_B_DQ2")
	)
	(segment
		(start 129.8956 -12.7762)
		(end 129.7432 -12.6238)
		(width 0.1524)
		(layer "In7.Cu")
		(net "M_B_DQ2")
	)
	(segment
		(start 123.19 -12.192)
		(end 122.6058 -12.7762)
		(width 0.1524)
		(layer "In7.Cu")
		(net "M_B_DQ2")
	)
	(segment
		(start 128.54178 -12.192)
		(end 123.19 -12.192)
		(width 0.1524)
		(layer "In7.Cu")
		(net "M_B_DQ2")
	)
	(segment
		(start 117.3734 -12.7762)
		(end 115.299744 -12.7762)
		(width 0.1524)
		(layer "In7.Cu")
		(net "M_B_DQ2")
	)
	(segment
		(start 115.147344 -12.6238)
		(end 115.147344 -12.065762)
		(width 0.1524)
		(layer "In7.Cu")
		(net "M_B_DQ2")
	)
	(segment
		(start 93.6244 -23.0378)
		(end 93.6244 -23.2918)
		(width 0.1016)
		(layer "In7.Cu")
		(net "M_B_DQ2")
	)
	(segment
		(start 130.567176 -12.6238)
		(end 130.414776 -12.7762)
		(width 0.1524)
		(layer "In7.Cu")
		(net "M_B_DQ2")
	)
	(segment
		(start 133.096 -9.2202)
		(end 133.096 -10.425684)
		(width 0.1524)
		(layer "In7.Cu")
		(net "M_B_DQ2")
	)
	(segment
		(start 120.015 -10.9982)
		(end 119.8118 -10.795)
		(width 0.1524)
		(layer "In7.Cu")
		(net "M_B_DQ2")
	)
	(segment
		(start 114.968782 -11.8872)
		(end 114.716306 -11.8872)
		(width 0.1524)
		(layer "In7.Cu")
		(net "M_B_DQ2")
	)
	(segment
		(start 131.510024 -11.936984)
		(end 131.30022 -11.72718)
		(width 0.1524)
		(layer "In7.Cu")
		(net "M_B_DQ2")
	)
	(segment
		(start 131.725416 -11.936984)
		(end 131.510024 -11.936984)
		(width 0.1524)
		(layer "In7.Cu")
		(net "M_B_DQ2")
	)
	(segment
		(start 131.941316 -11.505692)
		(end 131.941316 -11.721084)
		(width 0.1524)
		(layer "In7.Cu")
		(net "M_B_DQ2")
	)
	(segment
		(start 100.3046 -18.796)
		(end 99.568 -19.5326)
		(width 0.1524)
		(layer "In7.Cu")
		(net "M_B_DQ2")
	)
	(segment
		(start 131.610354 -11.174984)
		(end 131.941316 -11.505692)
		(width 0.1524)
		(layer "In7.Cu")
		(net "M_B_DQ2")
	)
	(segment
		(start 132.774182 -8.898382)
		(end 133.096 -9.2202)
		(width 0.1524)
		(layer "In7.Cu")
		(net "M_B_DQ2")
	)
	(segment
		(start 94.3102 -24.7142)
		(end 94.1578 -24.5618)
		(width 0.1524)
		(layer "In7.Cu")
		(net "M_B_DQ2")
	)
	(segment
		(start 133.096 -10.425684)
		(end 132.517134 -11.004042)
		(width 0.1524)
		(layer "In7.Cu")
		(net "M_B_DQ2")
	)
	(segment
		(start 132.517134 -11.004042)
		(end 132.301742 -11.004042)
		(width 0.1524)
		(layer "In7.Cu")
		(net "M_B_DQ2")
	)
	(segment
		(start 31.949898 -20.018502)
		(end 31.949898 -21.085302)
		(width 0.1143)
		(layer "F.Cu")
		(net "XDP_DFX_PORT11")
	)
	(segment
		(start 34.995358 -24.05507)
		(end 36.37788 -24.05507)
		(width 0.1143)
		(layer "F.Cu")
		(net "XDP_DFX_PORT11")
	)
	(segment
		(start 31.54045 -22.091396)
		(end 33.420304 -23.97125)
		(width 0.1143)
		(layer "F.Cu")
		(net "XDP_DFX_PORT11")
	)
	(segment
		(start 34.486088 -24.16175)
		(end 34.888678 -24.16175)
		(width 0.1143)
		(layer "F.Cu")
		(net "XDP_DFX_PORT11")
	)
	(segment
		(start 83.266788 -43.666156)
		(end 83.826858 -44.226226)
		(width 0.1143)
		(layer "F.Cu")
		(net "XDP_DFX_PORT11")
	)
	(segment
		(start 33.420304 -23.97125)
		(end 34.295588 -23.97125)
		(width 0.1143)
		(layer "F.Cu")
		(net "XDP_DFX_PORT11")
	)
	(segment
		(start 34.888678 -24.16175)
		(end 34.995358 -24.05507)
		(width 0.1143)
		(layer "F.Cu")
		(net "XDP_DFX_PORT11")
	)
	(segment
		(start 31.949898 -21.085302)
		(end 31.54045 -21.49475)
		(width 0.1143)
		(layer "F.Cu")
		(net "XDP_DFX_PORT11")
	)
	(segment
		(start 83.266788 -43.403774)
		(end 83.266788 -43.666156)
		(width 0.1143)
		(layer "F.Cu")
		(net "XDP_DFX_PORT11")
	)
	(segment
		(start 34.295588 -23.97125)
		(end 34.486088 -24.16175)
		(width 0.1143)
		(layer "F.Cu")
		(net "XDP_DFX_PORT11")
	)
	(segment
		(start 31.54045 -21.49475)
		(end 31.54045 -22.091396)
		(width 0.1143)
		(layer "F.Cu")
		(net "XDP_DFX_PORT11")
	)
	(via
		(at 83.826858 -44.226226)
		(size 0.4318)
		(drill 0.2032)
		(layers "F.Cu" "B.Cu")
		(net "XDP_DFX_PORT11")
	)
	(via
		(at 31.949898 -20.018502)
		(size 0.508)
		(drill 0.254)
		(layers "F.Cu" "B.Cu")
		(net "XDP_DFX_PORT11")
	)
	(via
		(at 31.6738 -19.1516)
		(size 0.7112)
		(drill 0.3556)
		(layers "F.Cu" "B.Cu")
		(net "XDP_DFX_PORT11")
	)
	(segment
		(start 31.949898 -20.018502)
		(end 31.949898 -19.427698)
		(width 0.1143)
		(layer "B.Cu")
		(net "XDP_DFX_PORT11")
	)
	(segment
		(start 31.949898 -19.427698)
		(end 31.6738 -19.1516)
		(width 0.1143)
		(layer "B.Cu")
		(net "XDP_DFX_PORT11")
	)
	(segment
		(start 79.520796 -41.079674)
		(end 77.642466 -41.079674)
		(width 0.0889)
		(layer "In7.Cu")
		(net "XDP_DFX_PORT11")
	)
	(segment
		(start 32.027368 -20.018502)
		(end 31.949898 -20.018502)
		(width 0.0889)
		(layer "In7.Cu")
		(net "XDP_DFX_PORT11")
	)
	(segment
		(start 66.284348 -34.823654)
		(end 65.191894 -33.7312)
		(width 0.0889)
		(layer "In7.Cu")
		(net "XDP_DFX_PORT11")
	)
	(segment
		(start 71.917052 -34.8234)
		(end 67.505326 -34.8234)
		(width 0.0889)
		(layer "In7.Cu")
		(net "XDP_DFX_PORT11")
	)
	(segment
		(start 72.533002 -35.43935)
		(end 71.917052 -34.8234)
		(width 0.0889)
		(layer "In7.Cu")
		(net "XDP_DFX_PORT11")
	)
	(segment
		(start 44.925996 -24.058118)
		(end 44.925996 -22.771862)
		(width 0.0889)
		(layer "In7.Cu")
		(net "XDP_DFX_PORT11")
	)
	(segment
		(start 44.925996 -22.771862)
		(end 40.765222 -18.611088)
		(width 0.0889)
		(layer "In7.Cu")
		(net "XDP_DFX_PORT11")
	)
	(segment
		(start 83.360514 -43.878246)
		(end 82.802222 -43.878246)
		(width 0.0889)
		(layer "In7.Cu")
		(net "XDP_DFX_PORT11")
	)
	(segment
		(start 44.76115 -24.222964)
		(end 44.925996 -24.058118)
		(width 0.0889)
		(layer "In7.Cu")
		(net "XDP_DFX_PORT11")
	)
	(segment
		(start 82.802222 -43.878246)
		(end 82.118962 -43.194986)
		(width 0.0889)
		(layer "In7.Cu")
		(net "XDP_DFX_PORT11")
	)
	(segment
		(start 40.765222 -18.611088)
		(end 33.434782 -18.611088)
		(width 0.0889)
		(layer "In7.Cu")
		(net "XDP_DFX_PORT11")
	)
	(segment
		(start 77.642466 -41.079674)
		(end 76.477622 -39.91483)
		(width 0.0889)
		(layer "In7.Cu")
		(net "XDP_DFX_PORT11")
	)
	(segment
		(start 65.191894 -33.7312)
		(end 61.14415 -33.7312)
		(width 0.0889)
		(layer "In7.Cu")
		(net "XDP_DFX_PORT11")
	)
	(segment
		(start 44.958 -25.3238)
		(end 44.76115 -25.12695)
		(width 0.0889)
		(layer "In7.Cu")
		(net "XDP_DFX_PORT11")
	)
	(segment
		(start 76.477622 -39.061898)
		(end 72.855074 -35.43935)
		(width 0.0889)
		(layer "In7.Cu")
		(net "XDP_DFX_PORT11")
	)
	(segment
		(start 83.826858 -44.226226)
		(end 83.708494 -44.226226)
		(width 0.0889)
		(layer "In7.Cu")
		(net "XDP_DFX_PORT11")
	)
	(segment
		(start 46.989492 -30.0228)
		(end 44.958 -27.991308)
		(width 0.0889)
		(layer "In7.Cu")
		(net "XDP_DFX_PORT11")
	)
	(segment
		(start 81.636108 -43.194986)
		(end 79.520796 -41.079674)
		(width 0.0889)
		(layer "In7.Cu")
		(net "XDP_DFX_PORT11")
	)
	(segment
		(start 67.505326 -34.8234)
		(end 67.505072 -34.823654)
		(width 0.0889)
		(layer "In7.Cu")
		(net "XDP_DFX_PORT11")
	)
	(segment
		(start 44.76115 -25.12695)
		(end 44.76115 -24.222964)
		(width 0.0889)
		(layer "In7.Cu")
		(net "XDP_DFX_PORT11")
	)
	(segment
		(start 44.958 -27.991308)
		(end 44.958 -25.3238)
		(width 0.0889)
		(layer "In7.Cu")
		(net "XDP_DFX_PORT11")
	)
	(segment
		(start 67.505072 -34.823654)
		(end 66.284348 -34.823654)
		(width 0.0889)
		(layer "In7.Cu")
		(net "XDP_DFX_PORT11")
	)
	(segment
		(start 52.002944 -32.8422)
		(end 49.183544 -30.0228)
		(width 0.0889)
		(layer "In7.Cu")
		(net "XDP_DFX_PORT11")
	)
	(segment
		(start 49.183544 -30.0228)
		(end 46.989492 -30.0228)
		(width 0.0889)
		(layer "In7.Cu")
		(net "XDP_DFX_PORT11")
	)
	(segment
		(start 72.855074 -35.43935)
		(end 72.533002 -35.43935)
		(width 0.0889)
		(layer "In7.Cu")
		(net "XDP_DFX_PORT11")
	)
	(segment
		(start 61.14415 -33.7312)
		(end 60.25515 -32.8422)
		(width 0.0889)
		(layer "In7.Cu")
		(net "XDP_DFX_PORT11")
	)
	(segment
		(start 82.118962 -43.194986)
		(end 81.636108 -43.194986)
		(width 0.0889)
		(layer "In7.Cu")
		(net "XDP_DFX_PORT11")
	)
	(segment
		(start 76.477622 -39.91483)
		(end 76.477622 -39.061898)
		(width 0.0889)
		(layer "In7.Cu")
		(net "XDP_DFX_PORT11")
	)
	(segment
		(start 83.708494 -44.226226)
		(end 83.360514 -43.878246)
		(width 0.0889)
		(layer "In7.Cu")
		(net "XDP_DFX_PORT11")
	)
	(segment
		(start 33.434782 -18.611088)
		(end 32.027368 -20.018502)
		(width 0.0889)
		(layer "In7.Cu")
		(net "XDP_DFX_PORT11")
	)
	(segment
		(start 60.25515 -32.8422)
		(end 52.002944 -32.8422)
		(width 0.0889)
		(layer "In7.Cu")
		(net "XDP_DFX_PORT11")
	)
	(segment
		(start 18.542 -33.9598)
		(end 19.05 -34.4678)
		(width 0.254)
		(layer "F.Cu")
		(net "P3V3_STBY_LL_R")
	)
	(segment
		(start 19.4056 -34.8234)
		(end 19.05 -34.4678)
		(width 0.254)
		(layer "F.Cu")
		(net "P3V3_STBY_LL_R")
	)
	(segment
		(start 18.542 -33.6042)
		(end 18.542 -33.9598)
		(width 0.254)
		(layer "F.Cu")
		(net "P3V3_STBY_LL_R")
	)
	(segment
		(start 19.4056 -35.3568)
		(end 19.4056 -34.8234)
		(width 0.254)
		(layer "F.Cu")
		(net "P3V3_STBY_LL_R")
	)
	(segment
		(start 19.4056 -35.3568)
		(end 20.0914 -35.3568)
		(width 0.254)
		(layer "F.Cu")
		(net "P3V3_STBY_LL_R")
	)
	(via
		(at 19.05 -34.4678)
		(size 0.7112)
		(drill 0.3556)
		(layers "F.Cu" "B.Cu")
		(net "P3V3_STBY_LL_R")
	)
	(segment
		(start 185.1406 -33.775904)
		(end 186.856116 -33.775904)
		(width 0.2032)
		(layer "F.Cu")
		(net "VR_PVDDR_A_IMON")
	)
	(via
		(at 185.7248 -35.179)
		(size 0.7112)
		(drill 0.3556)
		(layers "F.Cu" "B.Cu")
		(net "VR_PVDDR_A_IMON")
	)
	(via
		(at 185.1406 -33.775904)
		(size 0.508)
		(drill 0.254)
		(layers "F.Cu" "B.Cu")
		(net "VR_PVDDR_A_IMON")
	)
	(segment
		(start 186.5884 -34.0614)
		(end 185.553096 -34.0614)
		(width 0.2032)
		(layer "B.Cu")
		(net "VR_PVDDR_A_IMON")
	)
	(segment
		(start 185.7248 -35.179)
		(end 186.2074 -35.179)
		(width 0.2032)
		(layer "B.Cu")
		(net "VR_PVDDR_A_IMON")
	)
	(segment
		(start 185.2676 -33.775904)
		(end 185.1406 -33.775904)
		(width 0.2032)
		(layer "B.Cu")
		(net "VR_PVDDR_A_IMON")
	)
	(segment
		(start 185.553096 -34.0614)
		(end 185.2676 -33.775904)
		(width 0.2032)
		(layer "B.Cu")
		(net "VR_PVDDR_A_IMON")
	)
	(segment
		(start 186.563 -34.8234)
		(end 186.563 -34.0868)
		(width 0.2032)
		(layer "B.Cu")
		(net "VR_PVDDR_A_IMON")
	)
	(segment
		(start 186.563 -34.0868)
		(end 186.5884 -34.0614)
		(width 0.2032)
		(layer "B.Cu")
		(net "VR_PVDDR_A_IMON")
	)
	(segment
		(start 186.2074 -35.179)
		(end 186.563 -34.8234)
		(width 0.2032)
		(layer "B.Cu")
		(net "VR_PVDDR_A_IMON")
	)
	(segment
		(start 108.839 -20.193)
		(end 108.839 -19.5326)
		(width 0.1143)
		(layer "F.Cu")
		(net "M_B_MON2_P")
	)
	(segment
		(start 108.839 -19.5326)
		(end 108.4834 -19.177)
		(width 0.1143)
		(layer "F.Cu")
		(net "M_B_MON2_P")
	)
	(segment
		(start 108.33735 -19.03095)
		(end 108.4834 -19.177)
		(width 0.1143)
		(layer "F.Cu")
		(net "M_B_MON2_P")
	)
	(segment
		(start 109.5502 -21.9202)
		(end 108.839 -21.209)
		(width 0.1143)
		(layer "F.Cu")
		(net "M_B_MON2_P")
	)
	(segment
		(start 108.839 -21.209)
		(end 108.839 -20.193)
		(width 0.1143)
		(layer "F.Cu")
		(net "M_B_MON2_P")
	)
	(segment
		(start 109.5502 -25.248362)
		(end 109.5502 -21.9202)
		(width 0.1143)
		(layer "F.Cu")
		(net "M_B_MON2_P")
	)
	(segment
		(start 107.39755 -19.03095)
		(end 108.33735 -19.03095)
		(width 0.1143)
		(layer "F.Cu")
		(net "M_B_MON2_P")
	)
	(segment
		(start 108.709968 -26.088594)
		(end 109.5502 -25.248362)
		(width 0.1143)
		(layer "F.Cu")
		(net "M_B_MON2_P")
	)
	(via
		(at 107.39755 -19.03095)
		(size 0.7112)
		(drill 0.3556)
		(layers "F.Cu" "B.Cu")
		(net "M_B_MON2_P")
	)
	(segment
		(start 99.593654 -31.140654)
		(end 99.944428 -31.491428)
		(width 0.1016)
		(layer "F.Cu")
		(net "M_B_CKE3")
	)
	(segment
		(start 157.150054 -3.459988)
		(end 156.643578 -3.966464)
		(width 0.1778)
		(layer "F.Cu")
		(net "M_B_CKE3")
	)
	(segment
		(start 99.591368 -31.140654)
		(end 99.593654 -31.140654)
		(width 0.1016)
		(layer "F.Cu")
		(net "M_B_CKE3")
	)
	(segment
		(start 157.150054 -1.68402)
		(end 157.150054 -3.459988)
		(width 0.1778)
		(layer "F.Cu")
		(net "M_B_CKE3")
	)
	(via
		(at 156.643578 -3.966464)
		(size 0.4318)
		(drill 0.2032)
		(layers "F.Cu" "B.Cu")
		(net "M_B_CKE3")
	)
	(via
		(at 99.944428 -31.491428)
		(size 0.4318)
		(drill 0.2032)
		(layers "F.Cu" "B.Cu")
		(net "M_B_CKE3")
	)
	(segment
		(start 113.8428 -16.888968)
		(end 113.8428 -17.2847)
		(width 0.1524)
		(layer "In9.Cu")
		(net "M_B_CKE3")
	)
	(segment
		(start 123.35129 -16.6624)
		(end 123.19889 -16.8148)
		(width 0.1524)
		(layer "In9.Cu")
		(net "M_B_CKE3")
	)
	(segment
		(start 156.961078 -4.283964)
		(end 156.961078 -7.021068)
		(width 0.1524)
		(layer "In9.Cu")
		(net "M_B_CKE3")
	)
	(segment
		(start 123.96089 -17.25549)
		(end 123.80849 -17.10309)
		(width 0.1524)
		(layer "In9.Cu")
		(net "M_B_CKE3")
	)
	(segment
		(start 137.65911 -17.25549)
		(end 123.96089 -17.25549)
		(width 0.1524)
		(layer "In9.Cu")
		(net "M_B_CKE3")
	)
	(segment
		(start 157.368494 -7.40156)
		(end 157.6324 -7.665466)
		(width 0.1524)
		(layer "In9.Cu")
		(net "M_B_CKE3")
	)
	(segment
		(start 138.176 -14.224)
		(end 138.176 -16.7386)
		(width 0.1524)
		(layer "In9.Cu")
		(net "M_B_CKE3")
	)
	(segment
		(start 122.301 -16.8783)
		(end 122.1105 -16.6878)
		(width 0.1524)
		(layer "In9.Cu")
		(net "M_B_CKE3")
	)
	(segment
		(start 99.619562 -31.166562)
		(end 99.944428 -31.491428)
		(width 0.1016)
		(layer "In9.Cu")
		(net "M_B_CKE3")
	)
	(segment
		(start 123.19889 -17.10309)
		(end 123.04649 -17.25549)
		(width 0.1524)
		(layer "In9.Cu")
		(net "M_B_CKE3")
	)
	(segment
		(start 109.522768 -21.209)
		(end 104.1273 -21.209)
		(width 0.1524)
		(layer "In9.Cu")
		(net "M_B_CKE3")
	)
	(segment
		(start 101.848412 -28.072588)
		(end 101.1555 -28.7655)
		(width 0.1016)
		(layer "In9.Cu")
		(net "M_B_CKE3")
	)
	(segment
		(start 123.04649 -17.25549)
		(end 122.46229 -17.25549)
		(width 0.1524)
		(layer "In9.Cu")
		(net "M_B_CKE3")
	)
	(segment
		(start 100.133912 -30.396688)
		(end 99.835208 -30.396688)
		(width 0.1016)
		(layer "In9.Cu")
		(net "M_B_CKE3")
	)
	(segment
		(start 113.8428 -17.2847)
		(end 113.6523 -17.4752)
		(width 0.1524)
		(layer "In9.Cu")
		(net "M_B_CKE3")
	)
	(segment
		(start 123.19889 -16.8148)
		(end 123.19889 -17.10309)
		(width 0.1524)
		(layer "In9.Cu")
		(net "M_B_CKE3")
	)
	(segment
		(start 103.9114 -26.574496)
		(end 103.006398 -27.479498)
		(width 0.1524)
		(layer "In9.Cu")
		(net "M_B_CKE3")
	)
	(segment
		(start 100.634038 -29.082492)
		(end 100.418138 -29.298392)
		(width 0.1016)
		(layer "In9.Cu")
		(net "M_B_CKE3")
	)
	(segment
		(start 100.2792 -30.2514)
		(end 100.133912 -30.396688)
		(width 0.1016)
		(layer "In9.Cu")
		(net "M_B_CKE3")
	)
	(segment
		(start 113.6523 -17.4752)
		(end 113.256568 -17.4752)
		(width 0.1524)
		(layer "In9.Cu")
		(net "M_B_CKE3")
	)
	(segment
		(start 102.413308 -28.072588)
		(end 101.848412 -28.072588)
		(width 0.1016)
		(layer "In9.Cu")
		(net "M_B_CKE3")
	)
	(segment
		(start 99.619562 -30.612334)
		(end 99.619562 -31.166562)
		(width 0.1016)
		(layer "In9.Cu")
		(net "M_B_CKE3")
	)
	(segment
		(start 123.80849 -16.8148)
		(end 123.65609 -16.6624)
		(width 0.1524)
		(layer "In9.Cu")
		(net "M_B_CKE3")
	)
	(segment
		(start 113.256568 -17.4752)
		(end 109.522768 -21.209)
		(width 0.1524)
		(layer "In9.Cu")
		(net "M_B_CKE3")
	)
	(segment
		(start 138.7602 -13.6398)
		(end 138.176 -14.224)
		(width 0.1524)
		(layer "In9.Cu")
		(net "M_B_CKE3")
	)
	(segment
		(start 123.80849 -17.10309)
		(end 123.80849 -16.8148)
		(width 0.1524)
		(layer "In9.Cu")
		(net "M_B_CKE3")
	)
	(segment
		(start 157.34157 -7.40156)
		(end 157.368494 -7.40156)
		(width 0.1524)
		(layer "In9.Cu")
		(net "M_B_CKE3")
	)
	(segment
		(start 138.176 -16.7386)
		(end 137.65911 -17.25549)
		(width 0.1524)
		(layer "In9.Cu")
		(net "M_B_CKE3")
	)
	(segment
		(start 103.006398 -27.479498)
		(end 102.413308 -28.072588)
		(width 0.1016)
		(layer "In9.Cu")
		(net "M_B_CKE3")
	)
	(segment
		(start 156.643578 -3.966464)
		(end 156.961078 -4.283964)
		(width 0.1524)
		(layer "In9.Cu")
		(net "M_B_CKE3")
	)
	(segment
		(start 100.2792 -29.718)
		(end 100.2792 -30.2514)
		(width 0.1016)
		(layer "In9.Cu")
		(net "M_B_CKE3")
	)
	(segment
		(start 155.1813 -13.6398)
		(end 138.7602 -13.6398)
		(width 0.1524)
		(layer "In9.Cu")
		(net "M_B_CKE3")
	)
	(segment
		(start 104.1273 -21.209)
		(end 103.9114 -21.4249)
		(width 0.1524)
		(layer "In9.Cu")
		(net "M_B_CKE3")
	)
	(segment
		(start 114.043968 -16.6878)
		(end 113.8428 -16.888968)
		(width 0.1524)
		(layer "In9.Cu")
		(net "M_B_CKE3")
	)
	(segment
		(start 123.65609 -16.6624)
		(end 123.35129 -16.6624)
		(width 0.1524)
		(layer "In9.Cu")
		(net "M_B_CKE3")
	)
	(segment
		(start 122.1105 -16.6878)
		(end 114.043968 -16.6878)
		(width 0.1524)
		(layer "In9.Cu")
		(net "M_B_CKE3")
	)
	(segment
		(start 157.6324 -11.1887)
		(end 155.1813 -13.6398)
		(width 0.1524)
		(layer "In9.Cu")
		(net "M_B_CKE3")
	)
	(segment
		(start 99.835208 -30.396688)
		(end 99.619562 -30.612334)
		(width 0.1016)
		(layer "In9.Cu")
		(net "M_B_CKE3")
	)
	(segment
		(start 122.301 -17.0942)
		(end 122.301 -16.8783)
		(width 0.1524)
		(layer "In9.Cu")
		(net "M_B_CKE3")
	)
	(segment
		(start 156.961078 -7.021068)
		(end 157.34157 -7.40156)
		(width 0.1524)
		(layer "In9.Cu")
		(net "M_B_CKE3")
	)
	(segment
		(start 157.6324 -7.665466)
		(end 157.6324 -11.1887)
		(width 0.1524)
		(layer "In9.Cu")
		(net "M_B_CKE3")
	)
	(segment
		(start 122.46229 -17.25549)
		(end 122.301 -17.0942)
		(width 0.1524)
		(layer "In9.Cu")
		(net "M_B_CKE3")
	)
	(segment
		(start 103.9114 -21.4249)
		(end 103.9114 -26.574496)
		(width 0.1524)
		(layer "In9.Cu")
		(net "M_B_CKE3")
	)
	(arc
		(start 100.88372 -28.927298)
		(mid 100.736737 -28.969263)
		(end 100.634038 -29.082492)
		(width 0.1016)
		(layer "In9.Cu")
		(net "M_B_CKE3")
	)
	(arc
		(start 101.1555 -28.7655)
		(mid 101.034469 -28.871349)
		(end 100.88372 -28.927298)
		(width 0.1016)
		(layer "In9.Cu")
		(net "M_B_CKE3")
	)
	(arc
		(start 100.418138 -29.298392)
		(mid 100.314834 -29.496993)
		(end 100.2792 -29.718)
		(width 0.1016)
		(layer "In9.Cu")
		(net "M_B_CKE3")
	)
	(segment
		(start 38.826694 -26.55443)
		(end 39.1922 -26.188924)
		(width 0.1143)
		(layer "F.Cu")
		(net "XDP_DFX_PORT12")
	)
	(segment
		(start 39.1922 -26.188924)
		(end 39.1922 -26.1747)
		(width 0.1143)
		(layer "F.Cu")
		(net "XDP_DFX_PORT12")
	)
	(segment
		(start 36.37788 -26.55443)
		(end 38.826694 -26.55443)
		(width 0.1143)
		(layer "F.Cu")
		(net "XDP_DFX_PORT12")
	)
	(segment
		(start 77.493114 -44.167552)
		(end 77.493114 -44.168314)
		(width 0.1143)
		(layer "F.Cu")
		(net "XDP_DFX_PORT12")
	)
	(segment
		(start 79.871316 -44.535344)
		(end 80.144366 -44.808394)
		(width 0.1143)
		(layer "F.Cu")
		(net "XDP_DFX_PORT12")
	)
	(segment
		(start 77.860144 -44.535344)
		(end 79.871316 -44.535344)
		(width 0.1143)
		(layer "F.Cu")
		(net "XDP_DFX_PORT12")
	)
	(segment
		(start 39.1922 -26.1747)
		(end 39.2557 -26.1112)
		(width 0.1143)
		(layer "F.Cu")
		(net "XDP_DFX_PORT12")
	)
	(segment
		(start 80.144366 -44.808394)
		(end 80.607408 -44.808394)
		(width 0.1143)
		(layer "F.Cu")
		(net "XDP_DFX_PORT12")
	)
	(segment
		(start 77.493114 -44.168314)
		(end 77.860144 -44.535344)
		(width 0.1143)
		(layer "F.Cu")
		(net "XDP_DFX_PORT12")
	)
	(via
		(at 77.493114 -44.167552)
		(size 0.508)
		(drill 0.254)
		(layers "F.Cu" "B.Cu")
		(net "XDP_DFX_PORT12")
	)
	(via
		(at 39.2557 -26.1112)
		(size 0.508)
		(drill 0.254)
		(layers "F.Cu" "B.Cu")
		(net "XDP_DFX_PORT12")
	)
	(via
		(at 78.373986 -44.400978)
		(size 0.7112)
		(drill 0.3556)
		(layers "F.Cu" "B.Cu")
		(net "XDP_DFX_PORT12")
	)
	(segment
		(start 77.713078 -44.387516)
		(end 78.360524 -44.387516)
		(width 0.1143)
		(layer "B.Cu")
		(net "XDP_DFX_PORT12")
	)
	(segment
		(start 77.493114 -44.167552)
		(end 77.713078 -44.387516)
		(width 0.1143)
		(layer "B.Cu")
		(net "XDP_DFX_PORT12")
	)
	(segment
		(start 78.360524 -44.387516)
		(end 78.373986 -44.400978)
		(width 0.1143)
		(layer "B.Cu")
		(net "XDP_DFX_PORT12")
	)
	(segment
		(start 77.492606 -44.061634)
		(end 77.492606 -44.167044)
		(width 0.0889)
		(layer "In7.Cu")
		(net "XDP_DFX_PORT12")
	)
	(segment
		(start 70.378066 -42.057066)
		(end 74.332592 -42.057066)
		(width 0.0889)
		(layer "In7.Cu")
		(net "XDP_DFX_PORT12")
	)
	(segment
		(start 47.498 -34.6202)
		(end 48.509682 -34.6202)
		(width 0.0889)
		(layer "In7.Cu")
		(net "XDP_DFX_PORT12")
	)
	(segment
		(start 46.0756 -33.1978)
		(end 47.498 -34.6202)
		(width 0.0889)
		(layer "In7.Cu")
		(net "XDP_DFX_PORT12")
	)
	(segment
		(start 70.07225 -39.33825)
		(end 70.07225 -41.75125)
		(width 0.0889)
		(layer "In7.Cu")
		(net "XDP_DFX_PORT12")
	)
	(segment
		(start 56.283352 -36.858956)
		(end 57.441846 -38.01745)
		(width 0.0889)
		(layer "In7.Cu")
		(net "XDP_DFX_PORT12")
	)
	(segment
		(start 75.983592 -43.6753)
		(end 77.106272 -43.6753)
		(width 0.0889)
		(layer "In7.Cu")
		(net "XDP_DFX_PORT12")
	)
	(segment
		(start 70.07225 -41.75125)
		(end 70.378066 -42.057066)
		(width 0.0889)
		(layer "In7.Cu")
		(net "XDP_DFX_PORT12")
	)
	(segment
		(start 48.509682 -34.6202)
		(end 50.748438 -36.858956)
		(width 0.0889)
		(layer "In7.Cu")
		(net "XDP_DFX_PORT12")
	)
	(segment
		(start 39.2557 -26.1112)
		(end 46.0756 -32.9311)
		(width 0.0889)
		(layer "In7.Cu")
		(net "XDP_DFX_PORT12")
	)
	(segment
		(start 57.441846 -38.01745)
		(end 65.628266 -38.01745)
		(width 0.0889)
		(layer "In7.Cu")
		(net "XDP_DFX_PORT12")
	)
	(segment
		(start 46.0756 -32.9311)
		(end 46.0756 -33.1978)
		(width 0.0889)
		(layer "In7.Cu")
		(net "XDP_DFX_PORT12")
	)
	(segment
		(start 74.332592 -42.057066)
		(end 74.54138 -42.265854)
		(width 0.0889)
		(layer "In7.Cu")
		(net "XDP_DFX_PORT12")
	)
	(segment
		(start 77.492606 -44.167044)
		(end 77.493114 -44.167552)
		(width 0.0889)
		(layer "In7.Cu")
		(net "XDP_DFX_PORT12")
	)
	(segment
		(start 66.726816 -39.116)
		(end 69.85 -39.116)
		(width 0.0889)
		(layer "In7.Cu")
		(net "XDP_DFX_PORT12")
	)
	(segment
		(start 50.748438 -36.858956)
		(end 56.283352 -36.858956)
		(width 0.0889)
		(layer "In7.Cu")
		(net "XDP_DFX_PORT12")
	)
	(segment
		(start 74.54138 -42.265854)
		(end 74.574146 -42.265854)
		(width 0.0889)
		(layer "In7.Cu")
		(net "XDP_DFX_PORT12")
	)
	(segment
		(start 65.628266 -38.01745)
		(end 66.726816 -39.116)
		(width 0.0889)
		(layer "In7.Cu")
		(net "XDP_DFX_PORT12")
	)
	(segment
		(start 77.106272 -43.6753)
		(end 77.492606 -44.061634)
		(width 0.0889)
		(layer "In7.Cu")
		(net "XDP_DFX_PORT12")
	)
	(segment
		(start 69.85 -39.116)
		(end 70.07225 -39.33825)
		(width 0.0889)
		(layer "In7.Cu")
		(net "XDP_DFX_PORT12")
	)
	(segment
		(start 74.574146 -42.265854)
		(end 75.983592 -43.6753)
		(width 0.0889)
		(layer "In7.Cu")
		(net "XDP_DFX_PORT12")
	)
	(via
		(at 14.1224 -40.3098)
		(size 0.7112)
		(drill 0.3556)
		(layers "F.Cu" "B.Cu")
		(net "P3V3_STBY_LL")
	)
	(segment
		(start 99.892866 -33.027112)
		(end 99.48672 -33.027112)
		(width 0.1524)
		(layer "F.Cu")
		(net "M_B_CMDPU")
	)
	(segment
		(start 99.0854 -32.625792)
		(end 99.0854 -32.4104)
		(width 0.1524)
		(layer "F.Cu")
		(net "M_B_CMDPU")
	)
	(segment
		(start 99.48672 -33.027112)
		(end 99.0854 -32.625792)
		(width 0.1524)
		(layer "F.Cu")
		(net "M_B_CMDPU")
	)
	(segment
		(start 100.292408 -33.426654)
		(end 99.892866 -33.027112)
		(width 0.1524)
		(layer "F.Cu")
		(net "M_B_CMDPU")
	)
	(via
		(at 98.3234 -26.1874)
		(size 0.7112)
		(drill 0.3556)
		(layers "F.Cu" "B.Cu")
		(net "M_B_CMDPU")
	)
	(via
		(at 99.0854 -32.4104)
		(size 0.4318)
		(drill 0.2032)
		(layers "F.Cu" "B.Cu")
		(net "M_B_CMDPU")
	)
	(segment
		(start 98.3234 -26.10993)
		(end 98.3234 -26.1874)
		(width 0.1778)
		(layer "B.Cu")
		(net "M_B_CMDPU")
	)
	(segment
		(start 98.592894 -27.80665)
		(end 98.592894 -26.456894)
		(width 0.1778)
		(layer "B.Cu")
		(net "M_B_CMDPU")
	)
	(segment
		(start 99.695 -22.606)
		(end 99.695 -24.73833)
		(width 0.1778)
		(layer "B.Cu")
		(net "M_B_CMDPU")
	)
	(segment
		(start 98.592894 -26.456894)
		(end 98.3234 -26.1874)
		(width 0.1778)
		(layer "B.Cu")
		(net "M_B_CMDPU")
	)
	(segment
		(start 99.695 -24.73833)
		(end 98.3234 -26.10993)
		(width 0.1778)
		(layer "B.Cu")
		(net "M_B_CMDPU")
	)
	(segment
		(start 99.0854 -32.4104)
		(end 98.631756 -31.956756)
		(width 0.1778)
		(layer "B.Cu")
		(net "M_B_CMDPU")
	)
	(segment
		(start 98.658934 -30.644338)
		(end 98.658934 -28.790138)
		(width 0.1778)
		(layer "B.Cu")
		(net "M_B_CMDPU")
	)
	(segment
		(start 99.949 -22.352)
		(end 99.695 -22.606)
		(width 0.1778)
		(layer "B.Cu")
		(net "M_B_CMDPU")
	)
	(segment
		(start 98.5774 -27.822144)
		(end 98.592894 -27.80665)
		(width 0.1778)
		(layer "B.Cu")
		(net "M_B_CMDPU")
	)
	(segment
		(start 98.631756 -31.956756)
		(end 98.631756 -30.671516)
		(width 0.1778)
		(layer "B.Cu")
		(net "M_B_CMDPU")
	)
	(segment
		(start 98.631756 -30.671516)
		(end 98.658934 -30.644338)
		(width 0.1778)
		(layer "B.Cu")
		(net "M_B_CMDPU")
	)
	(segment
		(start 98.658934 -28.790138)
		(end 98.5774 -28.708604)
		(width 0.1778)
		(layer "B.Cu")
		(net "M_B_CMDPU")
	)
	(segment
		(start 98.5774 -28.708604)
		(end 98.5774 -27.822144)
		(width 0.1778)
		(layer "B.Cu")
		(net "M_B_CMDPU")
	)
	(segment
		(start 98.306128 -30.759654)
		(end 98.306128 -30.693106)
		(width 0.1016)
		(layer "F.Cu")
		(net "M_B_DQS_DN3")
	)
	(segment
		(start 146.197574 -9.005316)
		(end 146.197574 -6.083046)
		(width 0.1778)
		(layer "F.Cu")
		(net "M_B_DQS_DN3")
	)
	(segment
		(start 146.05 -9.897364)
		(end 146.05 -9.15289)
		(width 0.1778)
		(layer "F.Cu")
		(net "M_B_DQS_DN3")
	)
	(segment
		(start 98.306128 -30.693106)
		(end 97.973134 -30.360112)
		(width 0.1016)
		(layer "F.Cu")
		(net "M_B_DQS_DN3")
	)
	(segment
		(start 146.05 -9.15289)
		(end 146.197574 -9.005316)
		(width 0.1778)
		(layer "F.Cu")
		(net "M_B_DQS_DN3")
	)
	(segment
		(start 146.197574 -6.083046)
		(end 145.932906 -5.818378)
		(width 0.1778)
		(layer "F.Cu")
		(net "M_B_DQS_DN3")
	)
	(via
		(at 145.932906 -5.818378)
		(size 0.4318)
		(drill 0.2032)
		(layers "F.Cu" "B.Cu")
		(net "M_B_DQS_DN3")
	)
	(via
		(at 97.973134 -30.360112)
		(size 0.4318)
		(drill 0.2032)
		(layers "F.Cu" "B.Cu")
		(net "M_B_DQS_DN3")
	)
	(segment
		(start 146.197574 -5.55371)
		(end 145.932906 -5.818378)
		(width 0.1778)
		(layer "B.Cu")
		(net "M_B_DQS_DN3")
	)
	(segment
		(start 146.05 -2.465578)
		(end 146.197574 -2.613152)
		(width 0.1778)
		(layer "B.Cu")
		(net "M_B_DQS_DN3")
	)
	(segment
		(start 146.05 -1.690624)
		(end 146.05 -2.465578)
		(width 0.1778)
		(layer "B.Cu")
		(net "M_B_DQS_DN3")
	)
	(segment
		(start 146.197574 -2.613152)
		(end 146.197574 -5.55371)
		(width 0.1778)
		(layer "B.Cu")
		(net "M_B_DQS_DN3")
	)
	(segment
		(start 125.177042 -20.5486)
		(end 125.052582 -20.42414)
		(width 0.1524)
		(layer "In4.Cu")
		(net "M_B_DQS_DN3")
	)
	(segment
		(start 125.80874 -20.42414)
		(end 125.68428 -20.5486)
		(width 0.1524)
		(layer "In4.Cu")
		(net "M_B_DQS_DN3")
	)
	(segment
		(start 133.223 -20.5486)
		(end 133.09854 -20.42414)
		(width 0.1524)
		(layer "In4.Cu")
		(net "M_B_DQS_DN3")
	)
	(segment
		(start 131.35356 -20.5486)
		(end 130.89636 -20.5486)
		(width 0.1524)
		(layer "In4.Cu")
		(net "M_B_DQS_DN3")
	)
	(segment
		(start 135.0772 -19.594576)
		(end 135.0772 -20.432776)
		(width 0.1524)
		(layer "In4.Cu")
		(net "M_B_DQS_DN3")
	)
	(segment
		(start 126.8476 -20.5486)
		(end 126.3904 -20.5486)
		(width 0.1524)
		(layer "In4.Cu")
		(net "M_B_DQS_DN3")
	)
	(segment
		(start 134.961376 -20.5486)
		(end 133.223 -20.5486)
		(width 0.1524)
		(layer "In4.Cu")
		(net "M_B_DQS_DN3")
	)
	(segment
		(start 114.768376 -20.5486)
		(end 112.329976 -22.987)
		(width 0.1524)
		(layer "In4.Cu")
		(net "M_B_DQS_DN3")
	)
	(segment
		(start 104.864408 -26.915872)
		(end 101.13645 -26.915872)
		(width 0.1016)
		(layer "In4.Cu")
		(net "M_B_DQS_DN3")
	)
	(segment
		(start 107.051602 -25.626314)
		(end 107.033822 -25.644094)
		(width 0.1016)
		(layer "In4.Cu")
		(net "M_B_DQS_DN3")
	)
	(segment
		(start 135.393176 -19.2786)
		(end 135.0772 -19.594576)
		(width 0.1524)
		(layer "In4.Cu")
		(net "M_B_DQS_DN3")
	)
	(segment
		(start 127.42926 -20.42414)
		(end 126.97206 -20.42414)
		(width 0.1524)
		(layer "In4.Cu")
		(net "M_B_DQS_DN3")
	)
	(segment
		(start 101.13645 -26.915872)
		(end 98.806762 -29.24556)
		(width 0.1016)
		(layer "In4.Cu")
		(net "M_B_DQS_DN3")
	)
	(segment
		(start 146.0246 -8.562848)
		(end 145.897854 -8.689594)
		(width 0.1524)
		(layer "In4.Cu")
		(net "M_B_DQS_DN3")
	)
	(segment
		(start 135.955024 -19.2786)
		(end 135.393176 -19.2786)
		(width 0.1524)
		(layer "In4.Cu")
		(net "M_B_DQS_DN3")
	)
	(segment
		(start 132.64134 -20.42414)
		(end 132.51688 -20.5486)
		(width 0.1524)
		(layer "In4.Cu")
		(net "M_B_DQS_DN3")
	)
	(segment
		(start 124.595382 -20.42414)
		(end 124.470922 -20.5486)
		(width 0.1524)
		(layer "In4.Cu")
		(net "M_B_DQS_DN3")
	)
	(segment
		(start 126.26594 -20.42414)
		(end 125.80874 -20.42414)
		(width 0.1524)
		(layer "In4.Cu")
		(net "M_B_DQS_DN3")
	)
	(segment
		(start 125.052582 -20.42414)
		(end 124.595382 -20.42414)
		(width 0.1524)
		(layer "In4.Cu")
		(net "M_B_DQS_DN3")
	)
	(segment
		(start 107.033822 -25.69845)
		(end 106.824272 -25.908)
		(width 0.1016)
		(layer "In4.Cu")
		(net "M_B_DQS_DN3")
	)
	(segment
		(start 98.272346 -30.360112)
		(end 97.973134 -30.360112)
		(width 0.1016)
		(layer "In4.Cu")
		(net "M_B_DQS_DN3")
	)
	(segment
		(start 132.51688 -20.5486)
		(end 132.05968 -20.5486)
		(width 0.1524)
		(layer "In4.Cu")
		(net "M_B_DQS_DN3")
	)
	(segment
		(start 127.55372 -20.5486)
		(end 127.42926 -20.42414)
		(width 0.1524)
		(layer "In4.Cu")
		(net "M_B_DQS_DN3")
	)
	(segment
		(start 126.3904 -20.5486)
		(end 126.26594 -20.42414)
		(width 0.1524)
		(layer "In4.Cu")
		(net "M_B_DQS_DN3")
	)
	(segment
		(start 128.71704 -20.5486)
		(end 128.59258 -20.42414)
		(width 0.1524)
		(layer "In4.Cu")
		(net "M_B_DQS_DN3")
	)
	(segment
		(start 136.488424 -20.5486)
		(end 136.271 -20.331176)
		(width 0.1524)
		(layer "In4.Cu")
		(net "M_B_DQS_DN3")
	)
	(segment
		(start 124.470922 -20.5486)
		(end 114.768376 -20.5486)
		(width 0.1524)
		(layer "In4.Cu")
		(net "M_B_DQS_DN3")
	)
	(segment
		(start 98.806762 -29.24556)
		(end 98.806762 -29.825696)
		(width 0.1016)
		(layer "In4.Cu")
		(net "M_B_DQS_DN3")
	)
	(segment
		(start 125.68428 -20.5486)
		(end 125.177042 -20.5486)
		(width 0.1524)
		(layer "In4.Cu")
		(net "M_B_DQS_DN3")
	)
	(segment
		(start 131.93522 -20.42414)
		(end 131.47802 -20.42414)
		(width 0.1524)
		(layer "In4.Cu")
		(net "M_B_DQS_DN3")
	)
	(segment
		(start 146.2278 -6.402578)
		(end 146.0246 -6.605778)
		(width 0.1524)
		(layer "In4.Cu")
		(net "M_B_DQS_DN3")
	)
	(segment
		(start 108.331 -22.987)
		(end 107.7214 -23.5966)
		(width 0.1524)
		(layer "In4.Cu")
		(net "M_B_DQS_DN3")
	)
	(segment
		(start 133.09854 -20.42414)
		(end 132.64134 -20.42414)
		(width 0.1524)
		(layer "In4.Cu")
		(net "M_B_DQS_DN3")
	)
	(segment
		(start 105.873042 -25.908)
		(end 104.864408 -26.915872)
		(width 0.1016)
		(layer "In4.Cu")
		(net "M_B_DQS_DN3")
	)
	(segment
		(start 107.033822 -25.644094)
		(end 107.033822 -25.69845)
		(width 0.1016)
		(layer "In4.Cu")
		(net "M_B_DQS_DN3")
	)
	(segment
		(start 128.13538 -20.42414)
		(end 128.01092 -20.5486)
		(width 0.1524)
		(layer "In4.Cu")
		(net "M_B_DQS_DN3")
	)
	(segment
		(start 130.19024 -20.5486)
		(end 128.71704 -20.5486)
		(width 0.1524)
		(layer "In4.Cu")
		(net "M_B_DQS_DN3")
	)
	(segment
		(start 128.01092 -20.5486)
		(end 127.55372 -20.5486)
		(width 0.1524)
		(layer "In4.Cu")
		(net "M_B_DQS_DN3")
	)
	(segment
		(start 145.415 -20.5486)
		(end 136.488424 -20.5486)
		(width 0.1524)
		(layer "In4.Cu")
		(net "M_B_DQS_DN3")
	)
	(segment
		(start 130.89636 -20.5486)
		(end 130.7719 -20.42414)
		(width 0.1524)
		(layer "In4.Cu")
		(net "M_B_DQS_DN3")
	)
	(segment
		(start 128.59258 -20.42414)
		(end 128.13538 -20.42414)
		(width 0.1524)
		(layer "In4.Cu")
		(net "M_B_DQS_DN3")
	)
	(segment
		(start 146.2278 -6.113272)
		(end 146.2278 -6.402578)
		(width 0.1524)
		(layer "In4.Cu")
		(net "M_B_DQS_DN3")
	)
	(segment
		(start 112.329976 -22.987)
		(end 108.331 -22.987)
		(width 0.1524)
		(layer "In4.Cu")
		(net "M_B_DQS_DN3")
	)
	(segment
		(start 98.806762 -29.825696)
		(end 98.272346 -30.360112)
		(width 0.1016)
		(layer "In4.Cu")
		(net "M_B_DQS_DN3")
	)
	(segment
		(start 136.271 -19.594576)
		(end 135.955024 -19.2786)
		(width 0.1524)
		(layer "In4.Cu")
		(net "M_B_DQS_DN3")
	)
	(segment
		(start 126.97206 -20.42414)
		(end 126.8476 -20.5486)
		(width 0.1524)
		(layer "In4.Cu")
		(net "M_B_DQS_DN3")
	)
	(segment
		(start 106.824272 -25.908)
		(end 105.873042 -25.908)
		(width 0.1016)
		(layer "In4.Cu")
		(net "M_B_DQS_DN3")
	)
	(segment
		(start 130.3147 -20.42414)
		(end 130.19024 -20.5486)
		(width 0.1524)
		(layer "In4.Cu")
		(net "M_B_DQS_DN3")
	)
	(segment
		(start 135.0772 -20.432776)
		(end 134.961376 -20.5486)
		(width 0.1524)
		(layer "In4.Cu")
		(net "M_B_DQS_DN3")
	)
	(segment
		(start 131.47802 -20.42414)
		(end 131.35356 -20.5486)
		(width 0.1524)
		(layer "In4.Cu")
		(net "M_B_DQS_DN3")
	)
	(segment
		(start 145.897854 -8.689594)
		(end 145.897854 -20.065746)
		(width 0.1524)
		(layer "In4.Cu")
		(net "M_B_DQS_DN3")
	)
	(segment
		(start 146.0246 -6.605778)
		(end 146.0246 -8.562848)
		(width 0.1524)
		(layer "In4.Cu")
		(net "M_B_DQS_DN3")
	)
	(segment
		(start 145.897854 -20.065746)
		(end 145.415 -20.5486)
		(width 0.1524)
		(layer "In4.Cu")
		(net "M_B_DQS_DN3")
	)
	(segment
		(start 107.7214 -23.5966)
		(end 107.7214 -24.956516)
		(width 0.1524)
		(layer "In4.Cu")
		(net "M_B_DQS_DN3")
	)
	(segment
		(start 130.7719 -20.42414)
		(end 130.3147 -20.42414)
		(width 0.1524)
		(layer "In4.Cu")
		(net "M_B_DQS_DN3")
	)
	(segment
		(start 107.7214 -24.956516)
		(end 107.051602 -25.626314)
		(width 0.1524)
		(layer "In4.Cu")
		(net "M_B_DQS_DN3")
	)
	(segment
		(start 136.271 -20.331176)
		(end 136.271 -19.594576)
		(width 0.1524)
		(layer "In4.Cu")
		(net "M_B_DQS_DN3")
	)
	(segment
		(start 132.05968 -20.5486)
		(end 131.93522 -20.42414)
		(width 0.1524)
		(layer "In4.Cu")
		(net "M_B_DQS_DN3")
	)
	(segment
		(start 145.932906 -5.818378)
		(end 146.2278 -6.113272)
		(width 0.1524)
		(layer "In4.Cu")
		(net "M_B_DQS_DN3")
	)
	(segment
		(start 37.99078 -29.6164)
		(end 37.4777 -29.6164)
		(width 0.1397)
		(layer "F.Cu")
		(net "CLK_100M_XDP_R_DP")
	)
	(segment
		(start 37.41674 -29.55544)
		(end 36.37788 -29.55544)
		(width 0.1397)
		(layer "F.Cu")
		(net "CLK_100M_XDP_R_DP")
	)
	(segment
		(start 37.4777 -29.6164)
		(end 37.41674 -29.55544)
		(width 0.1397)
		(layer "F.Cu")
		(net "CLK_100M_XDP_R_DP")
	)
	(segment
		(start 38.27018 -29.337)
		(end 37.99078 -29.6164)
		(width 0.1397)
		(layer "F.Cu")
		(net "CLK_100M_XDP_R_DP")
	)
	(via
		(at 38.27018 -29.337)
		(size 0.508)
		(drill 0.254)
		(layers "F.Cu" "B.Cu")
		(net "CLK_100M_XDP_R_DP")
	)
	(segment
		(start 37.084 -31.90494)
		(end 41.29786 -36.1188)
		(width 0.1397)
		(layer "B.Cu")
		(net "CLK_100M_XDP_R_DP")
	)
	(segment
		(start 48.0568 -44.779692)
		(end 47.258732 -45.57776)
		(width 0.1397)
		(layer "B.Cu")
		(net "CLK_100M_XDP_R_DP")
	)
	(segment
		(start 48.0568 -44.1452)
		(end 48.0568 -44.779692)
		(width 0.1397)
		(layer "B.Cu")
		(net "CLK_100M_XDP_R_DP")
	)
	(segment
		(start 47.9044 -43.9928)
		(end 48.0568 -44.1452)
		(width 0.1397)
		(layer "B.Cu")
		(net "CLK_100M_XDP_R_DP")
	)
	(segment
		(start 45.339 -36.1188)
		(end 47.9044 -38.6842)
		(width 0.1397)
		(layer "B.Cu")
		(net "CLK_100M_XDP_R_DP")
	)
	(segment
		(start 41.29786 -36.1188)
		(end 45.339 -36.1188)
		(width 0.1397)
		(layer "B.Cu")
		(net "CLK_100M_XDP_R_DP")
	)
	(segment
		(start 38.01618 -29.591)
		(end 37.55136 -29.591)
		(width 0.1397)
		(layer "B.Cu")
		(net "CLK_100M_XDP_R_DP")
	)
	(segment
		(start 47.258732 -45.57776)
		(end 47.258732 -46.087792)
		(width 0.1397)
		(layer "B.Cu")
		(net "CLK_100M_XDP_R_DP")
	)
	(segment
		(start 47.9044 -38.6842)
		(end 47.9044 -43.9928)
		(width 0.1397)
		(layer "B.Cu")
		(net "CLK_100M_XDP_R_DP")
	)
	(segment
		(start 37.084 -30.05836)
		(end 37.084 -31.90494)
		(width 0.1397)
		(layer "B.Cu")
		(net "CLK_100M_XDP_R_DP")
	)
	(segment
		(start 37.55136 -29.591)
		(end 37.084 -30.05836)
		(width 0.1397)
		(layer "B.Cu")
		(net "CLK_100M_XDP_R_DP")
	)
	(segment
		(start 38.27018 -29.337)
		(end 38.01618 -29.591)
		(width 0.1397)
		(layer "B.Cu")
		(net "CLK_100M_XDP_R_DP")
	)
	(segment
		(start 13.371322 -35.449002)
		(end 15.477998 -35.449002)
		(width 0.3048)
		(layer "F.Cu")
		(net "P3V3_STBY_VBST")
	)
	(segment
		(start 15.477998 -35.449002)
		(end 15.7988 -35.1282)
		(width 0.3048)
		(layer "F.Cu")
		(net "P3V3_STBY_VBST")
	)
	(segment
		(start 188.849 -25.527)
		(end 188.849 -25.7048)
		(width 0.2032)
		(layer "F.Cu")
		(net "VSENSE_PVDDR_A_VSEN")
	)
	(segment
		(start 187.071 -26.5684)
		(end 187.833 -26.5684)
		(width 0.2032)
		(layer "F.Cu")
		(net "VSENSE_PVDDR_A_VSEN")
	)
	(segment
		(start 187.071 -25.781)
		(end 187.071 -26.5684)
		(width 0.2032)
		(layer "F.Cu")
		(net "VSENSE_PVDDR_A_VSEN")
	)
	(segment
		(start 187.9854 -26.5684)
		(end 187.833 -26.5684)
		(width 0.2032)
		(layer "F.Cu")
		(net "VSENSE_PVDDR_A_VSEN")
	)
	(segment
		(start 188.849 -25.7048)
		(end 187.9854 -26.5684)
		(width 0.2032)
		(layer "F.Cu")
		(net "VSENSE_PVDDR_A_VSEN")
	)
	(via
		(at 188.849 -25.527)
		(size 0.7112)
		(drill 0.3556)
		(layers "F.Cu" "B.Cu")
		(net "VSENSE_PVDDR_A_VSEN")
	)
	(segment
		(start 98.636328 -32.715454)
		(end 98.636328 -30.896306)
		(width 0.1524)
		(layer "F.Cu")
		(net "M_B_VREF")
	)
	(segment
		(start 98.636328 -30.896306)
		(end 99.042728 -30.489906)
		(width 0.1524)
		(layer "F.Cu")
		(net "M_B_VREF")
	)
	(segment
		(start 99.042728 -28.59913)
		(end 98.9838 -28.540202)
		(width 0.1524)
		(layer "F.Cu")
		(net "M_B_VREF")
	)
	(segment
		(start 99.042728 -30.489906)
		(end 99.042728 -28.59913)
		(width 0.1524)
		(layer "F.Cu")
		(net "M_B_VREF")
	)
	(segment
		(start 98.306128 -33.045654)
		(end 98.636328 -32.715454)
		(width 0.1524)
		(layer "F.Cu")
		(net "M_B_VREF")
	)
	(via
		(at 101.6 -26.9494)
		(size 0.7112)
		(drill 0.3556)
		(layers "F.Cu" "B.Cu")
		(net "M_B_VREF")
	)
	(via
		(at 98.9838 -28.540202)
		(size 0.4318)
		(drill 0.2032)
		(layers "F.Cu" "B.Cu")
		(net "M_B_VREF")
	)
	(segment
		(start 100.796598 -27.752802)
		(end 100.709984 -27.752802)
		(width 0.1778)
		(layer "B.Cu")
		(net "M_B_VREF")
	)
	(segment
		(start 100.709984 -27.752802)
		(end 100.684584 -27.778202)
		(width 0.1778)
		(layer "B.Cu")
		(net "M_B_VREF")
	)
	(segment
		(start 100.684584 -27.778202)
		(end 99.947984 -27.778202)
		(width 0.1778)
		(layer "B.Cu")
		(net "M_B_VREF")
	)
	(segment
		(start 102.489 -26.889202)
		(end 101.660198 -26.889202)
		(width 0.1778)
		(layer "B.Cu")
		(net "M_B_VREF")
	)
	(segment
		(start 98.9838 -28.540202)
		(end 99.7458 -27.778202)
		(width 0.1778)
		(layer "B.Cu")
		(net "M_B_VREF")
	)
	(segment
		(start 101.660198 -26.889202)
		(end 101.6 -26.9494)
		(width 0.1778)
		(layer "B.Cu")
		(net "M_B_VREF")
	)
	(segment
		(start 99.7458 -27.778202)
		(end 99.947984 -27.778202)
		(width 0.1778)
		(layer "B.Cu")
		(net "M_B_VREF")
	)
	(segment
		(start 101.6 -26.9494)
		(end 100.796598 -27.752802)
		(width 0.1778)
		(layer "B.Cu")
		(net "M_B_VREF")
	)
	(segment
		(start 99.248468 -26.956766)
		(end 99.248468 -26.957274)
		(width 0.1016)
		(layer "F.Cu")
		(net "M_B_DQ11")
	)
	(segment
		(start 98.3488 -24.9428)
		(end 98.737928 -25.331928)
		(width 0.1016)
		(layer "F.Cu")
		(net "M_B_DQ11")
	)
	(segment
		(start 98.737928 -25.331928)
		(end 98.737928 -26.111708)
		(width 0.1016)
		(layer "F.Cu")
		(net "M_B_DQ11")
	)
	(segment
		(start 138.5062 -8.04545)
		(end 138.665712 -7.885938)
		(width 0.1778)
		(layer "F.Cu")
		(net "M_B_DQ11")
	)
	(segment
		(start 138.5062 -8.637778)
		(end 138.5062 -8.04545)
		(width 0.1778)
		(layer "F.Cu")
		(net "M_B_DQ11")
	)
	(segment
		(start 99.045268 -26.753566)
		(end 99.248468 -26.956766)
		(width 0.1016)
		(layer "F.Cu")
		(net "M_B_DQ11")
	)
	(segment
		(start 98.737928 -26.111708)
		(end 99.045268 -26.419048)
		(width 0.1016)
		(layer "F.Cu")
		(net "M_B_DQ11")
	)
	(segment
		(start 99.045268 -26.419048)
		(end 99.045268 -26.753566)
		(width 0.1016)
		(layer "F.Cu")
		(net "M_B_DQ11")
	)
	(segment
		(start 138.849862 -8.98144)
		(end 138.5062 -8.637778)
		(width 0.1778)
		(layer "F.Cu")
		(net "M_B_DQ11")
	)
	(segment
		(start 138.849862 -9.897364)
		(end 138.849862 -8.98144)
		(width 0.1778)
		(layer "F.Cu")
		(net "M_B_DQ11")
	)
	(segment
		(start 98.3488 -22.987)
		(end 98.3488 -24.9428)
		(width 0.1016)
		(layer "F.Cu")
		(net "M_B_DQ11")
	)
	(via
		(at 138.665712 -7.885938)
		(size 0.4318)
		(drill 0.2032)
		(layers "F.Cu" "B.Cu")
		(net "M_B_DQ11")
	)
	(via
		(at 98.3488 -22.987)
		(size 0.4318)
		(drill 0.2032)
		(layers "F.Cu" "B.Cu")
		(net "M_B_DQ11")
	)
	(segment
		(start 138.4554 -8.50392)
		(end 138.4554 -8.09625)
		(width 0.1778)
		(layer "B.Cu")
		(net "M_B_DQ11")
	)
	(segment
		(start 138.4554 -8.09625)
		(end 138.665712 -7.885938)
		(width 0.1778)
		(layer "B.Cu")
		(net "M_B_DQ11")
	)
	(segment
		(start 137.94994 -9.89076)
		(end 137.94994 -9.00938)
		(width 0.1778)
		(layer "B.Cu")
		(net "M_B_DQ11")
	)
	(segment
		(start 137.94994 -9.00938)
		(end 138.4554 -8.50392)
		(width 0.1778)
		(layer "B.Cu")
		(net "M_B_DQ11")
	)
	(segment
		(start 140.2588 -11.10107)
		(end 140.9192 -11.10107)
		(width 0.1524)
		(layer "In2.Cu")
		(net "M_B_DQ11")
	)
	(segment
		(start 120.1674 -17.500346)
		(end 120.015 -17.652746)
		(width 0.1524)
		(layer "In2.Cu")
		(net "M_B_DQ11")
	)
	(segment
		(start 109.939836 -17.652746)
		(end 107.77982 -19.812762)
		(width 0.1524)
		(layer "In2.Cu")
		(net "M_B_DQ11")
	)
	(segment
		(start 137.5664 -13.601954)
		(end 137.5664 -16.1036)
		(width 0.1524)
		(layer "In2.Cu")
		(net "M_B_DQ11")
	)
	(segment
		(start 140.1064 -10.94867)
		(end 140.2588 -11.10107)
		(width 0.1524)
		(layer "In2.Cu")
		(net "M_B_DQ11")
	)
	(segment
		(start 138.665712 -7.885938)
		(end 138.5062 -8.04545)
		(width 0.1524)
		(layer "In2.Cu")
		(net "M_B_DQ11")
	)
	(segment
		(start 120.015 -17.652746)
		(end 109.939836 -17.652746)
		(width 0.1524)
		(layer "In2.Cu")
		(net "M_B_DQ11")
	)
	(segment
		(start 101.007926 -21.4376)
		(end 99.6696 -21.4376)
		(width 0.1524)
		(layer "In2.Cu")
		(net "M_B_DQ11")
	)
	(segment
		(start 120.3198 -16.256)
		(end 120.1674 -16.4084)
		(width 0.1524)
		(layer "In2.Cu")
		(net "M_B_DQ11")
	)
	(segment
		(start 138.7348 -9.7028)
		(end 139.954 -9.7028)
		(width 0.1524)
		(layer "In2.Cu")
		(net "M_B_DQ11")
	)
	(segment
		(start 139.864846 -13.449554)
		(end 137.7188 -13.449554)
		(width 0.1524)
		(layer "In2.Cu")
		(net "M_B_DQ11")
	)
	(segment
		(start 99.6696 -21.4376)
		(end 98.3488 -22.7584)
		(width 0.1524)
		(layer "In2.Cu")
		(net "M_B_DQ11")
	)
	(segment
		(start 140.9192 -12.01547)
		(end 140.2588 -12.01547)
		(width 0.1524)
		(layer "In2.Cu")
		(net "M_B_DQ11")
	)
	(segment
		(start 98.3488 -22.7584)
		(end 98.3488 -22.987)
		(width 0.1524)
		(layer "In2.Cu")
		(net "M_B_DQ11")
	)
	(segment
		(start 120.1674 -16.4084)
		(end 120.1674 -17.500346)
		(width 0.1524)
		(layer "In2.Cu")
		(net "M_B_DQ11")
	)
	(segment
		(start 138.5062 -9.4742)
		(end 138.7348 -9.7028)
		(width 0.1524)
		(layer "In2.Cu")
		(net "M_B_DQ11")
	)
	(segment
		(start 141.0716 -11.86307)
		(end 140.9192 -12.01547)
		(width 0.1524)
		(layer "In2.Cu")
		(net "M_B_DQ11")
	)
	(segment
		(start 138.5062 -8.04545)
		(end 138.5062 -9.4742)
		(width 0.1524)
		(layer "In2.Cu")
		(net "M_B_DQ11")
	)
	(segment
		(start 107.77982 -19.812762)
		(end 102.632764 -19.812762)
		(width 0.1524)
		(layer "In2.Cu")
		(net "M_B_DQ11")
	)
	(segment
		(start 140.1064 -13.208)
		(end 139.864846 -13.449554)
		(width 0.1524)
		(layer "In2.Cu")
		(net "M_B_DQ11")
	)
	(segment
		(start 139.954 -9.7028)
		(end 140.1064 -9.8552)
		(width 0.1524)
		(layer "In2.Cu")
		(net "M_B_DQ11")
	)
	(segment
		(start 141.0716 -11.25347)
		(end 141.0716 -11.86307)
		(width 0.1524)
		(layer "In2.Cu")
		(net "M_B_DQ11")
	)
	(segment
		(start 137.5664 -16.1036)
		(end 137.414 -16.256)
		(width 0.1524)
		(layer "In2.Cu")
		(net "M_B_DQ11")
	)
	(segment
		(start 102.632764 -19.812762)
		(end 101.007926 -21.4376)
		(width 0.1524)
		(layer "In2.Cu")
		(net "M_B_DQ11")
	)
	(segment
		(start 140.2588 -12.01547)
		(end 140.1064 -12.16787)
		(width 0.1524)
		(layer "In2.Cu")
		(net "M_B_DQ11")
	)
	(segment
		(start 140.1064 -12.16787)
		(end 140.1064 -13.208)
		(width 0.1524)
		(layer "In2.Cu")
		(net "M_B_DQ11")
	)
	(segment
		(start 140.9192 -11.10107)
		(end 141.0716 -11.25347)
		(width 0.1524)
		(layer "In2.Cu")
		(net "M_B_DQ11")
	)
	(segment
		(start 137.414 -16.256)
		(end 120.3198 -16.256)
		(width 0.1524)
		(layer "In2.Cu")
		(net "M_B_DQ11")
	)
	(segment
		(start 140.1064 -9.8552)
		(end 140.1064 -10.94867)
		(width 0.1524)
		(layer "In2.Cu")
		(net "M_B_DQ11")
	)
	(segment
		(start 137.7188 -13.449554)
		(end 137.5664 -13.601954)
		(width 0.1524)
		(layer "In2.Cu")
		(net "M_B_DQ11")
	)
	(segment
		(start 48.387 -34.29)
		(end 48.387 -31.1912)
		(width 0.1143)
		(layer "F.Cu")
		(net "SPI_MOSI_R_1")
	)
	(segment
		(start 48.387 -31.1912)
		(end 48.876966 -30.701234)
		(width 0.1143)
		(layer "F.Cu")
		(net "SPI_MOSI_R_1")
	)
	(segment
		(start 48.876966 -30.701234)
		(end 49.326038 -30.701234)
		(width 0.1143)
		(layer "F.Cu")
		(net "SPI_MOSI_R_1")
	)
	(segment
		(start 48.5902 -34.4932)
		(end 48.387 -34.29)
		(width 0.1143)
		(layer "F.Cu")
		(net "SPI_MOSI_R_1")
	)
	(segment
		(start 36.37788 -21.05533)
		(end 34.59353 -21.05533)
		(width 0.1143)
		(layer "F.Cu")
		(net "XDP_DFX_PORT_R_CLK1")
	)
	(segment
		(start 32.385 -19.304)
		(end 32.8422 -19.7612)
		(width 0.1143)
		(layer "F.Cu")
		(net "XDP_DFX_PORT_R_CLK1")
	)
	(segment
		(start 33.2994 -19.7612)
		(end 32.893 -19.7612)
		(width 0.1143)
		(layer "F.Cu")
		(net "XDP_DFX_PORT_R_CLK1")
	)
	(segment
		(start 32.385 -18.796)
		(end 32.385 -19.304)
		(width 0.1143)
		(layer "F.Cu")
		(net "XDP_DFX_PORT_R_CLK1")
	)
	(segment
		(start 34.59353 -21.05533)
		(end 33.2994 -19.7612)
		(width 0.1143)
		(layer "F.Cu")
		(net "XDP_DFX_PORT_R_CLK1")
	)
	(segment
		(start 32.004 -18.415)
		(end 32.385 -18.796)
		(width 0.1143)
		(layer "F.Cu")
		(net "XDP_DFX_PORT_R_CLK1")
	)
	(segment
		(start 32.8422 -19.7612)
		(end 32.893 -19.7612)
		(width 0.1143)
		(layer "F.Cu")
		(net "XDP_DFX_PORT_R_CLK1")
	)
	(via
		(at 32.004 -18.415)
		(size 0.7112)
		(drill 0.3556)
		(layers "F.Cu" "B.Cu")
		(net "XDP_DFX_PORT_R_CLK1")
	)
	(segment
		(start 191.135 -8.002778)
		(end 190.449962 -8.687816)
		(width 0.1143)
		(layer "F.Cu")
		(net "SMB_M_B1_R_DATA")
	)
	(segment
		(start 197.993 -9.704578)
		(end 195.1228 -9.704578)
		(width 0.1143)
		(layer "F.Cu")
		(net "SMB_M_B1_R_DATA")
	)
	(segment
		(start 195.1228 -9.704578)
		(end 193.421 -8.002778)
		(width 0.1143)
		(layer "F.Cu")
		(net "SMB_M_B1_R_DATA")
	)
	(segment
		(start 190.449962 -8.687816)
		(end 190.449962 -9.897364)
		(width 0.1143)
		(layer "F.Cu")
		(net "SMB_M_B1_R_DATA")
	)
	(segment
		(start 193.421 -8.002778)
		(end 191.135 -8.002778)
		(width 0.1143)
		(layer "F.Cu")
		(net "SMB_M_B1_R_DATA")
	)
	(segment
		(start 6.5532 -35.4076)
		(end 6.7056 -35.2552)
		(width 0.3048)
		(layer "F.Cu")
		(net "P3V3_STBY_VDD")
	)
	(segment
		(start 5.08 -33.8836)
		(end 5.1562 -33.9598)
		(width 0.508)
		(layer "F.Cu")
		(net "P3V3_STBY_VDD")
	)
	(segment
		(start 5.6388 -33.9598)
		(end 6.5532 -34.8742)
		(width 0.508)
		(layer "F.Cu")
		(net "P3V3_STBY_VDD")
	)
	(segment
		(start 7.883398 -35.2552)
		(end 8.0772 -35.449002)
		(width 0.3048)
		(layer "F.Cu")
		(net "P3V3_STBY_VDD")
	)
	(segment
		(start 6.7056 -35.2552)
		(end 7.883398 -35.2552)
		(width 0.3048)
		(layer "F.Cu")
		(net "P3V3_STBY_VDD")
	)
	(segment
		(start 8.0772 -35.449002)
		(end 8.726678 -35.449002)
		(width 0.3048)
		(layer "F.Cu")
		(net "P3V3_STBY_VDD")
	)
	(segment
		(start 6.5532 -34.8742)
		(end 6.5532 -35.4076)
		(width 0.508)
		(layer "F.Cu")
		(net "P3V3_STBY_VDD")
	)
	(segment
		(start 5.08 -32.9184)
		(end 5.08 -33.8836)
		(width 0.508)
		(layer "F.Cu")
		(net "P3V3_STBY_VDD")
	)
	(segment
		(start 5.1562 -33.9598)
		(end 5.6388 -33.9598)
		(width 0.508)
		(layer "F.Cu")
		(net "P3V3_STBY_VDD")
	)
	(via
		(at 5.1562 -33.9598)
		(size 0.7112)
		(drill 0.3556)
		(layers "F.Cu" "B.Cu")
		(net "P3V3_STBY_VDD")
	)
	(segment
		(start 193.7766 -34.29)
		(end 193.5734 -34.29)
		(width 0.3048)
		(layer "F.Cu")
		(net "VR_PVDDR_A_PHASE1")
	)
	(segment
		(start 194.691 -33.7312)
		(end 194.3354 -33.7312)
		(width 0.3048)
		(layer "F.Cu")
		(net "VR_PVDDR_A_PHASE1")
	)
	(segment
		(start 195.834 -32.6644)
		(end 196.018404 -32.6644)
		(width 0.3048)
		(layer "F.Cu")
		(net "VR_PVDDR_A_PHASE1")
	)
	(segment
		(start 191.656716 -33.775904)
		(end 192.754504 -33.775904)
		(width 0.2032)
		(layer "F.Cu")
		(net "VR_PVDDR_A_PHASE1")
	)
	(segment
		(start 194.691 -33.7312)
		(end 194.7672 -33.7312)
		(width 0.3048)
		(layer "F.Cu")
		(net "VR_PVDDR_A_PHASE1")
	)
	(segment
		(start 199.263 -32.766)
		(end 200.3044 -32.766)
		(width 0.4572)
		(layer "F.Cu")
		(net "VR_PVDDR_A_PHASE1")
	)
	(segment
		(start 197.1802 -32.6644)
		(end 197.1802 -32.378142)
		(width 0.4572)
		(layer "F.Cu")
		(net "VR_PVDDR_A_PHASE1")
	)
	(segment
		(start 194.3354 -33.7312)
		(end 193.7766 -34.29)
		(width 0.3048)
		(layer "F.Cu")
		(net "VR_PVDDR_A_PHASE1")
	)
	(segment
		(start 196.018404 -32.6644)
		(end 197.1802 -32.6644)
		(width 0.4572)
		(layer "F.Cu")
		(net "VR_PVDDR_A_PHASE1")
	)
	(segment
		(start 197.503542 -32.0548)
		(end 198.5518 -32.0548)
		(width 0.4572)
		(layer "F.Cu")
		(net "VR_PVDDR_A_PHASE1")
	)
	(segment
		(start 200.66381 -33.12541)
		(end 200.66381 -33.667446)
		(width 0.4572)
		(layer "F.Cu")
		(net "VR_PVDDR_A_PHASE1")
	)
	(segment
		(start 200.3044 -32.766)
		(end 200.66381 -33.12541)
		(width 0.4572)
		(layer "F.Cu")
		(net "VR_PVDDR_A_PHASE1")
	)
	(segment
		(start 194.7672 -33.7312)
		(end 195.834 -32.6644)
		(width 0.3048)
		(layer "F.Cu")
		(net "VR_PVDDR_A_PHASE1")
	)
	(segment
		(start 193.2686 -34.29)
		(end 193.5734 -34.29)
		(width 0.2032)
		(layer "F.Cu")
		(net "VR_PVDDR_A_PHASE1")
	)
	(segment
		(start 192.754504 -33.775904)
		(end 193.2686 -34.29)
		(width 0.2032)
		(layer "F.Cu")
		(net "VR_PVDDR_A_PHASE1")
	)
	(segment
		(start 198.5518 -32.0548)
		(end 199.263 -32.766)
		(width 0.4572)
		(layer "F.Cu")
		(net "VR_PVDDR_A_PHASE1")
	)
	(segment
		(start 197.1802 -32.378142)
		(end 197.503542 -32.0548)
		(width 0.4572)
		(layer "F.Cu")
		(net "VR_PVDDR_A_PHASE1")
	)
	(via
		(at 193.5734 -34.29)
		(size 0.7112)
		(drill 0.3556)
		(layers "F.Cu" "B.Cu")
		(net "VR_PVDDR_A_PHASE1")
	)
	(segment
		(start 111.0742 -20.193)
		(end 111.0742 -19.4056)
		(width 0.1143)
		(layer "F.Cu")
		(net "M_B_MON1_N")
	)
	(segment
		(start 110.335568 -26.708354)
		(end 110.335568 -26.901394)
		(width 0.1143)
		(layer "F.Cu")
		(net "M_B_MON1_N")
	)
	(segment
		(start 111.0742 -21.1074)
		(end 111.0742 -25.969722)
		(width 0.1143)
		(layer "F.Cu")
		(net "M_B_MON1_N")
	)
	(segment
		(start 111.0742 -19.4056)
		(end 110.8456 -19.177)
		(width 0.1143)
		(layer "F.Cu")
		(net "M_B_MON1_N")
	)
	(segment
		(start 111.0742 -25.969722)
		(end 110.335568 -26.708354)
		(width 0.1143)
		(layer "F.Cu")
		(net "M_B_MON1_N")
	)
	(segment
		(start 111.0742 -20.193)
		(end 111.0742 -21.1074)
		(width 0.1143)
		(layer "F.Cu")
		(net "M_B_MON1_N")
	)
	(via
		(at 111.0742 -21.1074)
		(size 0.7112)
		(drill 0.3556)
		(layers "F.Cu" "B.Cu")
		(net "M_B_MON1_N")
	)
	(segment
		(start 49.3522 -33.3502)
		(end 50.540412 -32.161988)
		(width 0.1143)
		(layer "F.Cu")
		(net "SPI_SCLK_R_1")
	)
	(segment
		(start 50.005234 -29.431234)
		(end 49.429162 -29.431234)
		(width 0.1143)
		(layer "F.Cu")
		(net "SPI_SCLK_R_1")
	)
	(segment
		(start 49.3522 -34.4932)
		(end 49.3522 -33.3502)
		(width 0.1143)
		(layer "F.Cu")
		(net "SPI_SCLK_R_1")
	)
	(segment
		(start 50.540412 -32.161988)
		(end 50.540412 -29.966412)
		(width 0.1143)
		(layer "F.Cu")
		(net "SPI_SCLK_R_1")
	)
	(segment
		(start 50.540412 -29.966412)
		(end 50.005234 -29.431234)
		(width 0.1143)
		(layer "F.Cu")
		(net "SPI_SCLK_R_1")
	)
	(segment
		(start 170.953176 -46.620176)
		(end 170.18 -45.847)
		(width 0.1143)
		(layer "F.Cu")
		(net "XDP_SOC_CPU_TDI")
	)
	(segment
		(start 31.3436 -35.8648)
		(end 31.4198 -35.7886)
		(width 0.1143)
		(layer "F.Cu")
		(net "XDP_SOC_CPU_TDI")
	)
	(segment
		(start 33.467548 -36.016184)
		(end 33.467548 -36.020502)
		(width 0.1143)
		(layer "F.Cu")
		(net "XDP_SOC_CPU_TDI")
	)
	(segment
		(start 170.953176 -48.375824)
		(end 170.953176 -46.620176)
		(width 0.1143)
		(layer "F.Cu")
		(net "XDP_SOC_CPU_TDI")
	)
	(segment
		(start 170.18 -45.847)
		(end 170.1546 -45.847)
		(width 0.1143)
		(layer "F.Cu")
		(net "XDP_SOC_CPU_TDI")
	)
	(segment
		(start 83.861402 -36.195508)
		(end 84.409788 -36.743894)
		(width 0.1143)
		(layer "F.Cu")
		(net "XDP_SOC_CPU_TDI")
	)
	(segment
		(start 31.4198 -35.8648)
		(end 32.2072 -36.6522)
		(width 0.1143)
		(layer "F.Cu")
		(net "XDP_SOC_CPU_TDI")
	)
	(segment
		(start 31.4198 -35.7886)
		(end 31.4198 -35.8648)
		(width 0.1143)
		(layer "F.Cu")
		(net "XDP_SOC_CPU_TDI")
	)
	(segment
		(start 29.3243 -35.8648)
		(end 31.3436 -35.8648)
		(width 0.1143)
		(layer "F.Cu")
		(net "XDP_SOC_CPU_TDI")
	)
	(segment
		(start 33.467548 -36.020502)
		(end 32.83585 -36.6522)
		(width 0.1143)
		(layer "F.Cu")
		(net "XDP_SOC_CPU_TDI")
	)
	(segment
		(start 32.83585 -36.6522)
		(end 32.2072 -36.6522)
		(width 0.1143)
		(layer "F.Cu")
		(net "XDP_SOC_CPU_TDI")
	)
	(segment
		(start 83.861402 -36.070032)
		(end 83.861402 -36.195508)
		(width 0.1143)
		(layer "F.Cu")
		(net "XDP_SOC_CPU_TDI")
	)
	(via
		(at 83.861402 -36.070032)
		(size 0.4318)
		(drill 0.2032)
		(layers "F.Cu" "B.Cu")
		(net "XDP_SOC_CPU_TDI")
	)
	(via
		(at 188.722 -53.594)
		(size 0.508)
		(drill 0.254)
		(layers "F.Cu" "B.Cu")
		(net "XDP_SOC_CPU_TDI")
	)
	(via
		(at 57.885076 -26.5684)
		(size 0.508)
		(drill 0.254)
		(layers "F.Cu" "B.Cu")
		(net "XDP_SOC_CPU_TDI")
	)
	(via
		(at 170.953176 -48.375824)
		(size 0.508)
		(drill 0.254)
		(layers "F.Cu" "B.Cu")
		(net "XDP_SOC_CPU_TDI")
	)
	(via
		(at 67.437 -63.3222)
		(size 0.508)
		(drill 0.254)
		(layers "F.Cu" "B.Cu")
		(net "XDP_SOC_CPU_TDI")
	)
	(via
		(at 33.467548 -36.016184)
		(size 0.508)
		(drill 0.254)
		(layers "F.Cu" "B.Cu")
		(net "XDP_SOC_CPU_TDI")
	)
	(segment
		(start 84.455508 -36.070032)
		(end 84.65058 -35.87496)
		(width 0.1143)
		(layer "B.Cu")
		(net "XDP_SOC_CPU_TDI")
	)
	(segment
		(start 83.861402 -36.070032)
		(end 84.455508 -36.070032)
		(width 0.1143)
		(layer "B.Cu")
		(net "XDP_SOC_CPU_TDI")
	)
	(segment
		(start 43.86199 -44.321984)
		(end 45.348906 -45.8089)
		(width 0.0889)
		(layer "In2.Cu")
		(net "XDP_SOC_CPU_TDI")
	)
	(segment
		(start 35.742118 -35.687)
		(end 38.502844 -35.687)
		(width 0.0889)
		(layer "In2.Cu")
		(net "XDP_SOC_CPU_TDI")
	)
	(segment
		(start 50.979832 -49.4284)
		(end 53.494686 -51.943254)
		(width 0.0889)
		(layer "In2.Cu")
		(net "XDP_SOC_CPU_TDI")
	)
	(segment
		(start 40.45585 -37.640006)
		(end 40.45585 -38.86835)
		(width 0.0889)
		(layer "In2.Cu")
		(net "XDP_SOC_CPU_TDI")
	)
	(segment
		(start 55.501286 -53.3273)
		(end 61.24575 -59.071764)
		(width 0.0889)
		(layer "In2.Cu")
		(net "XDP_SOC_CPU_TDI")
	)
	(segment
		(start 53.494686 -52.060856)
		(end 54.76113 -53.3273)
		(width 0.0889)
		(layer "In2.Cu")
		(net "XDP_SOC_CPU_TDI")
	)
	(segment
		(start 35.352736 -35.686746)
		(end 35.741864 -35.686746)
		(width 0.0889)
		(layer "In2.Cu")
		(net "XDP_SOC_CPU_TDI")
	)
	(segment
		(start 39.80815 -41.289224)
		(end 42.079926 -43.561)
		(width 0.0889)
		(layer "In2.Cu")
		(net "XDP_SOC_CPU_TDI")
	)
	(segment
		(start 43.86199 -44.000928)
		(end 43.86199 -44.321984)
		(width 0.0889)
		(layer "In2.Cu")
		(net "XDP_SOC_CPU_TDI")
	)
	(segment
		(start 42.079926 -43.561)
		(end 43.422062 -43.561)
		(width 0.0889)
		(layer "In2.Cu")
		(net "XDP_SOC_CPU_TDI")
	)
	(segment
		(start 35.741864 -35.686746)
		(end 35.742118 -35.687)
		(width 0.0889)
		(layer "In2.Cu")
		(net "XDP_SOC_CPU_TDI")
	)
	(segment
		(start 33.900364 -36.449)
		(end 34.590482 -36.449)
		(width 0.0889)
		(layer "In2.Cu")
		(net "XDP_SOC_CPU_TDI")
	)
	(segment
		(start 33.467548 -36.016184)
		(end 33.900364 -36.449)
		(width 0.0889)
		(layer "In2.Cu")
		(net "XDP_SOC_CPU_TDI")
	)
	(segment
		(start 61.24575 -59.071764)
		(end 61.24575 -62.065154)
		(width 0.0889)
		(layer "In2.Cu")
		(net "XDP_SOC_CPU_TDI")
	)
	(segment
		(start 49.517046 -49.4284)
		(end 50.979832 -49.4284)
		(width 0.0889)
		(layer "In2.Cu")
		(net "XDP_SOC_CPU_TDI")
	)
	(segment
		(start 66.50355 -62.38875)
		(end 67.437 -63.3222)
		(width 0.0889)
		(layer "In2.Cu")
		(net "XDP_SOC_CPU_TDI")
	)
	(segment
		(start 39.80815 -39.51605)
		(end 39.80815 -41.289224)
		(width 0.0889)
		(layer "In2.Cu")
		(net "XDP_SOC_CPU_TDI")
	)
	(segment
		(start 34.590482 -36.449)
		(end 35.352736 -35.686746)
		(width 0.0889)
		(layer "In2.Cu")
		(net "XDP_SOC_CPU_TDI")
	)
	(segment
		(start 53.494686 -51.943254)
		(end 53.494686 -52.060856)
		(width 0.0889)
		(layer "In2.Cu")
		(net "XDP_SOC_CPU_TDI")
	)
	(segment
		(start 40.45585 -38.86835)
		(end 39.80815 -39.51605)
		(width 0.0889)
		(layer "In2.Cu")
		(net "XDP_SOC_CPU_TDI")
	)
	(segment
		(start 43.422062 -43.561)
		(end 43.86199 -44.000928)
		(width 0.0889)
		(layer "In2.Cu")
		(net "XDP_SOC_CPU_TDI")
	)
	(segment
		(start 45.897546 -45.8089)
		(end 49.517046 -49.4284)
		(width 0.0889)
		(layer "In2.Cu")
		(net "XDP_SOC_CPU_TDI")
	)
	(segment
		(start 61.24575 -62.065154)
		(end 61.569346 -62.38875)
		(width 0.0889)
		(layer "In2.Cu")
		(net "XDP_SOC_CPU_TDI")
	)
	(segment
		(start 38.502844 -35.687)
		(end 40.45585 -37.640006)
		(width 0.0889)
		(layer "In2.Cu")
		(net "XDP_SOC_CPU_TDI")
	)
	(segment
		(start 61.569346 -62.38875)
		(end 66.50355 -62.38875)
		(width 0.0889)
		(layer "In2.Cu")
		(net "XDP_SOC_CPU_TDI")
	)
	(segment
		(start 45.348906 -45.8089)
		(end 45.897546 -45.8089)
		(width 0.0889)
		(layer "In2.Cu")
		(net "XDP_SOC_CPU_TDI")
	)
	(segment
		(start 54.76113 -53.3273)
		(end 55.501286 -53.3273)
		(width 0.0889)
		(layer "In2.Cu")
		(net "XDP_SOC_CPU_TDI")
	)
	(segment
		(start 193.062098 -68.810124)
		(end 193.062098 -61.096144)
		(width 0.0889)
		(layer "In4.Cu")
		(net "XDP_SOC_CPU_TDI")
	)
	(segment
		(start 193.062098 -61.096144)
		(end 188.4934 -56.527446)
		(width 0.0889)
		(layer "In4.Cu")
		(net "XDP_SOC_CPU_TDI")
	)
	(segment
		(start 91.332558 -71.253604)
		(end 190.618618 -71.253604)
		(width 0.0889)
		(layer "In4.Cu")
		(net "XDP_SOC_CPU_TDI")
	)
	(segment
		(start 67.437 -64.550544)
		(end 68.774056 -65.8876)
		(width 0.0889)
		(layer "In4.Cu")
		(net "XDP_SOC_CPU_TDI")
	)
	(segment
		(start 48.62195 -27.37485)
		(end 53.594 -27.37485)
		(width 0.0889)
		(layer "In4.Cu")
		(net "XDP_SOC_CPU_TDI")
	)
	(segment
		(start 188.7982 -53.594)
		(end 188.722 -53.594)
		(width 0.0889)
		(layer "In4.Cu")
		(net "XDP_SOC_CPU_TDI")
	)
	(segment
		(start 68.774056 -65.8876)
		(end 85.966554 -65.8876)
		(width 0.0889)
		(layer "In4.Cu")
		(net "XDP_SOC_CPU_TDI")
	)
	(segment
		(start 34.132774 -35.350958)
		(end 34.132774 -34.871406)
		(width 0.0889)
		(layer "In4.Cu")
		(net "XDP_SOC_CPU_TDI")
	)
	(segment
		(start 34.132774 -34.871406)
		(end 34.39668 -34.6075)
		(width 0.0889)
		(layer "In4.Cu")
		(net "XDP_SOC_CPU_TDI")
	)
	(segment
		(start 67.437 -63.3222)
		(end 67.437 -64.550544)
		(width 0.0889)
		(layer "In4.Cu")
		(net "XDP_SOC_CPU_TDI")
	)
	(segment
		(start 34.39668 -34.6075)
		(end 41.823894 -34.6075)
		(width 0.0889)
		(layer "In4.Cu")
		(net "XDP_SOC_CPU_TDI")
	)
	(segment
		(start 190.618618 -71.253604)
		(end 193.062098 -68.810124)
		(width 0.0889)
		(layer "In4.Cu")
		(net "XDP_SOC_CPU_TDI")
	)
	(segment
		(start 188.4934 -56.527446)
		(end 188.4934 -56.121554)
		(width 0.0889)
		(layer "In4.Cu")
		(net "XDP_SOC_CPU_TDI")
	)
	(segment
		(start 41.823894 -34.6075)
		(end 44.08805 -32.343344)
		(width 0.0889)
		(layer "In4.Cu")
		(net "XDP_SOC_CPU_TDI")
	)
	(segment
		(start 33.467548 -36.016184)
		(end 34.132774 -35.350958)
		(width 0.0889)
		(layer "In4.Cu")
		(net "XDP_SOC_CPU_TDI")
	)
	(segment
		(start 44.08805 -32.343344)
		(end 44.08805 -31.90875)
		(width 0.0889)
		(layer "In4.Cu")
		(net "XDP_SOC_CPU_TDI")
	)
	(segment
		(start 189.3824 -54.1782)
		(end 188.7982 -53.594)
		(width 0.0889)
		(layer "In4.Cu")
		(net "XDP_SOC_CPU_TDI")
	)
	(segment
		(start 53.594 -27.37485)
		(end 54.40045 -26.5684)
		(width 0.0889)
		(layer "In4.Cu")
		(net "XDP_SOC_CPU_TDI")
	)
	(segment
		(start 85.966554 -65.8876)
		(end 91.332558 -71.253604)
		(width 0.0889)
		(layer "In4.Cu")
		(net "XDP_SOC_CPU_TDI")
	)
	(segment
		(start 189.3824 -55.232554)
		(end 189.3824 -54.1782)
		(width 0.0889)
		(layer "In4.Cu")
		(net "XDP_SOC_CPU_TDI")
	)
	(segment
		(start 54.40045 -26.5684)
		(end 57.885076 -26.5684)
		(width 0.0889)
		(layer "In4.Cu")
		(net "XDP_SOC_CPU_TDI")
	)
	(segment
		(start 188.4934 -56.121554)
		(end 189.3824 -55.232554)
		(width 0.0889)
		(layer "In4.Cu")
		(net "XDP_SOC_CPU_TDI")
	)
	(segment
		(start 44.08805 -31.90875)
		(end 48.62195 -27.37485)
		(width 0.0889)
		(layer "In4.Cu")
		(net "XDP_SOC_CPU_TDI")
	)
	(segment
		(start 67.371722 -29.4767)
		(end 65.142872 -27.24785)
		(width 0.0889)
		(layer "In7.Cu")
		(net "XDP_SOC_CPU_TDI")
	)
	(segment
		(start 75.729846 -30.704282)
		(end 75.729846 -30.592268)
		(width 0.0889)
		(layer "In7.Cu")
		(net "XDP_SOC_CPU_TDI")
	)
	(segment
		(start 79.8703 -35.4457)
		(end 78.469236 -35.4457)
		(width 0.0889)
		(layer "In7.Cu")
		(net "XDP_SOC_CPU_TDI")
	)
	(segment
		(start 80.880966 -36.456366)
		(end 79.8703 -35.4457)
		(width 0.0889)
		(layer "In7.Cu")
		(net "XDP_SOC_CPU_TDI")
	)
	(segment
		(start 61.840872 -27.24785)
		(end 60.570872 -25.97785)
		(width 0.0889)
		(layer "In7.Cu")
		(net "XDP_SOC_CPU_TDI")
	)
	(segment
		(start 69.483478 -29.4767)
		(end 67.371722 -29.4767)
		(width 0.0889)
		(layer "In7.Cu")
		(net "XDP_SOC_CPU_TDI")
	)
	(segment
		(start 76.891896 -31.866332)
		(end 75.729846 -30.704282)
		(width 0.0889)
		(layer "In7.Cu")
		(net "XDP_SOC_CPU_TDI")
	)
	(segment
		(start 69.862446 -29.476954)
		(end 69.483732 -29.476954)
		(width 0.0889)
		(layer "In7.Cu")
		(net "XDP_SOC_CPU_TDI")
	)
	(segment
		(start 70.51675 -28.82265)
		(end 69.862446 -29.476954)
		(width 0.0889)
		(layer "In7.Cu")
		(net "XDP_SOC_CPU_TDI")
	)
	(segment
		(start 76.891896 -33.86836)
		(end 76.891896 -31.866332)
		(width 0.0889)
		(layer "In7.Cu")
		(net "XDP_SOC_CPU_TDI")
	)
	(segment
		(start 65.142872 -27.24785)
		(end 61.840872 -27.24785)
		(width 0.0889)
		(layer "In7.Cu")
		(net "XDP_SOC_CPU_TDI")
	)
	(segment
		(start 83.861402 -36.070032)
		(end 83.475068 -36.456366)
		(width 0.0889)
		(layer "In7.Cu")
		(net "XDP_SOC_CPU_TDI")
	)
	(segment
		(start 73.960228 -28.82265)
		(end 70.51675 -28.82265)
		(width 0.0889)
		(layer "In7.Cu")
		(net "XDP_SOC_CPU_TDI")
	)
	(segment
		(start 58.475626 -25.97785)
		(end 57.885076 -26.5684)
		(width 0.0889)
		(layer "In7.Cu")
		(net "XDP_SOC_CPU_TDI")
	)
	(segment
		(start 83.475068 -36.456366)
		(end 80.880966 -36.456366)
		(width 0.0889)
		(layer "In7.Cu")
		(net "XDP_SOC_CPU_TDI")
	)
	(segment
		(start 75.729846 -30.592268)
		(end 73.960228 -28.82265)
		(width 0.0889)
		(layer "In7.Cu")
		(net "XDP_SOC_CPU_TDI")
	)
	(segment
		(start 69.483732 -29.476954)
		(end 69.483478 -29.4767)
		(width 0.0889)
		(layer "In7.Cu")
		(net "XDP_SOC_CPU_TDI")
	)
	(segment
		(start 60.570872 -25.97785)
		(end 58.475626 -25.97785)
		(width 0.0889)
		(layer "In7.Cu")
		(net "XDP_SOC_CPU_TDI")
	)
	(segment
		(start 78.469236 -35.4457)
		(end 76.891896 -33.86836)
		(width 0.0889)
		(layer "In7.Cu")
		(net "XDP_SOC_CPU_TDI")
	)
	(segment
		(start 176.419002 -53.84165)
		(end 186.59475 -53.84165)
		(width 0.0889)
		(layer "In9.Cu")
		(net "XDP_SOC_CPU_TDI")
	)
	(segment
		(start 186.8424 -53.594)
		(end 188.722 -53.594)
		(width 0.0889)
		(layer "In9.Cu")
		(net "XDP_SOC_CPU_TDI")
	)
	(segment
		(start 186.59475 -53.84165)
		(end 186.8424 -53.594)
		(width 0.0889)
		(layer "In9.Cu")
		(net "XDP_SOC_CPU_TDI")
	)
	(segment
		(start 170.953176 -48.375824)
		(end 176.419002 -53.84165)
		(width 0.0889)
		(layer "In9.Cu")
		(net "XDP_SOC_CPU_TDI")
	)
	(via
		(at 8.6614 -37.4142)
		(size 0.7112)
		(drill 0.3556)
		(layers "F.Cu" "B.Cu")
		(net "P3V3_STBY_VIN")
	)
	(via
		(at 8.636 -41.021)
		(size 0.7112)
		(drill 0.4064)
		(layers "F.Cu" "B.Cu")
		(net "P3V3_STBY_VIN")
	)
	(via
		(at 7.6708 -36.83)
		(size 0.7112)
		(drill 0.4064)
		(layers "F.Cu" "B.Cu")
		(net "P3V3_STBY_VIN")
	)
	(via
		(at 7.6708 -38.9636)
		(size 0.7112)
		(drill 0.4064)
		(layers "F.Cu" "B.Cu")
		(net "P3V3_STBY_VIN")
	)
	(via
		(at 7.6962 -40.0304)
		(size 0.7112)
		(drill 0.4064)
		(layers "F.Cu" "B.Cu")
		(net "P3V3_STBY_VIN")
	)
	(via
		(at 7.6708 -37.8968)
		(size 0.7112)
		(drill 0.4064)
		(layers "F.Cu" "B.Cu")
		(net "P3V3_STBY_VIN")
	)
	(segment
		(start 197.612 -34.1122)
		(end 197.612 -35.052)
		(width 0.508)
		(layer "F.Cu")
		(net "VR_PVDDR_A_GH1_R")
	)
	(segment
		(start 197.9422 -33.782)
		(end 197.612 -34.1122)
		(width 0.508)
		(layer "F.Cu")
		(net "VR_PVDDR_A_GH1_R")
	)
	(segment
		(start 198.0438 -33.02)
		(end 197.9422 -33.1216)
		(width 0.508)
		(layer "F.Cu")
		(net "VR_PVDDR_A_GH1_R")
	)
	(segment
		(start 198.056754 -33.667446)
		(end 197.9422 -33.782)
		(width 0.508)
		(layer "F.Cu")
		(net "VR_PVDDR_A_GH1_R")
	)
	(segment
		(start 198.0438 -32.6644)
		(end 198.0438 -33.02)
		(width 0.508)
		(layer "F.Cu")
		(net "VR_PVDDR_A_GH1_R")
	)
	(segment
		(start 197.9422 -33.1216)
		(end 197.9422 -33.782)
		(width 0.508)
		(layer "F.Cu")
		(net "VR_PVDDR_A_GH1_R")
	)
	(segment
		(start 199.39381 -33.667446)
		(end 198.056754 -33.667446)
		(width 0.508)
		(layer "F.Cu")
		(net "VR_PVDDR_A_GH1_R")
	)
	(via
		(at 197.612 -35.052)
		(size 0.7112)
		(drill 0.3556)
		(layers "F.Cu" "B.Cu")
		(net "VR_PVDDR_A_GH1_R")
	)
	(segment
		(start 169.15003 -3.089148)
		(end 169.138854 -3.100324)
		(width 0.1778)
		(layer "F.Cu")
		(net "M_B_CS_N3")
	)
	(segment
		(start 169.138854 -3.100324)
		(end 169.138854 -3.125978)
		(width 0.1778)
		(layer "F.Cu")
		(net "M_B_CS_N3")
	)
	(segment
		(start 111.192056 -29.5656)
		(end 110.460282 -30.297374)
		(width 0.1778)
		(layer "F.Cu")
		(net "M_B_CS_N3")
	)
	(segment
		(start 111.379 -29.5656)
		(end 111.192056 -29.5656)
		(width 0.1778)
		(layer "F.Cu")
		(net "M_B_CS_N3")
	)
	(segment
		(start 110.460282 -30.297374)
		(end 110.391448 -30.297374)
		(width 0.1778)
		(layer "F.Cu")
		(net "M_B_CS_N3")
	)
	(segment
		(start 169.15003 -1.68402)
		(end 169.15003 -3.089148)
		(width 0.1778)
		(layer "F.Cu")
		(net "M_B_CS_N3")
	)
	(via
		(at 169.138854 -3.125978)
		(size 0.4318)
		(drill 0.2032)
		(layers "F.Cu" "B.Cu")
		(net "M_B_CS_N3")
	)
	(via
		(at 111.379 -29.5656)
		(size 0.4318)
		(drill 0.2032)
		(layers "F.Cu" "B.Cu")
		(net "M_B_CS_N3")
	)
	(segment
		(start 168.732454 -2.719578)
		(end 167.818816 -2.719578)
		(width 0.1524)
		(layer "In9.Cu")
		(net "M_B_CS_N3")
	)
	(segment
		(start 156.7942 -21.495004)
		(end 156.211778 -22.077426)
		(width 0.1524)
		(layer "In9.Cu")
		(net "M_B_CS_N3")
	)
	(segment
		(start 166.751254 -4.612132)
		(end 167.0431 -4.903978)
		(width 0.1524)
		(layer "In9.Cu")
		(net "M_B_CS_N3")
	)
	(segment
		(start 114.630454 -25.501346)
		(end 113.906554 -26.225246)
		(width 0.1524)
		(layer "In9.Cu")
		(net "M_B_CS_N3")
	)
	(segment
		(start 167.818562 -10.898886)
		(end 168.808654 -11.888978)
		(width 0.1524)
		(layer "In9.Cu")
		(net "M_B_CS_N3")
	)
	(segment
		(start 156.211778 -22.077426)
		(end 156.211778 -23.100538)
		(width 0.1524)
		(layer "In9.Cu")
		(net "M_B_CS_N3")
	)
	(segment
		(start 167.818816 -2.719578)
		(end 167.563038 -2.975356)
		(width 0.1524)
		(layer "In9.Cu")
		(net "M_B_CS_N3")
	)
	(segment
		(start 167.6146 -7.931404)
		(end 167.818562 -8.135366)
		(width 0.1524)
		(layer "In9.Cu")
		(net "M_B_CS_N3")
	)
	(segment
		(start 113.906554 -27.115008)
		(end 111.455962 -29.5656)
		(width 0.1524)
		(layer "In9.Cu")
		(net "M_B_CS_N3")
	)
	(segment
		(start 167.6146 -7.559294)
		(end 167.6146 -7.931404)
		(width 0.1524)
		(layer "In9.Cu")
		(net "M_B_CS_N3")
	)
	(segment
		(start 164.713412 -17.72285)
		(end 160.566354 -17.72285)
		(width 0.1524)
		(layer "In9.Cu")
		(net "M_B_CS_N3")
	)
	(segment
		(start 156.7942 -20.828)
		(end 156.7942 -21.495004)
		(width 0.1524)
		(layer "In9.Cu")
		(net "M_B_CS_N3")
	)
	(segment
		(start 111.455962 -29.5656)
		(end 111.379 -29.5656)
		(width 0.1524)
		(layer "In9.Cu")
		(net "M_B_CS_N3")
	)
	(segment
		(start 113.906554 -26.225246)
		(end 113.906554 -27.115008)
		(width 0.1524)
		(layer "In9.Cu")
		(net "M_B_CS_N3")
	)
	(segment
		(start 157.708854 -20.58035)
		(end 157.04185 -20.58035)
		(width 0.1524)
		(layer "In9.Cu")
		(net "M_B_CS_N3")
	)
	(segment
		(start 156.211778 -23.100538)
		(end 153.81097 -25.501346)
		(width 0.1524)
		(layer "In9.Cu")
		(net "M_B_CS_N3")
	)
	(segment
		(start 157.04185 -20.58035)
		(end 156.7942 -20.828)
		(width 0.1524)
		(layer "In9.Cu")
		(net "M_B_CS_N3")
	)
	(segment
		(start 167.818562 -8.135366)
		(end 167.818562 -10.898886)
		(width 0.1524)
		(layer "In9.Cu")
		(net "M_B_CS_N3")
	)
	(segment
		(start 160.566354 -17.72285)
		(end 157.708854 -20.58035)
		(width 0.1524)
		(layer "In9.Cu")
		(net "M_B_CS_N3")
	)
	(segment
		(start 168.808654 -11.888978)
		(end 168.808654 -13.627608)
		(width 0.1524)
		(layer "In9.Cu")
		(net "M_B_CS_N3")
	)
	(segment
		(start 167.0431 -6.987794)
		(end 167.6146 -7.559294)
		(width 0.1524)
		(layer "In9.Cu")
		(net "M_B_CS_N3")
	)
	(segment
		(start 166.751254 -3.785362)
		(end 166.751254 -4.612132)
		(width 0.1524)
		(layer "In9.Cu")
		(net "M_B_CS_N3")
	)
	(segment
		(start 167.563038 -2.975356)
		(end 167.563038 -3.3655)
		(width 0.1524)
		(layer "In9.Cu")
		(net "M_B_CS_N3")
	)
	(segment
		(start 167.563038 -3.3655)
		(end 167.295322 -3.633216)
		(width 0.1524)
		(layer "In9.Cu")
		(net "M_B_CS_N3")
	)
	(segment
		(start 168.808654 -13.627608)
		(end 164.713412 -17.72285)
		(width 0.1524)
		(layer "In9.Cu")
		(net "M_B_CS_N3")
	)
	(segment
		(start 153.81097 -25.501346)
		(end 114.630454 -25.501346)
		(width 0.1524)
		(layer "In9.Cu")
		(net "M_B_CS_N3")
	)
	(segment
		(start 167.0431 -4.903978)
		(end 167.0431 -6.987794)
		(width 0.1524)
		(layer "In9.Cu")
		(net "M_B_CS_N3")
	)
	(segment
		(start 167.295322 -3.633216)
		(end 166.9034 -3.633216)
		(width 0.1524)
		(layer "In9.Cu")
		(net "M_B_CS_N3")
	)
	(segment
		(start 169.138854 -3.125978)
		(end 168.732454 -2.719578)
		(width 0.1524)
		(layer "In9.Cu")
		(net "M_B_CS_N3")
	)
	(segment
		(start 166.9034 -3.633216)
		(end 166.751254 -3.785362)
		(width 0.1524)
		(layer "In9.Cu")
		(net "M_B_CS_N3")
	)
	(segment
		(start 99.591368 -33.426654)
		(end 99.591368 -33.520634)
		(width 0.1524)
		(layer "F.Cu")
		(net "M_B_DQPU")
	)
	(segment
		(start 99.591368 -33.520634)
		(end 99.11207 -33.999932)
		(width 0.1524)
		(layer "F.Cu")
		(net "M_B_DQPU")
	)
	(via
		(at 99.11207 -33.999932)
		(size 0.4318)
		(drill 0.2032)
		(layers "F.Cu" "B.Cu")
		(net "M_B_DQPU")
	)
	(via
		(at 97.8662 -23.9522)
		(size 0.7112)
		(drill 0.3556)
		(layers "F.Cu" "B.Cu")
		(net "M_B_DQPU")
	)
	(segment
		(start 98.379534 -28.905962)
		(end 98.288602 -28.81503)
		(width 0.1778)
		(layer "B.Cu")
		(net "M_B_DQPU")
	)
	(segment
		(start 98.7552 -20.574)
		(end 98.171 -20.574)
		(width 0.1778)
		(layer "B.Cu")
		(net "M_B_DQPU")
	)
	(segment
		(start 98.171 -20.574)
		(end 97.8662 -20.8788)
		(width 0.1778)
		(layer "B.Cu")
		(net "M_B_DQPU")
	)
	(segment
		(start 98.352356 -32.11957)
		(end 98.352356 -30.555692)
		(width 0.1778)
		(layer "B.Cu")
		(net "M_B_DQPU")
	)
	(segment
		(start 98.288602 -28.81503)
		(end 98.288602 -28.315158)
		(width 0.1778)
		(layer "B.Cu")
		(net "M_B_DQPU")
	)
	(segment
		(start 97.7519 -27.778456)
		(end 97.7519 -24.0665)
		(width 0.1778)
		(layer "B.Cu")
		(net "M_B_DQPU")
	)
	(segment
		(start 98.4504 -33.3756)
		(end 98.4504 -32.217614)
		(width 0.1778)
		(layer "B.Cu")
		(net "M_B_DQPU")
	)
	(segment
		(start 98.288602 -28.315158)
		(end 97.7519 -27.778456)
		(width 0.1778)
		(layer "B.Cu")
		(net "M_B_DQPU")
	)
	(segment
		(start 97.7519 -24.0665)
		(end 97.8662 -23.9522)
		(width 0.1778)
		(layer "B.Cu")
		(net "M_B_DQPU")
	)
	(segment
		(start 99.11207 -33.999932)
		(end 99.074732 -33.999932)
		(width 0.1778)
		(layer "B.Cu")
		(net "M_B_DQPU")
	)
	(segment
		(start 98.352356 -30.555692)
		(end 98.379534 -30.528514)
		(width 0.1778)
		(layer "B.Cu")
		(net "M_B_DQPU")
	)
	(segment
		(start 99.074732 -33.999932)
		(end 98.4504 -33.3756)
		(width 0.1778)
		(layer "B.Cu")
		(net "M_B_DQPU")
	)
	(segment
		(start 98.379534 -30.528514)
		(end 98.379534 -28.905962)
		(width 0.1778)
		(layer "B.Cu")
		(net "M_B_DQPU")
	)
	(segment
		(start 97.8662 -20.8788)
		(end 97.8662 -23.9522)
		(width 0.1778)
		(layer "B.Cu")
		(net "M_B_DQPU")
	)
	(segment
		(start 98.4504 -32.217614)
		(end 98.352356 -32.11957)
		(width 0.1778)
		(layer "B.Cu")
		(net "M_B_DQPU")
	)
	(segment
		(start 12.954 -32.805878)
		(end 12.954 -32.3088)
		(width 0.254)
		(layer "F.Cu")
		(net "P3V3_STBY_VFB")
	)
	(segment
		(start 19.304 -32.6898)
		(end 19.939 -32.6898)
		(width 0.254)
		(layer "F.Cu")
		(net "P3V3_STBY_VFB")
	)
	(segment
		(start 19.939 -32.6898)
		(end 20.066 -32.8168)
		(width 0.254)
		(layer "F.Cu")
		(net "P3V3_STBY_VFB")
	)
	(segment
		(start 18.542 -32.6898)
		(end 17.378426 -32.6898)
		(width 0.254)
		(layer "F.Cu")
		(net "P3V3_STBY_VFB")
	)
	(segment
		(start 13.371322 -33.948878)
		(end 13.371322 -33.2232)
		(width 0.254)
		(layer "F.Cu")
		(net "P3V3_STBY_VFB")
	)
	(segment
		(start 13.371322 -33.2232)
		(end 12.954 -32.805878)
		(width 0.254)
		(layer "F.Cu")
		(net "P3V3_STBY_VFB")
	)
	(segment
		(start 18.542 -32.6898)
		(end 19.304 -32.6898)
		(width 0.254)
		(layer "F.Cu")
		(net "P3V3_STBY_VFB")
	)
	(segment
		(start 17.200626 -32.512)
		(end 16.891 -32.512)
		(width 0.254)
		(layer "F.Cu")
		(net "P3V3_STBY_VFB")
	)
	(segment
		(start 12.954 -32.3088)
		(end 13.6906 -32.3088)
		(width 0.254)
		(layer "F.Cu")
		(net "P3V3_STBY_VFB")
	)
	(segment
		(start 17.378426 -32.6898)
		(end 17.200626 -32.512)
		(width 0.254)
		(layer "F.Cu")
		(net "P3V3_STBY_VFB")
	)
	(segment
		(start 13.6906 -32.3088)
		(end 13.716 -32.3342)
		(width 0.254)
		(layer "F.Cu")
		(net "P3V3_STBY_VFB")
	)
	(via
		(at 13.371322 -33.2232)
		(size 0.508)
		(drill 0.254)
		(layers "F.Cu" "B.Cu")
		(net "P3V3_STBY_VFB")
	)
	(via
		(at 16.891 -32.512)
		(size 0.508)
		(drill 0.254)
		(layers "F.Cu" "B.Cu")
		(net "P3V3_STBY_VFB")
	)
	(via
		(at 17.78 -32.385)
		(size 0.7112)
		(drill 0.3556)
		(layers "F.Cu" "B.Cu")
		(net "P3V3_STBY_VFB")
	)
	(segment
		(start 17.653 -32.512)
		(end 16.891 -32.512)
		(width 0.254)
		(layer "B.Cu")
		(net "P3V3_STBY_VFB")
	)
	(segment
		(start 17.78 -32.385)
		(end 17.653 -32.512)
		(width 0.254)
		(layer "B.Cu")
		(net "P3V3_STBY_VFB")
	)
	(segment
		(start 16.891 -32.512)
		(end 16.764 -32.385)
		(width 0.254)
		(layer "In4.Cu")
		(net "P3V3_STBY_VFB")
	)
	(segment
		(start 16.764 -32.385)
		(end 14.209522 -32.385)
		(width 0.254)
		(layer "In4.Cu")
		(net "P3V3_STBY_VFB")
	)
	(segment
		(start 14.209522 -32.385)
		(end 13.371322 -33.2232)
		(width 0.254)
		(layer "In4.Cu")
		(net "P3V3_STBY_VFB")
	)
	(segment
		(start 199.39381 -40.17899)
		(end 199.0344 -40.5384)
		(width 0.508)
		(layer "F.Cu")
		(net "VR_PVDDR_A_GL1_BG")
	)
	(segment
		(start 197.485 -37.7698)
		(end 197.993 -37.7698)
		(width 0.508)
		(layer "F.Cu")
		(net "VR_PVDDR_A_GL1_BG")
	)
	(segment
		(start 197.993 -37.7698)
		(end 197.8914 -37.8714)
		(width 0.4572)
		(layer "F.Cu")
		(net "VR_PVDDR_A_GL1_BG")
	)
	(segment
		(start 197.8914 -37.8714)
		(end 197.8914 -39.243)
		(width 0.4572)
		(layer "F.Cu")
		(net "VR_PVDDR_A_GL1_BG")
	)
	(segment
		(start 197.01891 -37.30371)
		(end 197.485 -37.7698)
		(width 0.508)
		(layer "F.Cu")
		(net "VR_PVDDR_A_GL1_BG")
	)
	(segment
		(start 198.2724 -40.5384)
		(end 197.8914 -40.1574)
		(width 0.508)
		(layer "F.Cu")
		(net "VR_PVDDR_A_GL1_BG")
	)
	(segment
		(start 199.0344 -40.5384)
		(end 198.2724 -40.5384)
		(width 0.508)
		(layer "F.Cu")
		(net "VR_PVDDR_A_GL1_BG")
	)
	(segment
		(start 197.8914 -40.1574)
		(end 197.8914 -39.243)
		(width 0.508)
		(layer "F.Cu")
		(net "VR_PVDDR_A_GL1_BG")
	)
	(segment
		(start 199.39381 -38.638734)
		(end 199.39381 -40.17899)
		(width 0.508)
		(layer "F.Cu")
		(net "VR_PVDDR_A_GL1_BG")
	)
	(via
		(at 197.01891 -37.30371)
		(size 0.7112)
		(drill 0.3556)
		(layers "F.Cu" "B.Cu")
		(net "VR_PVDDR_A_GL1_BG")
	)
	(segment
		(start 111.9378 -20.193)
		(end 111.9378 -19.4056)
		(width 0.1143)
		(layer "F.Cu")
		(net "M_B_MON1_P")
	)
	(segment
		(start 110.710218 -26.63952)
		(end 111.541306 -25.808432)
		(width 0.1143)
		(layer "F.Cu")
		(net "M_B_MON1_P")
	)
	(segment
		(start 111.846614 -25.502616)
		(end 111.9378 -25.41143)
		(width 0.1143)
		(layer "F.Cu")
		(net "M_B_MON1_P")
	)
	(segment
		(start 111.9378 -19.4056)
		(end 112.1664 -19.177)
		(width 0.1143)
		(layer "F.Cu")
		(net "M_B_MON1_P")
	)
	(segment
		(start 111.9378 -25.41143)
		(end 111.9378 -22.098)
		(width 0.1143)
		(layer "F.Cu")
		(net "M_B_MON1_P")
	)
	(segment
		(start 111.9378 -22.098)
		(end 111.9378 -20.193)
		(width 0.1143)
		(layer "F.Cu")
		(net "M_B_MON1_P")
	)
	(segment
		(start 111.541306 -25.808432)
		(end 111.846614 -25.502616)
		(width 0.1143)
		(layer "F.Cu")
		(net "M_B_MON1_P")
	)
	(segment
		(start 110.335568 -27.714194)
		(end 110.710218 -27.339544)
		(width 0.1143)
		(layer "F.Cu")
		(net "M_B_MON1_P")
	)
	(segment
		(start 110.710218 -27.339544)
		(end 110.710218 -26.63952)
		(width 0.1143)
		(layer "F.Cu")
		(net "M_B_MON1_P")
	)
	(via
		(at 111.9378 -22.098)
		(size 0.7112)
		(drill 0.3556)
		(layers "F.Cu" "B.Cu")
		(net "M_B_MON1_P")
	)
	(segment
		(start 96.901 -31.2928)
		(end 96.748854 -31.140654)
		(width 0.1016)
		(layer "F.Cu")
		(net "M_B_DQ27")
	)
	(segment
		(start 96.748854 -31.140654)
		(end 96.319848 -31.140654)
		(width 0.1016)
		(layer "F.Cu")
		(net "M_B_DQ27")
	)
	(segment
		(start 148.450046 -9.897364)
		(end 148.450046 -8.889746)
		(width 0.1778)
		(layer "F.Cu")
		(net "M_B_DQ27")
	)
	(segment
		(start 148.254212 -8.109966)
		(end 148.52396 -7.840218)
		(width 0.1778)
		(layer "F.Cu")
		(net "M_B_DQ27")
	)
	(segment
		(start 148.450046 -8.889746)
		(end 148.254212 -8.693912)
		(width 0.1778)
		(layer "F.Cu")
		(net "M_B_DQ27")
	)
	(segment
		(start 148.52396 -7.840218)
		(end 148.635466 -7.840218)
		(width 0.1778)
		(layer "F.Cu")
		(net "M_B_DQ27")
	)
	(segment
		(start 148.254212 -8.693912)
		(end 148.254212 -8.109966)
		(width 0.1778)
		(layer "F.Cu")
		(net "M_B_DQ27")
	)
	(via
		(at 96.901 -31.2928)
		(size 0.4318)
		(drill 0.2032)
		(layers "F.Cu" "B.Cu")
		(net "M_B_DQ27")
	)
	(via
		(at 148.635466 -7.840218)
		(size 0.4318)
		(drill 0.2032)
		(layers "F.Cu" "B.Cu")
		(net "M_B_DQ27")
	)
	(segment
		(start 148.2852 -8.421878)
		(end 148.2852 -8.190484)
		(width 0.1778)
		(layer "B.Cu")
		(net "M_B_DQ27")
	)
	(segment
		(start 148.2852 -8.190484)
		(end 148.635466 -7.840218)
		(width 0.1778)
		(layer "B.Cu")
		(net "M_B_DQ27")
	)
	(segment
		(start 147.54987 -9.157208)
		(end 148.2852 -8.421878)
		(width 0.1778)
		(layer "B.Cu")
		(net "M_B_DQ27")
	)
	(segment
		(start 147.54987 -9.89076)
		(end 147.54987 -9.157208)
		(width 0.1778)
		(layer "B.Cu")
		(net "M_B_DQ27")
	)
	(segment
		(start 106.930444 -27.2415)
		(end 105.520744 -28.6512)
		(width 0.1524)
		(layer "In4.Cu")
		(net "M_B_DQ27")
	)
	(segment
		(start 147.12188 -23.932134)
		(end 147.076414 -23.9776)
		(width 0.1524)
		(layer "In4.Cu")
		(net "M_B_DQ27")
	)
	(segment
		(start 108.869988 -26.162)
		(end 108.4326 -26.162)
		(width 0.1524)
		(layer "In4.Cu")
		(net "M_B_DQ27")
	)
	(segment
		(start 100.5586 -31.337504)
		(end 101.14026 -30.755844)
		(width 0.1016)
		(layer "In4.Cu")
		(net "M_B_DQ27")
	)
	(segment
		(start 103.378 -29.501338)
		(end 103.224584 -30.042866)
		(width 0.1524)
		(layer "In4.Cu")
		(net "M_B_DQ27")
	)
	(segment
		(start 103.5685 -28.8417)
		(end 103.378 -29.0322)
		(width 0.1524)
		(layer "In4.Cu")
		(net "M_B_DQ27")
	)
	(segment
		(start 101.14026 -30.755844)
		(end 102.083108 -30.755844)
		(width 0.1016)
		(layer "In4.Cu")
		(net "M_B_DQ27")
	)
	(segment
		(start 98.702622 -32.176466)
		(end 98.8822 -32.0294)
		(width 0.1016)
		(layer "In4.Cu")
		(net "M_B_DQ27")
	)
	(segment
		(start 102.235 -30.755844)
		(end 102.083108 -30.755844)
		(width 0.1524)
		(layer "In4.Cu")
		(net "M_B_DQ27")
	)
	(segment
		(start 114.046 -25.019)
		(end 110.012988 -25.019)
		(width 0.1524)
		(layer "In4.Cu")
		(net "M_B_DQ27")
	)
	(segment
		(start 96.6089 -32.499046)
		(end 96.6978 -32.587946)
		(width 0.1016)
		(layer "In4.Cu")
		(net "M_B_DQ27")
	)
	(segment
		(start 147.076414 -23.9776)
		(end 115.0874 -23.9776)
		(width 0.1524)
		(layer "In4.Cu")
		(net "M_B_DQ27")
	)
	(segment
		(start 148.55444 -22.499574)
		(end 148.188934 -22.865334)
		(width 0.1524)
		(layer "In4.Cu")
		(net "M_B_DQ27")
	)
	(segment
		(start 108.4326 -26.162)
		(end 107.3531 -27.2415)
		(width 0.1524)
		(layer "In4.Cu")
		(net "M_B_DQ27")
	)
	(segment
		(start 100.1522 -31.877)
		(end 100.5586 -31.4706)
		(width 0.1016)
		(layer "In4.Cu")
		(net "M_B_DQ27")
	)
	(segment
		(start 102.87 -30.5562)
		(end 102.235 -30.755844)
		(width 0.1524)
		(layer "In4.Cu")
		(net "M_B_DQ27")
	)
	(segment
		(start 98.358706 -32.805878)
		(end 98.702622 -32.176466)
		(width 0.1016)
		(layer "In4.Cu")
		(net "M_B_DQ27")
	)
	(segment
		(start 148.3106 -8.732266)
		(end 148.55444 -8.976106)
		(width 0.1524)
		(layer "In4.Cu")
		(net "M_B_DQ27")
	)
	(segment
		(start 147.122134 -23.932134)
		(end 147.12188 -23.932134)
		(width 0.1524)
		(layer "In4.Cu")
		(net "M_B_DQ27")
	)
	(segment
		(start 99.8982 -31.877)
		(end 100.1522 -31.877)
		(width 0.1016)
		(layer "In4.Cu")
		(net "M_B_DQ27")
	)
	(segment
		(start 99.2886 -32.0294)
		(end 99.8982 -31.877)
		(width 0.1016)
		(layer "In4.Cu")
		(net "M_B_DQ27")
	)
	(segment
		(start 104.0638 -28.6512)
		(end 103.5685 -28.8417)
		(width 0.1524)
		(layer "In4.Cu")
		(net "M_B_DQ27")
	)
	(segment
		(start 148.55444 -8.976106)
		(end 148.55444 -22.499574)
		(width 0.1524)
		(layer "In4.Cu")
		(net "M_B_DQ27")
	)
	(segment
		(start 98.8822 -32.0294)
		(end 99.2886 -32.0294)
		(width 0.1016)
		(layer "In4.Cu")
		(net "M_B_DQ27")
	)
	(segment
		(start 100.5586 -31.4706)
		(end 100.5586 -31.337504)
		(width 0.1016)
		(layer "In4.Cu")
		(net "M_B_DQ27")
	)
	(segment
		(start 148.188934 -22.865334)
		(end 147.122134 -23.932134)
		(width 0.1524)
		(layer "In4.Cu")
		(net "M_B_DQ27")
	)
	(segment
		(start 103.378 -29.0322)
		(end 103.378 -29.501338)
		(width 0.1524)
		(layer "In4.Cu")
		(net "M_B_DQ27")
	)
	(segment
		(start 107.3531 -27.2415)
		(end 106.930444 -27.2415)
		(width 0.1524)
		(layer "In4.Cu")
		(net "M_B_DQ27")
	)
	(segment
		(start 115.0874 -23.9776)
		(end 114.046 -25.019)
		(width 0.1524)
		(layer "In4.Cu")
		(net "M_B_DQ27")
	)
	(segment
		(start 110.012988 -25.019)
		(end 108.869988 -26.162)
		(width 0.1524)
		(layer "In4.Cu")
		(net "M_B_DQ27")
	)
	(segment
		(start 96.4946 -32.1056)
		(end 96.4946 -32.1818)
		(width 0.1016)
		(layer "In4.Cu")
		(net "M_B_DQ27")
	)
	(segment
		(start 148.3106 -8.165084)
		(end 148.3106 -8.732266)
		(width 0.1524)
		(layer "In4.Cu")
		(net "M_B_DQ27")
	)
	(segment
		(start 105.520744 -28.6512)
		(end 104.0638 -28.6512)
		(width 0.1524)
		(layer "In4.Cu")
		(net "M_B_DQ27")
	)
	(segment
		(start 148.635466 -7.840218)
		(end 148.3106 -8.165084)
		(width 0.1524)
		(layer "In4.Cu")
		(net "M_B_DQ27")
	)
	(segment
		(start 96.6978 -32.587946)
		(end 97.206562 -32.843216)
		(width 0.1016)
		(layer "In4.Cu")
		(net "M_B_DQ27")
	)
	(arc
		(start 97.206562 -32.843216)
		(mid 97.563834 -32.976304)
		(end 97.9424 -33.021524)
		(width 0.1016)
		(layer "In4.Cu")
		(net "M_B_DQ27")
	)
	(arc
		(start 96.4946 -32.1818)
		(mid 96.524051 -32.350401)
		(end 96.6089 -32.499046)
		(width 0.1016)
		(layer "In4.Cu")
		(net "M_B_DQ27")
	)
	(arc
		(start 103.224584 -30.042866)
		(mid 103.127322 -30.354816)
		(end 102.87 -30.5562)
		(width 0.1524)
		(layer "In4.Cu")
		(net "M_B_DQ27")
	)
	(arc
		(start 97.9424 -33.021524)
		(mid 98.176833 -32.964421)
		(end 98.358706 -32.805878)
		(width 0.1016)
		(layer "In4.Cu")
		(net "M_B_DQ27")
	)
	(arc
		(start 96.901 -31.2928)
		(mid 96.601862 -31.651231)
		(end 96.4946 -32.1056)
		(width 0.1016)
		(layer "In4.Cu")
		(net "M_B_DQ27")
	)
	(segment
		(start 54.3052 -36.1442)
		(end 54.3052 -33.5661)
		(width 0.1143)
		(layer "F.Cu")
		(net "SPI_CS0_N_M_1")
	)
	(segment
		(start 54.896766 -26.891234)
		(end 56.106822 -26.891234)
		(width 0.1143)
		(layer "F.Cu")
		(net "SPI_CS0_N_M_1")
	)
	(segment
		(start 55.5752 -36.83)
		(end 54.991 -36.83)
		(width 0.1143)
		(layer "F.Cu")
		(net "SPI_CS0_N_M_1")
	)
	(segment
		(start 55.5752 -37.592)
		(end 55.5752 -36.83)
		(width 0.1143)
		(layer "F.Cu")
		(net "SPI_CS0_N_M_1")
	)
	(segment
		(start 54.1655 -27.6225)
		(end 54.896766 -26.891234)
		(width 0.1143)
		(layer "F.Cu")
		(net "SPI_CS0_N_M_1")
	)
	(segment
		(start 53.8607 -33.1216)
		(end 53.8607 -29.320236)
		(width 0.1143)
		(layer "F.Cu")
		(net "SPI_CS0_N_M_1")
	)
	(segment
		(start 54.1655 -29.015436)
		(end 54.1655 -27.6225)
		(width 0.1143)
		(layer "F.Cu")
		(net "SPI_CS0_N_M_1")
	)
	(segment
		(start 54.991 -36.83)
		(end 54.3052 -36.1442)
		(width 0.1143)
		(layer "F.Cu")
		(net "SPI_CS0_N_M_1")
	)
	(segment
		(start 54.3052 -33.5661)
		(end 53.8607 -33.1216)
		(width 0.1143)
		(layer "F.Cu")
		(net "SPI_CS0_N_M_1")
	)
	(segment
		(start 53.8607 -29.320236)
		(end 54.1655 -29.015436)
		(width 0.1143)
		(layer "F.Cu")
		(net "SPI_CS0_N_M_1")
	)
	(segment
		(start 96.632522 -33.09874)
		(end 96.632522 -33.045908)
		(width 0.1524)
		(layer "F.Cu")
		(net "M_B_ODTPU")
	)
	(segment
		(start 96.319848 -33.411414)
		(end 96.632522 -33.09874)
		(width 0.1524)
		(layer "F.Cu")
		(net "M_B_ODTPU")
	)
	(segment
		(start 96.319848 -33.426654)
		(end 96.319848 -33.411414)
		(width 0.1524)
		(layer "F.Cu")
		(net "M_B_ODTPU")
	)
	(via
		(at 95.7326 -32.5374)
		(size 0.7112)
		(drill 0.3556)
		(layers "F.Cu" "B.Cu")
		(net "M_B_ODTPU")
	)
	(via
		(at 96.632522 -33.045908)
		(size 0.4318)
		(drill 0.2032)
		(layers "F.Cu" "B.Cu")
		(net "M_B_ODTPU")
	)
	(segment
		(start 95.98152 -32.5374)
		(end 95.7326 -32.5374)
		(width 0.1778)
		(layer "B.Cu")
		(net "M_B_ODTPU")
	)
	(segment
		(start 95.7326 -32.5374)
		(end 94.8182 -32.5374)
		(width 0.1778)
		(layer "B.Cu")
		(net "M_B_ODTPU")
	)
	(segment
		(start 96.632522 -33.045908)
		(end 96.490028 -33.045908)
		(width 0.1778)
		(layer "B.Cu")
		(net "M_B_ODTPU")
	)
	(segment
		(start 96.490028 -33.045908)
		(end 95.98152 -32.5374)
		(width 0.1778)
		(layer "B.Cu")
		(net "M_B_ODTPU")
	)
	(segment
		(start 130.149854 -1.68402)
		(end 130.149854 -3.024124)
		(width 0.1778)
		(layer "F.Cu")
		(net "M_B_DQ5")
	)
	(segment
		(start 92.634308 -26.952194)
		(end 92.615004 -26.93289)
		(width 0.1016)
		(layer "F.Cu")
		(net "M_B_DQ5")
	)
	(segment
		(start 92.615004 -26.93289)
		(end 92.151962 -26.93289)
		(width 0.1016)
		(layer "F.Cu")
		(net "M_B_DQ5")
	)
	(segment
		(start 130.149854 -3.024124)
		(end 129.9972 -3.176778)
		(width 0.1778)
		(layer "F.Cu")
		(net "M_B_DQ5")
	)
	(via
		(at 92.151962 -26.93289)
		(size 0.4318)
		(drill 0.2032)
		(layers "F.Cu" "B.Cu")
		(net "M_B_DQ5")
	)
	(via
		(at 129.9972 -3.176778)
		(size 0.4318)
		(drill 0.2032)
		(layers "F.Cu" "B.Cu")
		(net "M_B_DQ5")
	)
	(segment
		(start 129.84988 -3.029458)
		(end 129.9972 -3.176778)
		(width 0.1778)
		(layer "B.Cu")
		(net "M_B_DQ5")
	)
	(segment
		(start 129.84988 -1.690624)
		(end 129.84988 -3.029458)
		(width 0.1778)
		(layer "B.Cu")
		(net "M_B_DQ5")
	)
	(segment
		(start 111.633 -6.223)
		(end 111.4806 -6.3754)
		(width 0.1524)
		(layer "In7.Cu")
		(net "M_B_DQ5")
	)
	(segment
		(start 113.7412 -5.9182)
		(end 113.4364 -6.223)
		(width 0.1524)
		(layer "In7.Cu")
		(net "M_B_DQ5")
	)
	(segment
		(start 127.892556 -2.668778)
		(end 126.827534 -3.7338)
		(width 0.1524)
		(layer "In7.Cu")
		(net "M_B_DQ5")
	)
	(segment
		(start 115.3668 -6.223)
		(end 114.4524 -6.223)
		(width 0.1524)
		(layer "In7.Cu")
		(net "M_B_DQ5")
	)
	(segment
		(start 120.7262 -3.429)
		(end 120.5738 -3.5814)
		(width 0.1524)
		(layer "In7.Cu")
		(net "M_B_DQ5")
	)
	(segment
		(start 115.5192 -6.0706)
		(end 115.3668 -6.223)
		(width 0.1524)
		(layer "In7.Cu")
		(net "M_B_DQ5")
	)
	(segment
		(start 119.9642 -3.5814)
		(end 119.8118 -3.429)
		(width 0.1524)
		(layer "In7.Cu")
		(net "M_B_DQ5")
	)
	(segment
		(start 129.9972 -3.176778)
		(end 129.9972 -2.973578)
		(width 0.1524)
		(layer "In7.Cu")
		(net "M_B_DQ5")
	)
	(segment
		(start 114.4778 -3.429)
		(end 114.3254 -3.5814)
		(width 0.1524)
		(layer "In7.Cu")
		(net "M_B_DQ5")
	)
	(segment
		(start 124.084334 -3.7338)
		(end 123.779534 -3.429)
		(width 0.1524)
		(layer "In7.Cu")
		(net "M_B_DQ5")
	)
	(segment
		(start 123.474734 -3.429)
		(end 123.169934 -3.7338)
		(width 0.1524)
		(layer "In7.Cu")
		(net "M_B_DQ5")
	)
	(segment
		(start 120.395238 -4.3434)
		(end 120.142762 -4.3434)
		(width 0.1524)
		(layer "In7.Cu")
		(net "M_B_DQ5")
	)
	(segment
		(start 124.389134 -3.7338)
		(end 124.084334 -3.7338)
		(width 0.1524)
		(layer "In7.Cu")
		(net "M_B_DQ5")
	)
	(segment
		(start 126.217934 -3.429)
		(end 125.913134 -3.429)
		(width 0.1524)
		(layer "In7.Cu")
		(net "M_B_DQ5")
	)
	(segment
		(start 89.6366 -25.2984)
		(end 91.27109 -26.93289)
		(width 0.1016)
		(layer "In7.Cu")
		(net "M_B_DQ5")
	)
	(segment
		(start 120.5738 -4.164838)
		(end 120.395238 -4.3434)
		(width 0.1524)
		(layer "In7.Cu")
		(net "M_B_DQ5")
	)
	(segment
		(start 123.169934 -3.7338)
		(end 122.865134 -3.7338)
		(width 0.1524)
		(layer "In7.Cu")
		(net "M_B_DQ5")
	)
	(segment
		(start 111.4806 -6.3754)
		(end 111.4806 -8.7376)
		(width 0.1524)
		(layer "In7.Cu")
		(net "M_B_DQ5")
	)
	(segment
		(start 119.9642 -4.164838)
		(end 119.9642 -3.5814)
		(width 0.1524)
		(layer "In7.Cu")
		(net "M_B_DQ5")
	)
	(segment
		(start 125.303534 -3.7338)
		(end 124.998734 -3.429)
		(width 0.1524)
		(layer "In7.Cu")
		(net "M_B_DQ5")
	)
	(segment
		(start 114.1476 -5.9182)
		(end 113.7412 -5.9182)
		(width 0.1524)
		(layer "In7.Cu")
		(net "M_B_DQ5")
	)
	(segment
		(start 114.4524 -6.223)
		(end 114.1476 -5.9182)
		(width 0.1524)
		(layer "In7.Cu")
		(net "M_B_DQ5")
	)
	(segment
		(start 115.5192 -4.445)
		(end 115.5192 -6.0706)
		(width 0.1524)
		(layer "In7.Cu")
		(net "M_B_DQ5")
	)
	(segment
		(start 125.608334 -3.7338)
		(end 125.303534 -3.7338)
		(width 0.1524)
		(layer "In7.Cu")
		(net "M_B_DQ5")
	)
	(segment
		(start 114.3254 -4.1402)
		(end 114.4778 -4.2926)
		(width 0.1524)
		(layer "In7.Cu")
		(net "M_B_DQ5")
	)
	(segment
		(start 120.142762 -4.3434)
		(end 119.9642 -4.164838)
		(width 0.1524)
		(layer "In7.Cu")
		(net "M_B_DQ5")
	)
	(segment
		(start 113.4364 -6.223)
		(end 111.633 -6.223)
		(width 0.1524)
		(layer "In7.Cu")
		(net "M_B_DQ5")
	)
	(segment
		(start 105.647744 -14.570456)
		(end 96.830896 -14.570456)
		(width 0.1524)
		(layer "In7.Cu")
		(net "M_B_DQ5")
	)
	(segment
		(start 126.522734 -3.7338)
		(end 126.217934 -3.429)
		(width 0.1524)
		(layer "In7.Cu")
		(net "M_B_DQ5")
	)
	(segment
		(start 120.5738 -3.5814)
		(end 120.5738 -4.164838)
		(width 0.1524)
		(layer "In7.Cu")
		(net "M_B_DQ5")
	)
	(segment
		(start 115.3668 -4.2926)
		(end 115.5192 -4.445)
		(width 0.1524)
		(layer "In7.Cu")
		(net "M_B_DQ5")
	)
	(segment
		(start 126.827534 -3.7338)
		(end 126.522734 -3.7338)
		(width 0.1524)
		(layer "In7.Cu")
		(net "M_B_DQ5")
	)
	(segment
		(start 114.3254 -3.5814)
		(end 114.3254 -4.1402)
		(width 0.1524)
		(layer "In7.Cu")
		(net "M_B_DQ5")
	)
	(segment
		(start 114.4778 -4.2926)
		(end 115.3668 -4.2926)
		(width 0.1524)
		(layer "In7.Cu")
		(net "M_B_DQ5")
	)
	(segment
		(start 96.830896 -14.570456)
		(end 89.984834 -21.416518)
		(width 0.1524)
		(layer "In7.Cu")
		(net "M_B_DQ5")
	)
	(segment
		(start 124.693934 -3.429)
		(end 124.389134 -3.7338)
		(width 0.1524)
		(layer "In7.Cu")
		(net "M_B_DQ5")
	)
	(segment
		(start 125.913134 -3.429)
		(end 125.608334 -3.7338)
		(width 0.1524)
		(layer "In7.Cu")
		(net "M_B_DQ5")
	)
	(segment
		(start 111.4806 -8.7376)
		(end 105.647744 -14.570456)
		(width 0.1524)
		(layer "In7.Cu")
		(net "M_B_DQ5")
	)
	(segment
		(start 91.27109 -26.93289)
		(end 92.151962 -26.93289)
		(width 0.1016)
		(layer "In7.Cu")
		(net "M_B_DQ5")
	)
	(segment
		(start 123.779534 -3.429)
		(end 123.474734 -3.429)
		(width 0.1524)
		(layer "In7.Cu")
		(net "M_B_DQ5")
	)
	(segment
		(start 129.9972 -2.973578)
		(end 129.6924 -2.668778)
		(width 0.1524)
		(layer "In7.Cu")
		(net "M_B_DQ5")
	)
	(segment
		(start 89.6366 -21.764752)
		(end 89.6366 -25.2984)
		(width 0.1016)
		(layer "In7.Cu")
		(net "M_B_DQ5")
	)
	(segment
		(start 122.865134 -3.7338)
		(end 122.560334 -3.429)
		(width 0.1524)
		(layer "In7.Cu")
		(net "M_B_DQ5")
	)
	(segment
		(start 119.8118 -3.429)
		(end 114.4778 -3.429)
		(width 0.1524)
		(layer "In7.Cu")
		(net "M_B_DQ5")
	)
	(segment
		(start 124.998734 -3.429)
		(end 124.693934 -3.429)
		(width 0.1524)
		(layer "In7.Cu")
		(net "M_B_DQ5")
	)
	(segment
		(start 129.6924 -2.668778)
		(end 127.892556 -2.668778)
		(width 0.1524)
		(layer "In7.Cu")
		(net "M_B_DQ5")
	)
	(segment
		(start 122.560334 -3.429)
		(end 120.7262 -3.429)
		(width 0.1524)
		(layer "In7.Cu")
		(net "M_B_DQ5")
	)
	(segment
		(start 89.984834 -21.416518)
		(end 89.6366 -21.764752)
		(width 0.1016)
		(layer "In7.Cu")
		(net "M_B_DQ5")
	)
	(segment
		(start 54.864 -32.4866)
		(end 54.864 -29.718)
		(width 0.1143)
		(layer "F.Cu")
		(net "SPI_WP_R_N_1")
	)
	(segment
		(start 55.150766 -29.431234)
		(end 56.106822 -29.431234)
		(width 0.1143)
		(layer "F.Cu")
		(net "SPI_WP_R_N_1")
	)
	(segment
		(start 55.5752 -35.306)
		(end 55.5752 -34.544)
		(width 0.1143)
		(layer "F.Cu")
		(net "SPI_WP_R_N_1")
	)
	(segment
		(start 55.5752 -33.1978)
		(end 54.864 -32.4866)
		(width 0.1143)
		(layer "F.Cu")
		(net "SPI_WP_R_N_1")
	)
	(segment
		(start 54.864 -29.718)
		(end 55.150766 -29.431234)
		(width 0.1143)
		(layer "F.Cu")
		(net "SPI_WP_R_N_1")
	)
	(segment
		(start 55.5752 -34.544)
		(end 55.5752 -33.1978)
		(width 0.1143)
		(layer "F.Cu")
		(net "SPI_WP_R_N_1")
	)
	(segment
		(start 20.066 -33.6804)
		(end 20.7772 -34.3916)
		(width 0.254)
		(layer "F.Cu")
		(net "P3V3_STBY_VFB_R")
	)
	(segment
		(start 19.9898 -33.6042)
		(end 20.066 -33.6804)
		(width 0.254)
		(layer "F.Cu")
		(net "P3V3_STBY_VFB_R")
	)
	(segment
		(start 20.7772 -34.3916)
		(end 21.717 -34.3916)
		(width 0.254)
		(layer "F.Cu")
		(net "P3V3_STBY_VFB_R")
	)
	(segment
		(start 28.2321 -35.9156)
		(end 27.5717 -35.9156)
		(width 0.254)
		(layer "F.Cu")
		(net "P3V3_STBY_VFB_R")
	)
	(segment
		(start 19.304 -33.6042)
		(end 19.9898 -33.6042)
		(width 0.254)
		(layer "F.Cu")
		(net "P3V3_STBY_VFB_R")
	)
	(segment
		(start 28.5877 -36.2712)
		(end 28.2321 -35.9156)
		(width 0.254)
		(layer "F.Cu")
		(net "P3V3_STBY_VFB_R")
	)
	(via
		(at 21.717 -34.3916)
		(size 0.508)
		(drill 0.254)
		(layers "F.Cu" "B.Cu")
		(net "P3V3_STBY_VFB_R")
	)
	(via
		(at 27.3558 -36.322)
		(size 0.7112)
		(drill 0.3556)
		(layers "F.Cu" "B.Cu")
		(net "P3V3_STBY_VFB_R")
	)
	(via
		(at 28.5877 -36.2712)
		(size 0.508)
		(drill 0.254)
		(layers "F.Cu" "B.Cu")
		(net "P3V3_STBY_VFB_R")
	)
	(segment
		(start 24.084026 -36.322)
		(end 22.153626 -34.3916)
		(width 0.254)
		(layer "B.Cu")
		(net "P3V3_STBY_VFB_R")
	)
	(segment
		(start 28.5369 -36.322)
		(end 28.5877 -36.2712)
		(width 0.254)
		(layer "B.Cu")
		(net "P3V3_STBY_VFB_R")
	)
	(segment
		(start 27.3558 -36.322)
		(end 28.5369 -36.322)
		(width 0.254)
		(layer "B.Cu")
		(net "P3V3_STBY_VFB_R")
	)
	(segment
		(start 27.3558 -36.322)
		(end 24.084026 -36.322)
		(width 0.254)
		(layer "B.Cu")
		(net "P3V3_STBY_VFB_R")
	)
	(segment
		(start 22.153626 -34.3916)
		(end 21.717 -34.3916)
		(width 0.254)
		(layer "B.Cu")
		(net "P3V3_STBY_VFB_R")
	)
	(via
		(at 182.5498 -28.575)
		(size 0.7112)
		(drill 0.3556)
		(layers "F.Cu" "B.Cu")
		(net "VSENSE_PVDDR_A_VSEN_FB")
	)
	(segment
		(start 182.545228 -30.39999)
		(end 182.545228 -29.595572)
		(width 0.2032)
		(layer "B.Cu")
		(net "VSENSE_PVDDR_A_VSEN_FB")
	)
	(segment
		(start 182.545228 -29.595572)
		(end 182.5498 -29.591)
		(width 0.2032)
		(layer "B.Cu")
		(net "VSENSE_PVDDR_A_VSEN_FB")
	)
	(segment
		(start 182.5498 -28.575)
		(end 182.5498 -29.591)
		(width 0.2032)
		(layer "B.Cu")
		(net "VSENSE_PVDDR_A_VSEN_FB")
	)
	(segment
		(start 109.855 -24.6888)
		(end 110.0328 -24.511)
		(width 0.1143)
		(layer "F.Cu")
		(net "M_B_MON2_N")
	)
	(segment
		(start 109.7026 -19.2786)
		(end 109.8042 -19.177)
		(width 0.1143)
		(layer "F.Cu")
		(net "M_B_MON2_N")
	)
	(segment
		(start 109.855 -25.756362)
		(end 109.855 -24.6888)
		(width 0.1143)
		(layer "F.Cu")
		(net "M_B_MON2_N")
	)
	(segment
		(start 110.0328 -21.463)
		(end 109.7026 -21.1328)
		(width 0.1143)
		(layer "F.Cu")
		(net "M_B_MON2_N")
	)
	(segment
		(start 109.522768 -26.088594)
		(end 109.855 -25.756362)
		(width 0.1143)
		(layer "F.Cu")
		(net "M_B_MON2_N")
	)
	(segment
		(start 109.7026 -20.193)
		(end 109.7026 -19.2786)
		(width 0.1143)
		(layer "F.Cu")
		(net "M_B_MON2_N")
	)
	(segment
		(start 109.7026 -21.1328)
		(end 109.7026 -20.193)
		(width 0.1143)
		(layer "F.Cu")
		(net "M_B_MON2_N")
	)
	(segment
		(start 110.0328 -24.511)
		(end 110.0328 -21.463)
		(width 0.1143)
		(layer "F.Cu")
		(net "M_B_MON2_N")
	)
	(via
		(at 109.7026 -21.1328)
		(size 0.7112)
		(drill 0.3556)
		(layers "F.Cu" "B.Cu")
		(net "M_B_MON2_N")
	)
	(segment
		(start 92.47124 -25.627584)
		(end 93.004132 -25.627584)
		(width 0.1016)
		(layer "F.Cu")
		(net "M_B_DQS_DP0")
	)
	(segment
		(start 131.4958 -9.000236)
		(end 131.4958 -6.089904)
		(width 0.1778)
		(layer "F.Cu")
		(net "M_B_DQS_DP0")
	)
	(segment
		(start 131.649978 -9.154414)
		(end 131.4958 -9.000236)
		(width 0.1778)
		(layer "F.Cu")
		(net "M_B_DQS_DP0")
	)
	(segment
		(start 91.982036 -25.002236)
		(end 91.982036 -25.13838)
		(width 0.1016)
		(layer "F.Cu")
		(net "M_B_DQS_DP0")
	)
	(segment
		(start 91.7448 -24.765)
		(end 91.982036 -25.002236)
		(width 0.1016)
		(layer "F.Cu")
		(net "M_B_DQS_DP0")
	)
	(segment
		(start 91.982036 -25.13838)
		(end 92.47124 -25.627584)
		(width 0.1016)
		(layer "F.Cu")
		(net "M_B_DQS_DP0")
	)
	(segment
		(start 94.132908 -27.216608)
		(end 94.132908 -27.300174)
		(width 0.1016)
		(layer "F.Cu")
		(net "M_B_DQS_DP0")
	)
	(segment
		(start 93.543628 -26.16708)
		(end 93.543628 -26.627328)
		(width 0.1016)
		(layer "F.Cu")
		(net "M_B_DQS_DP0")
	)
	(segment
		(start 93.543628 -26.627328)
		(end 94.132908 -27.216608)
		(width 0.1016)
		(layer "F.Cu")
		(net "M_B_DQS_DP0")
	)
	(segment
		(start 93.004132 -25.627584)
		(end 93.543628 -26.16708)
		(width 0.1016)
		(layer "F.Cu")
		(net "M_B_DQS_DP0")
	)
	(segment
		(start 131.4958 -6.089904)
		(end 131.767326 -5.818378)
		(width 0.1778)
		(layer "F.Cu")
		(net "M_B_DQS_DP0")
	)
	(segment
		(start 131.649978 -9.897364)
		(end 131.649978 -9.154414)
		(width 0.1778)
		(layer "F.Cu")
		(net "M_B_DQS_DP0")
	)
	(via
		(at 131.767326 -5.818378)
		(size 0.4318)
		(drill 0.2032)
		(layers "F.Cu" "B.Cu")
		(net "M_B_DQS_DP0")
	)
	(via
		(at 91.7448 -24.765)
		(size 0.4318)
		(drill 0.2032)
		(layers "F.Cu" "B.Cu")
		(net "M_B_DQS_DP0")
	)
	(segment
		(start 131.649978 -2.4638)
		(end 131.502404 -2.611374)
		(width 0.1778)
		(layer "B.Cu")
		(net "M_B_DQS_DP0")
	)
	(segment
		(start 131.502404 -2.611374)
		(end 131.502404 -5.553456)
		(width 0.1778)
		(layer "B.Cu")
		(net "M_B_DQS_DP0")
	)
	(segment
		(start 131.649978 -1.690624)
		(end 131.649978 -2.4638)
		(width 0.1778)
		(layer "B.Cu")
		(net "M_B_DQS_DP0")
	)
	(segment
		(start 131.502404 -5.553456)
		(end 131.767326 -5.818378)
		(width 0.1778)
		(layer "B.Cu")
		(net "M_B_DQS_DP0")
	)
	(segment
		(start 92.1766 -24.3332)
		(end 91.7448 -24.765)
		(width 0.1016)
		(layer "In7.Cu")
		(net "M_B_DQS_DP0")
	)
	(segment
		(start 127.4064 -8.797798)
		(end 127.092202 -8.797798)
		(width 0.1524)
		(layer "In7.Cu")
		(net "M_B_DQS_DP0")
	)
	(segment
		(start 121.539 -8.701024)
		(end 121.539 -7.9502)
		(width 0.1524)
		(layer "In7.Cu")
		(net "M_B_DQS_DP0")
	)
	(segment
		(start 124.833634 -10.0584)
		(end 124.271786 -10.0584)
		(width 0.1524)
		(layer "In7.Cu")
		(net "M_B_DQS_DP0")
	)
	(segment
		(start 114.3 -10.1092)
		(end 113.809272 -10.1092)
		(width 0.1524)
		(layer "In7.Cu")
		(net "M_B_DQS_DP0")
	)
	(segment
		(start 125.7808 -9.717024)
		(end 125.7808 -8.9662)
		(width 0.1524)
		(layer "In7.Cu")
		(net "M_B_DQS_DP0")
	)
	(segment
		(start 127.092202 -8.797798)
		(end 126.9492 -8.9408)
		(width 0.1524)
		(layer "In7.Cu")
		(net "M_B_DQS_DP0")
	)
	(segment
		(start 92.1766 -21.688044)
		(end 92.1766 -24.3332)
		(width 0.1016)
		(layer "In7.Cu")
		(net "M_B_DQS_DP0")
	)
	(segment
		(start 131.767326 -5.818378)
		(end 131.489704 -6.096)
		(width 0.1524)
		(layer "In7.Cu")
		(net "M_B_DQS_DP0")
	)
	(segment
		(start 127.5588 -9.869424)
		(end 127.5588 -8.950198)
		(width 0.1524)
		(layer "In7.Cu")
		(net "M_B_DQS_DP0")
	)
	(segment
		(start 120.9294 -7.9502)
		(end 120.9294 -8.701024)
		(width 0.1524)
		(layer "In7.Cu")
		(net "M_B_DQS_DP0")
	)
	(segment
		(start 124.271786 -10.0584)
		(end 123.95581 -9.742424)
		(width 0.1524)
		(layer "In7.Cu")
		(net "M_B_DQS_DP0")
	)
	(segment
		(start 125.30201 -8.8138)
		(end 125.14961 -8.9662)
		(width 0.1524)
		(layer "In7.Cu")
		(net "M_B_DQS_DP0")
	)
	(segment
		(start 131.489704 -6.096)
		(end 131.489704 -6.49732)
		(width 0.1524)
		(layer "In7.Cu")
		(net "M_B_DQS_DP0")
	)
	(segment
		(start 120.613424 -9.017)
		(end 115.3922 -9.017)
		(width 0.1524)
		(layer "In7.Cu")
		(net "M_B_DQS_DP0")
	)
	(segment
		(start 98.055684 -17.186656)
		(end 95.10014 -20.1422)
		(width 0.1524)
		(layer "In7.Cu")
		(net "M_B_DQS_DP0")
	)
	(segment
		(start 131.00177 -6.985254)
		(end 131.00177 -9.28243)
		(width 0.1524)
		(layer "In7.Cu")
		(net "M_B_DQS_DP0")
	)
	(segment
		(start 125.6284 -8.8138)
		(end 125.30201 -8.8138)
		(width 0.1524)
		(layer "In7.Cu")
		(net "M_B_DQS_DP0")
	)
	(segment
		(start 131.489704 -6.49732)
		(end 131.00177 -6.985254)
		(width 0.1524)
		(layer "In7.Cu")
		(net "M_B_DQS_DP0")
	)
	(segment
		(start 127.5588 -8.950198)
		(end 127.4064 -8.797798)
		(width 0.1524)
		(layer "In7.Cu")
		(net "M_B_DQS_DP0")
	)
	(segment
		(start 121.854976 -9.017)
		(end 121.539 -8.701024)
		(width 0.1524)
		(layer "In7.Cu")
		(net "M_B_DQS_DP0")
	)
	(segment
		(start 121.3866 -7.7978)
		(end 121.0818 -7.7978)
		(width 0.1524)
		(layer "In7.Cu")
		(net "M_B_DQS_DP0")
	)
	(segment
		(start 93.646244 -20.2184)
		(end 92.1766 -21.688044)
		(width 0.1016)
		(layer "In7.Cu")
		(net "M_B_DQS_DP0")
	)
	(segment
		(start 127.798576 -10.1092)
		(end 127.5588 -9.869424)
		(width 0.1524)
		(layer "In7.Cu")
		(net "M_B_DQS_DP0")
	)
	(segment
		(start 93.730318 -20.218654)
		(end 93.730064 -20.2184)
		(width 0.1016)
		(layer "In7.Cu")
		(net "M_B_DQS_DP0")
	)
	(segment
		(start 126.071376 -10.0076)
		(end 125.7808 -9.717024)
		(width 0.1524)
		(layer "In7.Cu")
		(net "M_B_DQS_DP0")
	)
	(segment
		(start 131.00177 -9.28243)
		(end 130.175 -10.1092)
		(width 0.1524)
		(layer "In7.Cu")
		(net "M_B_DQS_DP0")
	)
	(segment
		(start 95.10014 -20.1422)
		(end 95.02394 -20.2184)
		(width 0.1016)
		(layer "In7.Cu")
		(net "M_B_DQS_DP0")
	)
	(segment
		(start 130.175 -10.1092)
		(end 127.798576 -10.1092)
		(width 0.1524)
		(layer "In7.Cu")
		(net "M_B_DQS_DP0")
	)
	(segment
		(start 95.02394 -20.2184)
		(end 94.987618 -20.218654)
		(width 0.1016)
		(layer "In7.Cu")
		(net "M_B_DQS_DP0")
	)
	(segment
		(start 121.0818 -7.7978)
		(end 120.9294 -7.9502)
		(width 0.1524)
		(layer "In7.Cu")
		(net "M_B_DQS_DP0")
	)
	(segment
		(start 94.987618 -20.218654)
		(end 93.730318 -20.218654)
		(width 0.1016)
		(layer "In7.Cu")
		(net "M_B_DQS_DP0")
	)
	(segment
		(start 115.3922 -9.017)
		(end 114.3 -10.1092)
		(width 0.1524)
		(layer "In7.Cu")
		(net "M_B_DQS_DP0")
	)
	(segment
		(start 126.633224 -10.0076)
		(end 126.071376 -10.0076)
		(width 0.1524)
		(layer "In7.Cu")
		(net "M_B_DQS_DP0")
	)
	(segment
		(start 123.80341 -9.017)
		(end 121.854976 -9.017)
		(width 0.1524)
		(layer "In7.Cu")
		(net "M_B_DQS_DP0")
	)
	(segment
		(start 125.7808 -8.9662)
		(end 125.6284 -8.8138)
		(width 0.1524)
		(layer "In7.Cu")
		(net "M_B_DQS_DP0")
	)
	(segment
		(start 126.9492 -8.9408)
		(end 126.9492 -9.691624)
		(width 0.1524)
		(layer "In7.Cu")
		(net "M_B_DQS_DP0")
	)
	(segment
		(start 120.9294 -8.701024)
		(end 120.613424 -9.017)
		(width 0.1524)
		(layer "In7.Cu")
		(net "M_B_DQS_DP0")
	)
	(segment
		(start 126.9492 -9.691624)
		(end 126.633224 -10.0076)
		(width 0.1524)
		(layer "In7.Cu")
		(net "M_B_DQS_DP0")
	)
	(segment
		(start 123.95581 -9.742424)
		(end 123.95581 -9.1694)
		(width 0.1524)
		(layer "In7.Cu")
		(net "M_B_DQS_DP0")
	)
	(segment
		(start 123.95581 -9.1694)
		(end 123.80341 -9.017)
		(width 0.1524)
		(layer "In7.Cu")
		(net "M_B_DQS_DP0")
	)
	(segment
		(start 121.539 -7.9502)
		(end 121.3866 -7.7978)
		(width 0.1524)
		(layer "In7.Cu")
		(net "M_B_DQS_DP0")
	)
	(segment
		(start 125.14961 -8.9662)
		(end 125.14961 -9.742424)
		(width 0.1524)
		(layer "In7.Cu")
		(net "M_B_DQS_DP0")
	)
	(segment
		(start 93.730064 -20.2184)
		(end 93.646244 -20.2184)
		(width 0.1016)
		(layer "In7.Cu")
		(net "M_B_DQS_DP0")
	)
	(segment
		(start 106.731816 -17.186656)
		(end 98.055684 -17.186656)
		(width 0.1524)
		(layer "In7.Cu")
		(net "M_B_DQS_DP0")
	)
	(segment
		(start 113.809272 -10.1092)
		(end 106.731816 -17.186656)
		(width 0.1524)
		(layer "In7.Cu")
		(net "M_B_DQS_DP0")
	)
	(segment
		(start 125.14961 -9.742424)
		(end 124.833634 -10.0584)
		(width 0.1524)
		(layer "In7.Cu")
		(net "M_B_DQS_DP0")
	)
	(segment
		(start 54.871366 -28.161234)
		(end 56.106822 -28.161234)
		(width 0.1143)
		(layer "F.Cu")
		(net "SPI_MISO_R_1")
	)
	(segment
		(start 54.6608 -29.220668)
		(end 54.6608 -28.3718)
		(width 0.1143)
		(layer "F.Cu")
		(net "SPI_MISO_R_1")
	)
	(segment
		(start 54.356 -29.591)
		(end 54.3687 -29.5783)
		(width 0.1143)
		(layer "F.Cu")
		(net "SPI_MISO_R_1")
	)
	(segment
		(start 54.8005 -33.3375)
		(end 54.356 -32.893)
		(width 0.1143)
		(layer "F.Cu")
		(net "SPI_MISO_R_1")
	)
	(segment
		(start 54.8005 -35.8775)
		(end 54.8005 -33.3375)
		(width 0.1143)
		(layer "F.Cu")
		(net "SPI_MISO_R_1")
	)
	(segment
		(start 54.356 -32.893)
		(end 54.356 -29.591)
		(width 0.1143)
		(layer "F.Cu")
		(net "SPI_MISO_R_1")
	)
	(segment
		(start 54.991 -36.068)
		(end 54.8005 -35.8775)
		(width 0.1143)
		(layer "F.Cu")
		(net "SPI_MISO_R_1")
	)
	(segment
		(start 54.3687 -29.512768)
		(end 54.6608 -29.220668)
		(width 0.1143)
		(layer "F.Cu")
		(net "SPI_MISO_R_1")
	)
	(segment
		(start 55.5752 -36.068)
		(end 54.991 -36.068)
		(width 0.1143)
		(layer "F.Cu")
		(net "SPI_MISO_R_1")
	)
	(segment
		(start 54.6608 -28.3718)
		(end 54.871366 -28.161234)
		(width 0.1143)
		(layer "F.Cu")
		(net "SPI_MISO_R_1")
	)
	(segment
		(start 54.3687 -29.5783)
		(end 54.3687 -29.512768)
		(width 0.1143)
		(layer "F.Cu")
		(net "SPI_MISO_R_1")
	)
	(segment
		(start 12.3952 -32.004)
		(end 12.0904 -32.004)
		(width 0.254)
		(layer "F.Cu")
		(net "AGND_P3V3_STBY")
	)
	(segment
		(start 11.2522 -30.8864)
		(end 12.0904 -31.7246)
		(width 0.254)
		(layer "F.Cu")
		(net "AGND_P3V3_STBY")
	)
	(segment
		(start 9.3218 -30.8864)
		(end 11.2522 -30.8864)
		(width 0.254)
		(layer "F.Cu")
		(net "AGND_P3V3_STBY")
	)
	(segment
		(start 7.6708 -31.5722)
		(end 8.636 -31.5722)
		(width 0.254)
		(layer "F.Cu")
		(net "AGND_P3V3_STBY")
	)
	(segment
		(start 14.4526 -31.4198)
		(end 13.716 -31.4198)
		(width 0.254)
		(layer "F.Cu")
		(net "AGND_P3V3_STBY")
	)
	(segment
		(start 13.6906 -31.4452)
		(end 12.954 -31.4452)
		(width 0.254)
		(layer "F.Cu")
		(net "AGND_P3V3_STBY")
	)
	(segment
		(start 6.9088 -31.5722)
		(end 6.096 -31.5722)
		(width 0.254)
		(layer "F.Cu")
		(net "AGND_P3V3_STBY")
	)
	(segment
		(start 14.478 -31.4452)
		(end 14.4526 -31.4198)
		(width 0.254)
		(layer "F.Cu")
		(net "AGND_P3V3_STBY")
	)
	(segment
		(start 8.636 -31.5722)
		(end 9.3218 -30.8864)
		(width 0.254)
		(layer "F.Cu")
		(net "AGND_P3V3_STBY")
	)
	(segment
		(start 12.0904 -31.7246)
		(end 12.0904 -32.004)
		(width 0.254)
		(layer "F.Cu")
		(net "AGND_P3V3_STBY")
	)
	(segment
		(start 13.716 -31.4198)
		(end 13.6906 -31.4452)
		(width 0.254)
		(layer "F.Cu")
		(net "AGND_P3V3_STBY")
	)
	(segment
		(start 6.9088 -31.5722)
		(end 7.6708 -31.5722)
		(width 0.254)
		(layer "F.Cu")
		(net "AGND_P3V3_STBY")
	)
	(segment
		(start 12.954 -31.4452)
		(end 12.3952 -32.004)
		(width 0.254)
		(layer "F.Cu")
		(net "AGND_P3V3_STBY")
	)
	(segment
		(start 13.716 -31.4198)
		(end 13.716 -30.7086)
		(width 0.254)
		(layer "F.Cu")
		(net "AGND_P3V3_STBY")
	)
	(segment
		(start 13.716 -30.7086)
		(end 13.589 -30.5816)
		(width 0.254)
		(layer "F.Cu")
		(net "AGND_P3V3_STBY")
	)
	(via
		(at 13.589 -30.5816)
		(size 0.508)
		(drill 0.254)
		(layers "F.Cu" "B.Cu")
		(net "AGND_P3V3_STBY")
	)
	(via
		(at 18.1102 -33.655)
		(size 0.7112)
		(drill 0.3556)
		(layers "F.Cu" "B.Cu")
		(net "AGND_P3V3_STBY")
	)
	(segment
		(start 18.415 -33.3502)
		(end 18.415 -31.877)
		(width 0.254)
		(layer "B.Cu")
		(net "AGND_P3V3_STBY")
	)
	(segment
		(start 17.2212 -33.655)
		(end 18.1102 -33.655)
		(width 0.254)
		(layer "B.Cu")
		(net "AGND_P3V3_STBY")
	)
	(segment
		(start 17.1196 -30.5816)
		(end 15.4178 -30.5816)
		(width 0.254)
		(layer "B.Cu")
		(net "AGND_P3V3_STBY")
	)
	(segment
		(start 18.415 -31.877)
		(end 17.1196 -30.5816)
		(width 0.254)
		(layer "B.Cu")
		(net "AGND_P3V3_STBY")
	)
	(segment
		(start 15.4178 -30.5816)
		(end 15.367 -30.5308)
		(width 0.254)
		(layer "B.Cu")
		(net "AGND_P3V3_STBY")
	)
	(segment
		(start 17.1958 -34.417)
		(end 17.1958 -33.6804)
		(width 0.254)
		(layer "B.Cu")
		(net "AGND_P3V3_STBY")
	)
	(segment
		(start 15.3162 -30.5816)
		(end 13.589 -30.5816)
		(width 0.254)
		(layer "B.Cu")
		(net "AGND_P3V3_STBY")
	)
	(segment
		(start 18.1102 -33.655)
		(end 18.415 -33.3502)
		(width 0.254)
		(layer "B.Cu")
		(net "AGND_P3V3_STBY")
	)
	(segment
		(start 15.367 -30.5308)
		(end 15.3162 -30.5816)
		(width 0.254)
		(layer "B.Cu")
		(net "AGND_P3V3_STBY")
	)
	(segment
		(start 17.1958 -33.6804)
		(end 17.2212 -33.655)
		(width 0.254)
		(layer "B.Cu")
		(net "AGND_P3V3_STBY")
	)
	(segment
		(start 109.879384 -58.944002)
		(end 109.879384 -58.065416)
		(width 0.1143)
		(layer "F.Cu")
		(net "M_A_MON1_N")
	)
	(segment
		(start 110.109 -56.9976)
		(end 110.109 -57.8358)
		(width 0.1143)
		(layer "F.Cu")
		(net "M_A_MON1_N")
	)
	(segment
		(start 109.2454 -55.499)
		(end 109.2454 -52.588922)
		(width 0.1143)
		(layer "F.Cu")
		(net "M_A_MON1_N")
	)
	(segment
		(start 110.109 -57.8358)
		(end 110.0328 -57.912)
		(width 0.1143)
		(layer "F.Cu")
		(net "M_A_MON1_N")
	)
	(segment
		(start 109.879384 -58.065416)
		(end 110.0328 -57.912)
		(width 0.1143)
		(layer "F.Cu")
		(net "M_A_MON1_N")
	)
	(segment
		(start 110.109 -56.9976)
		(end 110.109 -56.3626)
		(width 0.1143)
		(layer "F.Cu")
		(net "M_A_MON1_N")
	)
	(segment
		(start 109.2454 -52.588922)
		(end 109.522768 -52.311554)
		(width 0.1143)
		(layer "F.Cu")
		(net "M_A_MON1_N")
	)
	(segment
		(start 110.109 -56.3626)
		(end 109.2454 -55.499)
		(width 0.1143)
		(layer "F.Cu")
		(net "M_A_MON1_N")
	)
	(via
		(at 110.109 -56.9976)
		(size 0.7112)
		(drill 0.3556)
		(layers "F.Cu" "B.Cu")
		(net "M_A_MON1_N")
	)
	(segment
		(start 6.9088 -32.4358)
		(end 6.9088 -32.765238)
		(width 0.254)
		(layer "F.Cu")
		(net "P3V3_STBY_TRIP")
	)
	(segment
		(start 6.9088 -32.765238)
		(end 7.531354 -33.387792)
		(width 0.254)
		(layer "F.Cu")
		(net "P3V3_STBY_TRIP")
	)
	(segment
		(start 8.726678 -34.449004)
		(end 8.283194 -34.449004)
		(width 0.254)
		(layer "F.Cu")
		(net "P3V3_STBY_TRIP")
	)
	(segment
		(start 8.283194 -34.449004)
		(end 7.531354 -33.697164)
		(width 0.254)
		(layer "F.Cu")
		(net "P3V3_STBY_TRIP")
	)
	(segment
		(start 7.531354 -33.697164)
		(end 7.531354 -33.387792)
		(width 0.254)
		(layer "F.Cu")
		(net "P3V3_STBY_TRIP")
	)
	(via
		(at 7.531354 -33.387792)
		(size 0.7112)
		(drill 0.3556)
		(layers "F.Cu" "B.Cu")
		(net "P3V3_STBY_TRIP")
	)
	(segment
		(start 45.1358 -20.2692)
		(end 44.6024 -19.7358)
		(width 0.3048)
		(layer "F.Cu")
		(net "P1V0")
	)
	(segment
		(start 73.8378 -63.1698)
		(end 73.8378 -58.684922)
		(width 0.3048)
		(layer "F.Cu")
		(net "P1V0")
	)
	(segment
		(start 100.249228 -43.200574)
		(end 100.249228 -43.200066)
		(width 0.3048)
		(layer "F.Cu")
		(net "P1V0")
	)
	(segment
		(start 98.649028 -40.800274)
		(end 98.649028 -40.799766)
		(width 0.3048)
		(layer "F.Cu")
		(net "P1V0")
	)
	(segment
		(start 93.4593 -38.7604)
		(end 93.4593 -38.7731)
		(width 0.3048)
		(layer "F.Cu")
		(net "P1V0")
	)
	(segment
		(start 99.451668 -44.000166)
		(end 99.84359 -44.392088)
		(width 0.3048)
		(layer "F.Cu")
		(net "P1V0")
	)
	(segment
		(start 97.854262 -40.000174)
		(end 98.241358 -40.38727)
		(width 0.3048)
		(layer "F.Cu")
		(net "P1V0")
	)
	(segment
		(start 100.249228 -44.000166)
		(end 100.64115 -43.608244)
		(width 0.3048)
		(layer "F.Cu")
		(net "P1V0")
	)
	(segment
		(start 97.851468 -40.000174)
		(end 97.854262 -40.000174)
		(width 0.3048)
		(layer "F.Cu")
		(net "P1V0")
	)
	(segment
		(start 10.4394 -61.72073)
		(end 10.4394 -61.05398)
		(width 0.254)
		(layer "F.Cu")
		(net "P1V0")
	)
	(segment
		(start 98.649028 -37.599874)
		(end 98.649028 -37.620194)
		(width 0.3048)
		(layer "F.Cu")
		(net "P1V0")
	)
	(segment
		(start 99.451668 -44.000674)
		(end 99.451668 -44.000166)
		(width 0.3048)
		(layer "F.Cu")
		(net "P1V0")
	)
	(segment
		(start 92.767912 -44.984162)
		(end 92.610178 -44.984162)
		(width 0.3048)
		(layer "F.Cu")
		(net "P1V0")
	)
	(segment
		(start 45.1358 -21.463)
		(end 45.1358 -20.701)
		(width 0.3048)
		(layer "F.Cu")
		(net "P1V0")
	)
	(segment
		(start 93.848428 -37.599874)
		(end 93.848428 -37.658548)
		(width 0.3048)
		(layer "F.Cu")
		(net "P1V0")
	)
	(segment
		(start 93.848428 -39.162228)
		(end 93.848428 -39.200074)
		(width 0.3048)
		(layer "F.Cu")
		(net "P1V0")
	)
	(segment
		(start 99.84359 -44.392088)
		(end 99.84359 -44.408344)
		(width 0.3048)
		(layer "F.Cu")
		(net "P1V0")
	)
	(segment
		(start 93.848428 -39.200074)
		(end 93.848428 -40.000174)
		(width 0.3048)
		(layer "F.Cu")
		(net "P1V0")
	)
	(segment
		(start 100.249228 -44.000674)
		(end 100.249228 -44.000166)
		(width 0.3048)
		(layer "F.Cu")
		(net "P1V0")
	)
	(segment
		(start 98.649028 -37.620194)
		(end 98.260662 -38.00856)
		(width 0.3048)
		(layer "F.Cu")
		(net "P1V0")
	)
	(segment
		(start 10.5664 -59.14898)
		(end 11.394694 -58.320686)
		(width 0.254)
		(layer "F.Cu")
		(net "P1V0")
	)
	(segment
		(start 44.6024 -19.7358)
		(end 44.4246 -19.7358)
		(width 0.3048)
		(layer "F.Cu")
		(net "P1V0")
	)
	(segment
		(start 74.97699 -57.545732)
		(end 74.97699 -55.956454)
		(width 0.3048)
		(layer "F.Cu")
		(net "P1V0")
	)
	(segment
		(start 98.649028 -40.799766)
		(end 98.241358 -40.392096)
		(width 0.3048)
		(layer "F.Cu")
		(net "P1V0")
	)
	(segment
		(start 99.451668 -43.200066)
		(end 99.84359 -43.591988)
		(width 0.3048)
		(layer "F.Cu")
		(net "P1V0")
	)
	(segment
		(start 10.5664 -60.12942)
		(end 10.5664 -59.14898)
		(width 0.254)
		(layer "F.Cu")
		(net "P1V0")
	)
	(segment
		(start 93.848428 -38.398196)
		(end 93.478604 -38.028372)
		(width 0.3048)
		(layer "F.Cu")
		(net "P1V0")
	)
	(segment
		(start 73.8378 -58.684922)
		(end 74.97699 -57.545732)
		(width 0.3048)
		(layer "F.Cu")
		(net "P1V0")
	)
	(segment
		(start 92.108528 -44.973494)
		(end 92.108528 -44.972986)
		(width 0.3048)
		(layer "F.Cu")
		(net "P1V0")
	)
	(segment
		(start 99.451668 -43.200574)
		(end 99.451668 -43.200066)
		(width 0.3048)
		(layer "F.Cu")
		(net "P1V0")
	)
	(segment
		(start 10.7442 -60.74918)
		(end 10.7442 -60.30722)
		(width 0.254)
		(layer "F.Cu")
		(net "P1V0")
	)
	(segment
		(start 101.051868 -44.000166)
		(end 101.44379 -43.608244)
		(width 0.3048)
		(layer "F.Cu")
		(net "P1V0")
	)
	(segment
		(start 75.057 -64.389)
		(end 73.8378 -63.1698)
		(width 0.3048)
		(layer "F.Cu")
		(net "P1V0")
	)
	(segment
		(start 98.649028 -44.000166)
		(end 99.01555 -44.366688)
		(width 0.3048)
		(layer "F.Cu")
		(net "P1V0")
	)
	(segment
		(start 11.55827 -62.8396)
		(end 10.4394 -61.72073)
		(width 0.254)
		(layer "F.Cu")
		(net "P1V0")
	)
	(segment
		(start 93.050868 -44.701206)
		(end 92.767912 -44.984162)
		(width 0.3048)
		(layer "F.Cu")
		(net "P1V0")
	)
	(segment
		(start 93.050868 -44.701714)
		(end 93.050868 -44.701206)
		(width 0.3048)
		(layer "F.Cu")
		(net "P1V0")
	)
	(segment
		(start 93.848428 -37.658548)
		(end 93.478604 -38.028372)
		(width 0.3048)
		(layer "F.Cu")
		(net "P1V0")
	)
	(segment
		(start 180.6702 -38.862)
		(end 180.6702 -39.22395)
		(width 0.3048)
		(layer "F.Cu")
		(net "P1V0")
	)
	(segment
		(start 93.448124 -43.60291)
		(end 93.448124 -43.550332)
		(width 0.3048)
		(layer "F.Cu")
		(net "P1V0")
	)
	(segment
		(start 93.050868 -44.000674)
		(end 93.050868 -44.000166)
		(width 0.3048)
		(layer "F.Cu")
		(net "P1V0")
	)
	(segment
		(start 98.649028 -44.000674)
		(end 98.649028 -44.000166)
		(width 0.3048)
		(layer "F.Cu")
		(net "P1V0")
	)
	(segment
		(start 73.8378 -54.991)
		(end 73.533 -54.6862)
		(width 0.3048)
		(layer "F.Cu")
		(net "P1V0")
	)
	(segment
		(start 93.4593 -38.7731)
		(end 93.848428 -39.162228)
		(width 0.3048)
		(layer "F.Cu")
		(net "P1V0")
	)
	(segment
		(start 100.249228 -43.200066)
		(end 100.64115 -43.591988)
		(width 0.3048)
		(layer "F.Cu")
		(net "P1V0")
	)
	(segment
		(start 12.573 -58.9026)
		(end 11.394694 -57.724294)
		(width 0.254)
		(layer "F.Cu")
		(net "P1V0")
	)
	(segment
		(start 180.6702 -37.338)
		(end 180.6702 -38.1)
		(width 0.3048)
		(layer "F.Cu")
		(net "P1V0")
	)
	(segment
		(start 101.051868 -44.000674)
		(end 101.051868 -44.000166)
		(width 0.3048)
		(layer "F.Cu")
		(net "P1V0")
	)
	(segment
		(start 97.851468 -37.599366)
		(end 98.260662 -38.00856)
		(width 0.3048)
		(layer "F.Cu")
		(net "P1V0")
	)
	(segment
		(start 180.6702 -39.22395)
		(end 181.0258 -39.57955)
		(width 0.3048)
		(layer "F.Cu")
		(net "P1V0")
	)
	(segment
		(start 98.241358 -40.392096)
		(end 98.241358 -40.38727)
		(width 0.3048)
		(layer "F.Cu")
		(net "P1V0")
	)
	(segment
		(start 180.6702 -38.1)
		(end 180.6702 -38.862)
		(width 0.3048)
		(layer "F.Cu")
		(net "P1V0")
	)
	(segment
		(start 100.64115 -43.591988)
		(end 100.64115 -43.608244)
		(width 0.3048)
		(layer "F.Cu")
		(net "P1V0")
	)
	(segment
		(start 73.7362 -54.483)
		(end 73.7362 -54.418484)
		(width 0.3048)
		(layer "F.Cu")
		(net "P1V0")
	)
	(segment
		(start 93.4466 -38.7477)
		(end 93.4593 -38.7604)
		(width 0.3048)
		(layer "F.Cu")
		(net "P1V0")
	)
	(segment
		(start 101.44379 -43.591988)
		(end 101.44379 -43.608244)
		(width 0.3048)
		(layer "F.Cu")
		(net "P1V0")
	)
	(segment
		(start 99.84359 -43.591988)
		(end 99.84359 -43.608244)
		(width 0.3048)
		(layer "F.Cu")
		(net "P1V0")
	)
	(segment
		(start 92.108528 -44.972986)
		(end 92.599002 -44.972986)
		(width 0.3048)
		(layer "F.Cu")
		(net "P1V0")
	)
	(segment
		(start 97.851468 -37.599874)
		(end 97.851468 -37.599366)
		(width 0.3048)
		(layer "F.Cu")
		(net "P1V0")
	)
	(segment
		(start 12.573 -59.6392)
		(end 12.573 -58.9026)
		(width 0.254)
		(layer "F.Cu")
		(net "P1V0")
	)
	(segment
		(start 12.4968 -62.8396)
		(end 11.55827 -62.8396)
		(width 0.254)
		(layer "F.Cu")
		(net "P1V0")
	)
	(segment
		(start 11.394694 -58.320686)
		(end 11.394694 -57.724294)
		(width 0.254)
		(layer "F.Cu")
		(net "P1V0")
	)
	(segment
		(start 132.715 -52.1208)
		(end 132.0038 -52.832)
		(width 0.3048)
		(layer "F.Cu")
		(net "P1V0")
	)
	(segment
		(start 42.10177 -30.55493)
		(end 40.209724 -30.55493)
		(width 0.2794)
		(layer "F.Cu")
		(net "P1V0")
	)
	(segment
		(start 10.7442 -60.30722)
		(end 10.5664 -60.12942)
		(width 0.254)
		(layer "F.Cu")
		(net "P1V0")
	)
	(segment
		(start 92.599002 -44.972986)
		(end 92.610178 -44.984162)
		(width 0.3048)
		(layer "F.Cu")
		(net "P1V0")
	)
	(segment
		(start 73.7362 -54.418484)
		(end 74.205084 -53.9496)
		(width 0.3048)
		(layer "F.Cu")
		(net "P1V0")
	)
	(segment
		(start 130.14325 -52.832)
		(end 129.71145 -53.2638)
		(width 0.3048)
		(layer "F.Cu")
		(net "P1V0")
	)
	(segment
		(start 74.205084 -53.9496)
		(end 74.4982 -53.9496)
		(width 0.3048)
		(layer "F.Cu")
		(net "P1V0")
	)
	(segment
		(start 45.1358 -20.701)
		(end 45.1358 -20.2692)
		(width 0.3048)
		(layer "F.Cu")
		(net "P1V0")
	)
	(segment
		(start 181.0258 -39.57955)
		(end 181.0258 -39.618412)
		(width 0.3048)
		(layer "F.Cu")
		(net "P1V0")
	)
	(segment
		(start 93.848428 -38.399974)
		(end 93.848428 -38.398196)
		(width 0.3048)
		(layer "F.Cu")
		(net "P1V0")
	)
	(segment
		(start 40.209724 -30.55493)
		(end 39.936166 -30.281372)
		(width 0.2794)
		(layer "F.Cu")
		(net "P1V0")
	)
	(segment
		(start 73.533 -54.6862)
		(end 73.7362 -54.483)
		(width 0.3048)
		(layer "F.Cu")
		(net "P1V0")
	)
	(segment
		(start 74.011536 -54.991)
		(end 73.8378 -54.991)
		(width 0.3048)
		(layer "F.Cu")
		(net "P1V0")
	)
	(segment
		(start 10.4394 -61.05398)
		(end 10.7442 -60.74918)
		(width 0.254)
		(layer "F.Cu")
		(net "P1V0")
	)
	(segment
		(start 101.051868 -43.200574)
		(end 101.051868 -43.200066)
		(width 0.3048)
		(layer "F.Cu")
		(net "P1V0")
	)
	(segment
		(start 101.051868 -43.200066)
		(end 101.44379 -43.591988)
		(width 0.3048)
		(layer "F.Cu")
		(net "P1V0")
	)
	(segment
		(start 93.050868 -44.000166)
		(end 93.448124 -43.60291)
		(width 0.3048)
		(layer "F.Cu")
		(net "P1V0")
	)
	(segment
		(start 132.0038 -52.832)
		(end 130.14325 -52.832)
		(width 0.3048)
		(layer "F.Cu")
		(net "P1V0")
	)
	(segment
		(start 99.01555 -44.366688)
		(end 99.06635 -44.366688)
		(width 0.3048)
		(layer "F.Cu")
		(net "P1V0")
	)
	(segment
		(start 74.97699 -55.956454)
		(end 74.011536 -54.991)
		(width 0.3048)
		(layer "F.Cu")
		(net "P1V0")
	)
	(via
		(at 31.4706 -28.2448)
		(size 0.7112)
		(drill 0.4064)
		(layers "F.Cu" "B.Cu")
		(net "P1V0")
	)
	(via
		(at 93.448124 -43.550332)
		(size 0.4318)
		(drill 0.2032)
		(layers "F.Cu" "B.Cu")
		(net "P1V0")
	)
	(via
		(at 30.3276 -25.9842)
		(size 0.7112)
		(drill 0.4064)
		(layers "F.Cu" "B.Cu")
		(net "P1V0")
	)
	(via
		(at 82.8294 -67.818)
		(size 0.508)
		(drill 0.254)
		(layers "F.Cu" "B.Cu")
		(net "P1V0")
	)
	(via
		(at 181.0258 -39.618412)
		(size 0.508)
		(drill 0.254)
		(layers "F.Cu" "B.Cu")
		(net "P1V0")
	)
	(via
		(at 44.4246 -19.7358)
		(size 0.508)
		(drill 0.254)
		(layers "F.Cu" "B.Cu")
		(net "P1V0")
	)
	(via
		(at 30.3276 -27.1018)
		(size 0.7112)
		(drill 0.4064)
		(layers "F.Cu" "B.Cu")
		(net "P1V0")
	)
	(via
		(at 30.3276 -28.2448)
		(size 0.7112)
		(drill 0.4064)
		(layers "F.Cu" "B.Cu")
		(net "P1V0")
	)
	(via
		(at 99.821492 -34.027872)
		(size 0.4318)
		(drill 0.2032)
		(layers "F.Cu" "B.Cu")
		(net "P1V0")
	)
	(via
		(at 102.2096 -35.601402)
		(size 0.4318)
		(drill 0.2032)
		(layers "F.Cu" "B.Cu")
		(net "P1V0")
	)
	(via
		(at 94.5896 -45.4914)
		(size 0.4318)
		(drill 0.2032)
		(layers "F.Cu" "B.Cu")
		(net "P1V0")
	)
	(via
		(at 26.416 -28.194)
		(size 0.7112)
		(drill 0.4064)
		(layers "F.Cu" "B.Cu")
		(net "P1V0")
	)
	(via
		(at 90.2716 -34.8234)
		(size 0.4318)
		(drill 0.2032)
		(layers "F.Cu" "B.Cu")
		(net "P1V0")
	)
	(via
		(at 91.292934 -32.290512)
		(size 0.4318)
		(drill 0.2032)
		(layers "F.Cu" "B.Cu")
		(net "P1V0")
	)
	(via
		(at 101.421692 -35.628072)
		(size 0.4318)
		(drill 0.2032)
		(layers "F.Cu" "B.Cu")
		(net "P1V0")
	)
	(via
		(at 30.3276 -29.4386)
		(size 0.7112)
		(drill 0.4064)
		(layers "F.Cu" "B.Cu")
		(net "P1V0")
	)
	(via
		(at 87.6554 -21.082)
		(size 0.7112)
		(drill 0.4064)
		(layers "F.Cu" "B.Cu")
		(net "P1V0")
	)
	(via
		(at 20.32 -24.511)
		(size 0.7112)
		(drill 0.3556)
		(layers "F.Cu" "B.Cu")
		(net "P1V0")
	)
	(via
		(at 94.6404 -46.0756)
		(size 0.4318)
		(drill 0.2032)
		(layers "F.Cu" "B.Cu")
		(net "P1V0")
	)
	(via
		(at 99.84359 -43.608244)
		(size 0.4318)
		(drill 0.2032)
		(layers "F.Cu" "B.Cu")
		(net "P1V0")
	)
	(via
		(at 99.06635 -44.366688)
		(size 0.4318)
		(drill 0.2032)
		(layers "F.Cu" "B.Cu")
		(net "P1V0")
	)
	(via
		(at 91.2622 -33.02)
		(size 0.4318)
		(drill 0.2032)
		(layers "F.Cu" "B.Cu")
		(net "P1V0")
	)
	(via
		(at 91.97848 -31.534862)
		(size 0.4318)
		(drill 0.2032)
		(layers "F.Cu" "B.Cu")
		(net "P1V0")
	)
	(via
		(at 100.621592 -34.027872)
		(size 0.4318)
		(drill 0.2032)
		(layers "F.Cu" "B.Cu")
		(net "P1V0")
	)
	(via
		(at 105.366058 -60.621672)
		(size 0.7112)
		(drill 0.3556)
		(layers "F.Cu" "B.Cu")
		(net "P1V0")
	)
	(via
		(at 98.241358 -40.38727)
		(size 0.4318)
		(drill 0.2032)
		(layers "F.Cu" "B.Cu")
		(net "P1V0")
	)
	(via
		(at 102.24516 -43.62704)
		(size 0.4318)
		(drill 0.2032)
		(layers "F.Cu" "B.Cu")
		(net "P1V0")
	)
	(via
		(at 100.64115 -43.608244)
		(size 0.4318)
		(drill 0.2032)
		(layers "F.Cu" "B.Cu")
		(net "P1V0")
	)
	(via
		(at 90.678 -17.653)
		(size 0.7112)
		(drill 0.4064)
		(layers "F.Cu" "B.Cu")
		(net "P1V0")
	)
	(via
		(at 28.829 -25.908)
		(size 0.7112)
		(drill 0.3556)
		(layers "F.Cu" "B.Cu")
		(net "P1V0")
	)
	(via
		(at 91.3892 -18.4658)
		(size 0.7112)
		(drill 0.4064)
		(layers "F.Cu" "B.Cu")
		(net "P1V0")
	)
	(via
		(at 90.424 -30.734)
		(size 0.7112)
		(drill 0.3556)
		(layers "F.Cu" "B.Cu")
		(net "P1V0")
	)
	(via
		(at 110.6678 -61.7855)
		(size 0.508)
		(drill 0.254)
		(layers "F.Cu" "B.Cu")
		(net "P1V0")
	)
	(via
		(at 92.6084 -44.3992)
		(size 0.4318)
		(drill 0.2032)
		(layers "F.Cu" "B.Cu")
		(net "P1V0")
	)
	(via
		(at 91.976194 -32.294068)
		(size 0.4318)
		(drill 0.2032)
		(layers "F.Cu" "B.Cu")
		(net "P1V0")
	)
	(via
		(at 99.84359 -44.408344)
		(size 0.4318)
		(drill 0.2032)
		(layers "F.Cu" "B.Cu")
		(net "P1V0")
	)
	(via
		(at 75.057 -64.389)
		(size 0.508)
		(drill 0.254)
		(layers "F.Cu" "B.Cu")
		(net "P1V0")
	)
	(via
		(at 88.7222 -21.082)
		(size 0.7112)
		(drill 0.4064)
		(layers "F.Cu" "B.Cu")
		(net "P1V0")
	)
	(via
		(at 74.4982 -53.9496)
		(size 0.508)
		(drill 0.254)
		(layers "F.Cu" "B.Cu")
		(net "P1V0")
	)
	(via
		(at 106.68 -61.976)
		(size 0.508)
		(drill 0.254)
		(layers "F.Cu" "B.Cu")
		(net "P1V0")
	)
	(via
		(at 101.44379 -43.608244)
		(size 0.4318)
		(drill 0.2032)
		(layers "F.Cu" "B.Cu")
		(net "P1V0")
	)
	(via
		(at 31.4452 -26.035)
		(size 0.7112)
		(drill 0.4064)
		(layers "F.Cu" "B.Cu")
		(net "P1V0")
	)
	(via
		(at 93.478604 -38.028372)
		(size 0.4318)
		(drill 0.2032)
		(layers "F.Cu" "B.Cu")
		(net "P1V0")
	)
	(via
		(at 31.4706 -29.4386)
		(size 0.7112)
		(drill 0.4064)
		(layers "F.Cu" "B.Cu")
		(net "P1V0")
	)
	(via
		(at 89.789 -18.2626)
		(size 0.7112)
		(drill 0.4064)
		(layers "F.Cu" "B.Cu")
		(net "P1V0")
	)
	(via
		(at 89.9668 -19.4056)
		(size 0.7112)
		(drill 0.4064)
		(layers "F.Cu" "B.Cu")
		(net "P1V0")
	)
	(via
		(at 92.610178 -44.984162)
		(size 0.4318)
		(drill 0.2032)
		(layers "F.Cu" "B.Cu")
		(net "P1V0")
	)
	(via
		(at 22.987 -25.654)
		(size 0.508)
		(drill 0.254)
		(layers "F.Cu" "B.Cu")
		(net "P1V0")
	)
	(via
		(at 98.260662 -38.00856)
		(size 0.4318)
		(drill 0.2032)
		(layers "F.Cu" "B.Cu")
		(net "P1V0")
	)
	(via
		(at 101.421692 -34.827972)
		(size 0.4318)
		(drill 0.2032)
		(layers "F.Cu" "B.Cu")
		(net "P1V0")
	)
	(via
		(at 26.416 -27.0764)
		(size 0.7112)
		(drill 0.4064)
		(layers "F.Cu" "B.Cu")
		(net "P1V0")
	)
	(via
		(at 26.416 -29.337)
		(size 0.7112)
		(drill 0.4064)
		(layers "F.Cu" "B.Cu")
		(net "P1V0")
	)
	(via
		(at 21.971 -28.829)
		(size 0.508)
		(drill 0.254)
		(layers "F.Cu" "B.Cu")
		(net "P1V0")
	)
	(via
		(at 25.908 -30.353)
		(size 0.7112)
		(drill 0.3556)
		(layers "F.Cu" "B.Cu")
		(net "P1V0")
	)
	(via
		(at 91.292934 -31.498032)
		(size 0.4318)
		(drill 0.2032)
		(layers "F.Cu" "B.Cu")
		(net "P1V0")
	)
	(via
		(at 102.250494 -34.798)
		(size 0.4318)
		(drill 0.2032)
		(layers "F.Cu" "B.Cu")
		(net "P1V0")
	)
	(via
		(at 39.936166 -30.281372)
		(size 0.508)
		(drill 0.254)
		(layers "F.Cu" "B.Cu")
		(net "P1V0")
	)
	(via
		(at 99.821492 -34.827972)
		(size 0.4318)
		(drill 0.2032)
		(layers "F.Cu" "B.Cu")
		(net "P1V0")
	)
	(via
		(at 89.9922 -32.6644)
		(size 0.4318)
		(drill 0.2032)
		(layers "F.Cu" "B.Cu")
		(net "P1V0")
	)
	(via
		(at 100.665534 -34.794698)
		(size 0.4318)
		(drill 0.2032)
		(layers "F.Cu" "B.Cu")
		(net "P1V0")
	)
	(via
		(at 92.6084 -43.5864)
		(size 0.4318)
		(drill 0.2032)
		(layers "F.Cu" "B.Cu")
		(net "P1V0")
	)
	(via
		(at 92.837 -19.304)
		(size 0.7112)
		(drill 0.3556)
		(layers "F.Cu" "B.Cu")
		(net "P1V0")
	)
	(via
		(at 100.621592 -35.628072)
		(size 0.4318)
		(drill 0.2032)
		(layers "F.Cu" "B.Cu")
		(net "P1V0")
	)
	(via
		(at 129.71145 -53.2638)
		(size 0.508)
		(drill 0.254)
		(layers "F.Cu" "B.Cu")
		(net "P1V0")
	)
	(via
		(at 93.4466 -38.7477)
		(size 0.4318)
		(drill 0.2032)
		(layers "F.Cu" "B.Cu")
		(net "P1V0")
	)
	(via
		(at 90.7542 -32.6644)
		(size 0.4318)
		(drill 0.2032)
		(layers "F.Cu" "B.Cu")
		(net "P1V0")
	)
	(via
		(at 31.4706 -27.1018)
		(size 0.7112)
		(drill 0.4064)
		(layers "F.Cu" "B.Cu")
		(net "P1V0")
	)
	(via
		(at 93.731334 -45.752512)
		(size 0.4318)
		(drill 0.2032)
		(layers "F.Cu" "B.Cu")
		(net "P1V0")
	)
	(via
		(at 89.281 -34.544)
		(size 0.4318)
		(drill 0.2032)
		(layers "F.Cu" "B.Cu")
		(net "P1V0")
	)
	(via
		(at 11.394694 -57.724294)
		(size 0.508)
		(drill 0.254)
		(layers "F.Cu" "B.Cu")
		(net "P1V0")
	)
	(via
		(at 93.98 -46.482)
		(size 0.7112)
		(drill 0.3556)
		(layers "F.Cu" "B.Cu")
		(net "P1V0")
	)
	(via
		(at 94.2086 -43.6118)
		(size 0.4318)
		(drill 0.2032)
		(layers "F.Cu" "B.Cu")
		(net "P1V0")
	)
	(via
		(at 92.1258 -17.6784)
		(size 0.7112)
		(drill 0.4064)
		(layers "F.Cu" "B.Cu")
		(net "P1V0")
	)
	(segment
		(start 133.1468 -28.067)
		(end 155.9306 -28.067)
		(width 0.3048)
		(layer "B.Cu")
		(net "P1V0")
	)
	(segment
		(start 22.5552 -27.94)
		(end 22.5552 -28.2448)
		(width 0.3048)
		(layer "B.Cu")
		(net "P1V0")
	)
	(segment
		(start 39.116 -30.0228)
		(end 39.497 -30.0228)
		(width 0.3048)
		(layer "B.Cu")
		(net "P1V0")
	)
	(segment
		(start 22.5552 -28.2448)
		(end 21.971 -28.829)
		(width 0.3048)
		(layer "B.Cu")
		(net "P1V0")
	)
	(segment
		(start 152.022302 -51.3207)
		(end 131.65455 -51.3207)
		(width 0.3048)
		(layer "B.Cu")
		(net "P1V0")
	)
	(segment
		(start 92.71 -38.0492)
		(end 92.7354 -38.0238)
		(width 0.3048)
		(layer "B.Cu")
		(net "P1V0")
	)
	(segment
		(start 181.864 -34.892488)
		(end 181.864 -38.780212)
		(width 0.3048)
		(layer "B.Cu")
		(net "P1V0")
	)
	(segment
		(start 76.628752 -64.9732)
		(end 78.827376 -64.9732)
		(width 0.3048)
		(layer "B.Cu")
		(net "P1V0")
	)
	(segment
		(start 78.827376 -64.9732)
		(end 80.071976 -66.2178)
		(width 0.3048)
		(layer "B.Cu")
		(net "P1V0")
	)
	(segment
		(start 158.46552 -49.7967)
		(end 156.08427 -52.17795)
		(width 0.3048)
		(layer "B.Cu")
		(net "P1V0")
	)
	(segment
		(start 93.478604 -38.715696)
		(end 93.478604 -38.028372)
		(width 0.3048)
		(layer "B.Cu")
		(net "P1V0")
	)
	(segment
		(start 181.864 -38.780212)
		(end 181.0258 -39.618412)
		(width 0.3048)
		(layer "B.Cu")
		(net "P1V0")
	)
	(segment
		(start 82.931 -63.5508)
		(end 83.8962 -64.516)
		(width 0.3048)
		(layer "B.Cu")
		(net "P1V0")
	)
	(segment
		(start 178.594512 -31.623)
		(end 181.864 -34.892488)
		(width 0.3048)
		(layer "B.Cu")
		(net "P1V0")
	)
	(segment
		(start 93.474032 -38.0238)
		(end 93.478604 -38.028372)
		(width 0.3048)
		(layer "B.Cu")
		(net "P1V0")
	)
	(segment
		(start 93.78442 -52.8574)
		(end 93.08084 -53.56098)
		(width 0.3048)
		(layer "B.Cu")
		(net "P1V0")
	)
	(segment
		(start 96.5962 -59.2074)
		(end 103.951786 -59.2074)
		(width 0.3048)
		(layer "B.Cu")
		(net "P1V0")
	)
	(segment
		(start 92.7354 -38.0238)
		(end 93.474032 -38.0238)
		(width 0.3048)
		(layer "B.Cu")
		(net "P1V0")
	)
	(segment
		(start 181.0258 -41.1988)
		(end 176.403 -45.8216)
		(width 0.3048)
		(layer "B.Cu")
		(net "P1V0")
	)
	(segment
		(start 167.840152 -49.53)
		(end 167.573452 -49.7967)
		(width 0.3048)
		(layer "B.Cu")
		(net "P1V0")
	)
	(segment
		(start 82.8294 -67.818)
		(end 82.423 -67.4116)
		(width 0.3048)
		(layer "B.Cu")
		(net "P1V0")
	)
	(segment
		(start 22.987 -24.5872)
		(end 22.4028 -24.003)
		(width 0.3048)
		(layer "B.Cu")
		(net "P1V0")
	)
	(segment
		(start 165.60165 -29.20365)
		(end 168.021 -31.623)
		(width 0.3048)
		(layer "B.Cu")
		(net "P1V0")
	)
	(segment
		(start 75.057 -64.389)
		(end 75.586844 -64.918844)
		(width 0.3048)
		(layer "B.Cu")
		(net "P1V0")
	)
	(segment
		(start 74.4982 -53.529484)
		(end 73.533 -52.564284)
		(width 0.254)
		(layer "B.Cu")
		(net "P1V0")
	)
	(segment
		(start 73.533 -52.564284)
		(end 73.533 -50.7238)
		(width 0.254)
		(layer "B.Cu")
		(net "P1V0")
	)
	(segment
		(start 75.438 -52.9844)
		(end 75.438 -53.0098)
		(width 0.3048)
		(layer "B.Cu")
		(net "P1V0")
	)
	(segment
		(start 110.684564 -61.768736)
		(end 110.684564 -59.965336)
		(width 0.3048)
		(layer "B.Cu")
		(net "P1V0")
	)
	(segment
		(start 19.2278 -24.765)
		(end 20.066 -24.765)
		(width 0.3048)
		(layer "B.Cu")
		(net "P1V0")
	)
	(segment
		(start 82.931 -63.5254)
		(end 82.931 -63.5508)
		(width 0.3048)
		(layer "B.Cu")
		(net "P1V0")
	)
	(segment
		(start 22.987 -25.654)
		(end 22.987 -24.5872)
		(width 0.3048)
		(layer "B.Cu")
		(net "P1V0")
	)
	(segment
		(start 156.08427 -52.17795)
		(end 152.879552 -52.17795)
		(width 0.3048)
		(layer "B.Cu")
		(net "P1V0")
	)
	(segment
		(start 98.933 -38.141402)
		(end 98.800158 -38.00856)
		(width 0.3048)
		(layer "B.Cu")
		(net "P1V0")
	)
	(segment
		(start 39.755572 -30.281372)
		(end 39.936166 -30.281372)
		(width 0.3048)
		(layer "B.Cu")
		(net "P1V0")
	)
	(segment
		(start 168.021 -31.623)
		(end 178.594512 -31.623)
		(width 0.3048)
		(layer "B.Cu")
		(net "P1V0")
	)
	(segment
		(start 83.8962 -64.516)
		(end 83.8962 -66.7512)
		(width 0.3048)
		(layer "B.Cu")
		(net "P1V0")
	)
	(segment
		(start 110.6678 -61.7855)
		(end 110.684564 -61.768736)
		(width 0.3048)
		(layer "B.Cu")
		(net "P1V0")
	)
	(segment
		(start 167.573452 -49.7967)
		(end 158.46552 -49.7967)
		(width 0.3048)
		(layer "B.Cu")
		(net "P1V0")
	)
	(segment
		(start 98.241358 -40.38727)
		(end 98.38309 -40.529002)
		(width 0.3048)
		(layer "B.Cu")
		(net "P1V0")
	)
	(segment
		(start 131.65455 -51.3207)
		(end 129.71145 -53.2638)
		(width 0.3048)
		(layer "B.Cu")
		(net "P1V0")
	)
	(segment
		(start 173.874684 -49.53)
		(end 167.840152 -49.53)
		(width 0.3048)
		(layer "B.Cu")
		(net "P1V0")
	)
	(segment
		(start 74.4982 -53.9496)
		(end 74.4982 -53.529484)
		(width 0.254)
		(layer "B.Cu")
		(net "P1V0")
	)
	(segment
		(start 75.438 -53.0098)
		(end 74.4982 -53.9496)
		(width 0.3048)
		(layer "B.Cu")
		(net "P1V0")
	)
	(segment
		(start 80.137 -66.2178)
		(end 81.026 -66.2178)
		(width 0.3048)
		(layer "B.Cu")
		(net "P1V0")
	)
	(segment
		(start 98.800158 -38.00856)
		(end 98.260662 -38.00856)
		(width 0.3048)
		(layer "B.Cu")
		(net "P1V0")
	)
	(segment
		(start 93.08084 -53.56098)
		(end 93.08084 -55.69204)
		(width 0.3048)
		(layer "B.Cu")
		(net "P1V0")
	)
	(segment
		(start 157.06725 -29.20365)
		(end 165.60165 -29.20365)
		(width 0.3048)
		(layer "B.Cu")
		(net "P1V0")
	)
	(segment
		(start 176.403 -47.001684)
		(end 173.874684 -49.53)
		(width 0.3048)
		(layer "B.Cu")
		(net "P1V0")
	)
	(segment
		(start 81.026 -66.2178)
		(end 81.915 -66.2178)
		(width 0.3048)
		(layer "B.Cu")
		(net "P1V0")
	)
	(segment
		(start 82.423 -67.4116)
		(end 82.423 -66.7258)
		(width 0.3048)
		(layer "B.Cu")
		(net "P1V0")
	)
	(segment
		(start 181.0258 -39.618412)
		(end 181.0258 -41.1988)
		(width 0.3048)
		(layer "B.Cu")
		(net "P1V0")
	)
	(segment
		(start 128.35255 -51.9049)
		(end 129.71145 -53.2638)
		(width 0.3048)
		(layer "B.Cu")
		(net "P1V0")
	)
	(segment
		(start 155.9306 -28.067)
		(end 157.06725 -29.20365)
		(width 0.3048)
		(layer "B.Cu")
		(net "P1V0")
	)
	(segment
		(start 93.08084 -55.69204)
		(end 96.5962 -59.2074)
		(width 0.3048)
		(layer "B.Cu")
		(net "P1V0")
	)
	(segment
		(start 20.066 -24.765)
		(end 20.32 -24.511)
		(width 0.3048)
		(layer "B.Cu")
		(net "P1V0")
	)
	(segment
		(start 73.533 -50.7238)
		(end 73.5838 -50.673)
		(width 0.254)
		(layer "B.Cu")
		(net "P1V0")
	)
	(segment
		(start 82.423 -66.7258)
		(end 81.915 -66.2178)
		(width 0.3048)
		(layer "B.Cu")
		(net "P1V0")
	)
	(segment
		(start 75.586844 -64.918844)
		(end 76.574396 -64.918844)
		(width 0.3048)
		(layer "B.Cu")
		(net "P1V0")
	)
	(segment
		(start 39.497 -30.0228)
		(end 39.755572 -30.281372)
		(width 0.3048)
		(layer "B.Cu")
		(net "P1V0")
	)
	(segment
		(start 103.951786 -59.2074)
		(end 105.366058 -60.621672)
		(width 0.3048)
		(layer "B.Cu")
		(net "P1V0")
	)
	(segment
		(start 83.8962 -66.7512)
		(end 82.8294 -67.818)
		(width 0.3048)
		(layer "B.Cu")
		(net "P1V0")
	)
	(segment
		(start 93.4466 -38.7477)
		(end 93.478604 -38.715696)
		(width 0.3048)
		(layer "B.Cu")
		(net "P1V0")
	)
	(segment
		(start 152.879552 -52.17795)
		(end 152.022302 -51.3207)
		(width 0.3048)
		(layer "B.Cu")
		(net "P1V0")
	)
	(segment
		(start 22.4028 -24.003)
		(end 20.828 -24.003)
		(width 0.3048)
		(layer "B.Cu")
		(net "P1V0")
	)
	(segment
		(start 98.38309 -40.529002)
		(end 98.933 -40.529002)
		(width 0.3048)
		(layer "B.Cu")
		(net "P1V0")
	)
	(segment
		(start 133.1468 -27.305)
		(end 133.1468 -28.067)
		(width 0.3048)
		(layer "B.Cu")
		(net "P1V0")
	)
	(segment
		(start 176.403 -45.8216)
		(end 176.403 -47.001684)
		(width 0.3048)
		(layer "B.Cu")
		(net "P1V0")
	)
	(segment
		(start 20.828 -24.003)
		(end 20.32 -24.511)
		(width 0.3048)
		(layer "B.Cu")
		(net "P1V0")
	)
	(segment
		(start 118.745 -51.9049)
		(end 128.35255 -51.9049)
		(width 0.3048)
		(layer "B.Cu")
		(net "P1V0")
	)
	(segment
		(start 105.366058 -60.621672)
		(end 106.68 -61.935614)
		(width 0.3048)
		(layer "B.Cu")
		(net "P1V0")
	)
	(segment
		(start 80.071976 -66.2178)
		(end 80.137 -66.2178)
		(width 0.3048)
		(layer "B.Cu")
		(net "P1V0")
	)
	(segment
		(start 94.361 -52.8574)
		(end 93.78442 -52.8574)
		(width 0.3048)
		(layer "B.Cu")
		(net "P1V0")
	)
	(segment
		(start 73.5838 -50.673)
		(end 74.4982 -50.673)
		(width 0.254)
		(layer "B.Cu")
		(net "P1V0")
	)
	(segment
		(start 76.574396 -64.918844)
		(end 76.628752 -64.9732)
		(width 0.3048)
		(layer "B.Cu")
		(net "P1V0")
	)
	(segment
		(start 106.68 -61.935614)
		(end 106.68 -61.976)
		(width 0.3048)
		(layer "B.Cu")
		(net "P1V0")
	)
	(segment
		(start 110.684564 -59.965336)
		(end 118.745 -51.9049)
		(width 0.3048)
		(layer "B.Cu")
		(net "P1V0")
	)
	(segment
		(start 36.875212 -27.813)
		(end 35.249612 -29.4386)
		(width 0.508)
		(layer "In4.Cu")
		(net "P1V0")
	)
	(segment
		(start 39.936166 -30.281372)
		(end 39.918894 -30.2641)
		(width 0.508)
		(layer "In4.Cu")
		(net "P1V0")
	)
	(segment
		(start 39.915592 -30.2641)
		(end 39.243 -29.591508)
		(width 0.508)
		(layer "In4.Cu")
		(net "P1V0")
	)
	(segment
		(start 38.543738 -27.813)
		(end 36.875212 -27.813)
		(width 0.508)
		(layer "In4.Cu")
		(net "P1V0")
	)
	(segment
		(start 39.918894 -30.2641)
		(end 39.915592 -30.2641)
		(width 0.508)
		(layer "In4.Cu")
		(net "P1V0")
	)
	(segment
		(start 35.249612 -29.4386)
		(end 31.4706 -29.4386)
		(width 0.508)
		(layer "In4.Cu")
		(net "P1V0")
	)
	(segment
		(start 39.243 -29.591508)
		(end 39.243 -28.512262)
		(width 0.508)
		(layer "In4.Cu")
		(net "P1V0")
	)
	(segment
		(start 39.243 -28.512262)
		(end 38.543738 -27.813)
		(width 0.508)
		(layer "In4.Cu")
		(net "P1V0")
	)
	(segment
		(start 82.8294 -67.818)
		(end 83.693 -67.818)
		(width 0.508)
		(layer "In9.Cu")
		(net "P1V0")
	)
	(segment
		(start 104.547416 -65.659)
		(end 104.54767 -65.659)
		(width 0.508)
		(layer "In9.Cu")
		(net "P1V0")
	)
	(segment
		(start 107.47375 -61.18225)
		(end 106.68 -61.976)
		(width 0.3048)
		(layer "In9.Cu")
		(net "P1V0")
	)
	(segment
		(start 106.7816 -62.0776)
		(end 106.68 -61.976)
		(width 0.508)
		(layer "In9.Cu")
		(net "P1V0")
	)
	(segment
		(start 26.416 -29.337)
		(end 26.416 -30.164278)
		(width 0.508)
		(layer "In9.Cu")
		(net "P1V0")
	)
	(segment
		(start 14.909292 -50.270156)
		(end 11.394694 -53.784754)
		(width 0.508)
		(layer "In9.Cu")
		(net "P1V0")
	)
	(segment
		(start 84.6328 -66.8782)
		(end 87.077804 -66.8782)
		(width 0.508)
		(layer "In9.Cu")
		(net "P1V0")
	)
	(segment
		(start 26.416 -30.164278)
		(end 23.024846 -33.555432)
		(width 0.508)
		(layer "In9.Cu")
		(net "P1V0")
	)
	(segment
		(start 23.024846 -33.555432)
		(end 23.024846 -41.138602)
		(width 0.508)
		(layer "In9.Cu")
		(net "P1V0")
	)
	(segment
		(start 11.394694 -53.784754)
		(end 11.394694 -57.724294)
		(width 0.508)
		(layer "In9.Cu")
		(net "P1V0")
	)
	(segment
		(start 110.06455 -61.18225)
		(end 107.47375 -61.18225)
		(width 0.3048)
		(layer "In9.Cu")
		(net "P1V0")
	)
	(segment
		(start 83.693 -67.818)
		(end 84.6328 -66.8782)
		(width 0.508)
		(layer "In9.Cu")
		(net "P1V0")
	)
	(segment
		(start 104.54767 -65.659)
		(end 106.7816 -63.42507)
		(width 0.508)
		(layer "In9.Cu")
		(net "P1V0")
	)
	(segment
		(start 104.242616 -65.9638)
		(end 104.547416 -65.659)
		(width 0.508)
		(layer "In9.Cu")
		(net "P1V0")
	)
	(segment
		(start 99.5172 -65.9638)
		(end 104.242616 -65.9638)
		(width 0.508)
		(layer "In9.Cu")
		(net "P1V0")
	)
	(segment
		(start 88.144604 -67.945)
		(end 97.536 -67.945)
		(width 0.508)
		(layer "In9.Cu")
		(net "P1V0")
	)
	(segment
		(start 110.6678 -61.7855)
		(end 110.06455 -61.18225)
		(width 0.3048)
		(layer "In9.Cu")
		(net "P1V0")
	)
	(segment
		(start 97.536 -67.945)
		(end 99.5172 -65.9638)
		(width 0.508)
		(layer "In9.Cu")
		(net "P1V0")
	)
	(segment
		(start 14.909292 -49.254156)
		(end 14.909292 -50.270156)
		(width 0.508)
		(layer "In9.Cu")
		(net "P1V0")
	)
	(segment
		(start 87.077804 -66.8782)
		(end 88.144604 -67.945)
		(width 0.508)
		(layer "In9.Cu")
		(net "P1V0")
	)
	(segment
		(start 106.7816 -63.42507)
		(end 106.7816 -62.0776)
		(width 0.508)
		(layer "In9.Cu")
		(net "P1V0")
	)
	(segment
		(start 23.024846 -41.138602)
		(end 14.909292 -49.254156)
		(width 0.508)
		(layer "In9.Cu")
		(net "P1V0")
	)
	(segment
		(start 101.90988 -44.701714)
		(end 102.2604 -44.351194)
		(width 0.1778)
		(layer "F.Cu")
		(net "M_A_DQPU")
	)
	(segment
		(start 101.750368 -44.701714)
		(end 101.90988 -44.701714)
		(width 0.1778)
		(layer "F.Cu")
		(net "M_A_DQPU")
	)
	(via
		(at 102.0572 -45.1612)
		(size 0.7112)
		(drill 0.3556)
		(layers "F.Cu" "B.Cu")
		(net "M_A_DQPU")
	)
	(via
		(at 102.2604 -44.351194)
		(size 0.4318)
		(drill 0.2032)
		(layers "F.Cu" "B.Cu")
		(net "M_A_DQPU")
	)
	(segment
		(start 102.2604 -44.351194)
		(end 102.2604 -44.958)
		(width 0.1778)
		(layer "B.Cu")
		(net "M_A_DQPU")
	)
	(segment
		(start 101.1682 -44.2214)
		(end 102.130606 -44.2214)
		(width 0.1778)
		(layer "B.Cu")
		(net "M_A_DQPU")
	)
	(segment
		(start 102.2604 -44.958)
		(end 102.0572 -45.1612)
		(width 0.1778)
		(layer "B.Cu")
		(net "M_A_DQPU")
	)
	(segment
		(start 102.130606 -44.2214)
		(end 102.2604 -44.351194)
		(width 0.1778)
		(layer "B.Cu")
		(net "M_A_DQPU")
	)
	(segment
		(start 179.049934 -8.586216)
		(end 178.92522 -8.461502)
		(width 0.1778)
		(layer "F.Cu")
		(net "M_B_DQ43")
	)
	(segment
		(start 111.783368 -37.3126)
		(end 111.251746 -36.780978)
		(width 0.1016)
		(layer "F.Cu")
		(net "M_B_DQ43")
	)
	(segment
		(start 111.251746 -36.780978)
		(end 110.936532 -36.780978)
		(width 0.1016)
		(layer "F.Cu")
		(net "M_B_DQ43")
	)
	(segment
		(start 110.936532 -36.780978)
		(end 110.749588 -36.594034)
		(width 0.1016)
		(layer "F.Cu")
		(net "M_B_DQ43")
	)
	(segment
		(start 115.6716 -34.3154)
		(end 112.6744 -37.3126)
		(width 0.1016)
		(layer "F.Cu")
		(net "M_B_DQ43")
	)
	(segment
		(start 112.6744 -37.3126)
		(end 111.783368 -37.3126)
		(width 0.1016)
		(layer "F.Cu")
		(net "M_B_DQ43")
	)
	(segment
		(start 117.2718 -34.3154)
		(end 115.6716 -34.3154)
		(width 0.1016)
		(layer "F.Cu")
		(net "M_B_DQ43")
	)
	(segment
		(start 117.6274 -33.9598)
		(end 117.2718 -34.3154)
		(width 0.1016)
		(layer "F.Cu")
		(net "M_B_DQ43")
	)
	(segment
		(start 179.049934 -9.897364)
		(end 179.049934 -8.586216)
		(width 0.1778)
		(layer "F.Cu")
		(net "M_B_DQ43")
	)
	(via
		(at 117.6274 -33.9598)
		(size 0.4318)
		(drill 0.2032)
		(layers "F.Cu" "B.Cu")
		(net "M_B_DQ43")
	)
	(via
		(at 178.92522 -8.461502)
		(size 0.4318)
		(drill 0.2032)
		(layers "F.Cu" "B.Cu")
		(net "M_B_DQ43")
	)
	(segment
		(start 178.74996 -9.89076)
		(end 178.74996 -8.636762)
		(width 0.1778)
		(layer "B.Cu")
		(net "M_B_DQ43")
	)
	(segment
		(start 178.74996 -8.636762)
		(end 178.92522 -8.461502)
		(width 0.1778)
		(layer "B.Cu")
		(net "M_B_DQ43")
	)
	(segment
		(start 151.5364 -31.4198)
		(end 150.227538 -31.4198)
		(width 0.1524)
		(layer "In2.Cu")
		(net "M_B_DQ43")
	)
	(segment
		(start 149.948138 -31.1404)
		(end 139.573 -31.1404)
		(width 0.1524)
		(layer "In2.Cu")
		(net "M_B_DQ43")
	)
	(segment
		(start 152.661366 -31.869634)
		(end 151.986234 -31.869634)
		(width 0.1524)
		(layer "In2.Cu")
		(net "M_B_DQ43")
	)
	(segment
		(start 178.92522 -8.461502)
		(end 178.8922 -8.494522)
		(width 0.1524)
		(layer "In2.Cu")
		(net "M_B_DQ43")
	)
	(segment
		(start 138.843766 -31.869634)
		(end 131.58724 -31.869634)
		(width 0.1524)
		(layer "In2.Cu")
		(net "M_B_DQ43")
	)
	(segment
		(start 166.827962 -22.1996)
		(end 165.27272 -22.1996)
		(width 0.1524)
		(layer "In2.Cu")
		(net "M_B_DQ43")
	)
	(segment
		(start 160.50895 -27.591258)
		(end 160.50895 -27.80665)
		(width 0.1524)
		(layer "In2.Cu")
		(net "M_B_DQ43")
	)
	(segment
		(start 156.591 -30.988)
		(end 155.709366 -31.869634)
		(width 0.1524)
		(layer "In2.Cu")
		(net "M_B_DQ43")
	)
	(segment
		(start 153.1112 -31.4198)
		(end 152.661366 -31.869634)
		(width 0.1524)
		(layer "In2.Cu")
		(net "M_B_DQ43")
	)
	(segment
		(start 160.50895 -27.80665)
		(end 157.3276 -30.988)
		(width 0.1524)
		(layer "In2.Cu")
		(net "M_B_DQ43")
	)
	(segment
		(start 155.709366 -31.869634)
		(end 154.221434 -31.869634)
		(width 0.1524)
		(layer "In2.Cu")
		(net "M_B_DQ43")
	)
	(segment
		(start 164.4396 -23.03272)
		(end 164.4396 -23.9776)
		(width 0.1524)
		(layer "In2.Cu")
		(net "M_B_DQ43")
	)
	(segment
		(start 150.227538 -31.4198)
		(end 149.948138 -31.1404)
		(width 0.1524)
		(layer "In2.Cu")
		(net "M_B_DQ43")
	)
	(segment
		(start 130.172968 -33.284414)
		(end 118.937786 -33.284414)
		(width 0.1524)
		(layer "In2.Cu")
		(net "M_B_DQ43")
	)
	(segment
		(start 160.401 -27.267916)
		(end 160.401 -27.483308)
		(width 0.1524)
		(layer "In2.Cu")
		(net "M_B_DQ43")
	)
	(segment
		(start 160.832292 -27.052016)
		(end 160.6169 -27.052016)
		(width 0.1524)
		(layer "In2.Cu")
		(net "M_B_DQ43")
	)
	(segment
		(start 162.53714 -25.34031)
		(end 161.5694 -26.30805)
		(width 0.1524)
		(layer "In2.Cu")
		(net "M_B_DQ43")
	)
	(segment
		(start 160.6169 -27.052016)
		(end 160.401 -27.267916)
		(width 0.1524)
		(layer "In2.Cu")
		(net "M_B_DQ43")
	)
	(segment
		(start 163.5252 -25.11552)
		(end 163.30041 -25.34031)
		(width 0.1524)
		(layer "In2.Cu")
		(net "M_B_DQ43")
	)
	(segment
		(start 161.5694 -26.7462)
		(end 161.155634 -27.159966)
		(width 0.1524)
		(layer "In2.Cu")
		(net "M_B_DQ43")
	)
	(segment
		(start 151.986234 -31.869634)
		(end 151.5364 -31.4198)
		(width 0.1524)
		(layer "In2.Cu")
		(net "M_B_DQ43")
	)
	(segment
		(start 118.937786 -33.284414)
		(end 118.364 -33.8582)
		(width 0.1016)
		(layer "In2.Cu")
		(net "M_B_DQ43")
	)
	(segment
		(start 176.912016 -12.115546)
		(end 166.827962 -22.1996)
		(width 0.1524)
		(layer "In2.Cu")
		(net "M_B_DQ43")
	)
	(segment
		(start 161.155634 -27.159966)
		(end 160.940242 -27.159966)
		(width 0.1524)
		(layer "In2.Cu")
		(net "M_B_DQ43")
	)
	(segment
		(start 160.401 -27.483308)
		(end 160.50895 -27.591258)
		(width 0.1524)
		(layer "In2.Cu")
		(net "M_B_DQ43")
	)
	(segment
		(start 139.573 -31.1404)
		(end 138.843766 -31.869634)
		(width 0.1524)
		(layer "In2.Cu")
		(net "M_B_DQ43")
	)
	(segment
		(start 153.7716 -31.4198)
		(end 153.1112 -31.4198)
		(width 0.1524)
		(layer "In2.Cu")
		(net "M_B_DQ43")
	)
	(segment
		(start 131.58724 -31.869634)
		(end 130.172968 -33.284414)
		(width 0.1524)
		(layer "In2.Cu")
		(net "M_B_DQ43")
	)
	(segment
		(start 160.940242 -27.159966)
		(end 160.832292 -27.052016)
		(width 0.1524)
		(layer "In2.Cu")
		(net "M_B_DQ43")
	)
	(segment
		(start 161.5694 -26.30805)
		(end 161.5694 -26.7462)
		(width 0.1524)
		(layer "In2.Cu")
		(net "M_B_DQ43")
	)
	(segment
		(start 157.3276 -30.988)
		(end 156.591 -30.988)
		(width 0.1524)
		(layer "In2.Cu")
		(net "M_B_DQ43")
	)
	(segment
		(start 178.8922 -10.135616)
		(end 176.91227 -12.115546)
		(width 0.1524)
		(layer "In2.Cu")
		(net "M_B_DQ43")
	)
	(segment
		(start 164.4396 -23.9776)
		(end 164.211 -24.2062)
		(width 0.1524)
		(layer "In2.Cu")
		(net "M_B_DQ43")
	)
	(segment
		(start 163.5252 -24.4348)
		(end 163.5252 -25.11552)
		(width 0.1524)
		(layer "In2.Cu")
		(net "M_B_DQ43")
	)
	(segment
		(start 176.91227 -12.115546)
		(end 176.912016 -12.115546)
		(width 0.1524)
		(layer "In2.Cu")
		(net "M_B_DQ43")
	)
	(segment
		(start 164.211 -24.2062)
		(end 163.7538 -24.2062)
		(width 0.1524)
		(layer "In2.Cu")
		(net "M_B_DQ43")
	)
	(segment
		(start 178.8922 -8.494522)
		(end 178.8922 -10.135616)
		(width 0.1524)
		(layer "In2.Cu")
		(net "M_B_DQ43")
	)
	(segment
		(start 117.729 -33.8582)
		(end 117.6274 -33.9598)
		(width 0.1016)
		(layer "In2.Cu")
		(net "M_B_DQ43")
	)
	(segment
		(start 163.30041 -25.34031)
		(end 162.53714 -25.34031)
		(width 0.1524)
		(layer "In2.Cu")
		(net "M_B_DQ43")
	)
	(segment
		(start 165.27272 -22.1996)
		(end 164.4396 -23.03272)
		(width 0.1524)
		(layer "In2.Cu")
		(net "M_B_DQ43")
	)
	(segment
		(start 154.221434 -31.869634)
		(end 153.7716 -31.4198)
		(width 0.1524)
		(layer "In2.Cu")
		(net "M_B_DQ43")
	)
	(segment
		(start 118.364 -33.8582)
		(end 117.729 -33.8582)
		(width 0.1016)
		(layer "In2.Cu")
		(net "M_B_DQ43")
	)
	(segment
		(start 163.7538 -24.2062)
		(end 163.5252 -24.4348)
		(width 0.1524)
		(layer "In2.Cu")
		(net "M_B_DQ43")
	)
	(segment
		(start 15.7988 -33.4518)
		(end 17.0434 -33.4518)
		(width 0.508)
		(layer "F.Cu")
		(net "P3V3_STBY_VBST_RC")
	)
	(segment
		(start 17.0434 -33.4518)
		(end 17.4752 -33.8836)
		(width 0.508)
		(layer "F.Cu")
		(net "P3V3_STBY_VBST_RC")
	)
	(segment
		(start 185.9534 -32.7406)
		(end 186.188604 -32.975804)
		(width 0.2032)
		(layer "F.Cu")
		(net "VR_PVDDR_A_NTC")
	)
	(segment
		(start 184.771792 -32.738822)
		(end 184.834022 -32.738822)
		(width 0.2032)
		(layer "F.Cu")
		(net "VR_PVDDR_A_NTC")
	)
	(segment
		(start 186.188604 -32.975804)
		(end 186.856116 -32.975804)
		(width 0.2032)
		(layer "F.Cu")
		(net "VR_PVDDR_A_NTC")
	)
	(segment
		(start 184.8358 -32.7406)
		(end 185.9534 -32.7406)
		(width 0.2032)
		(layer "F.Cu")
		(net "VR_PVDDR_A_NTC")
	)
	(segment
		(start 184.834022 -32.738822)
		(end 184.8358 -32.7406)
		(width 0.2032)
		(layer "F.Cu")
		(net "VR_PVDDR_A_NTC")
	)
	(via
		(at 185.7248 -32.9184)
		(size 0.7112)
		(drill 0.3556)
		(layers "F.Cu" "B.Cu")
		(net "VR_PVDDR_A_NTC")
	)
	(via
		(at 184.771792 -32.738822)
		(size 0.508)
		(drill 0.254)
		(layers "F.Cu" "B.Cu")
		(net "VR_PVDDR_A_NTC")
	)
	(segment
		(start 185.545222 -32.738822)
		(end 184.771792 -32.738822)
		(width 0.2032)
		(layer "B.Cu")
		(net "VR_PVDDR_A_NTC")
	)
	(segment
		(start 185.7248 -32.9184)
		(end 185.545222 -32.738822)
		(width 0.2032)
		(layer "B.Cu")
		(net "VR_PVDDR_A_NTC")
	)
	(segment
		(start 186.5884 -33.2486)
		(end 186.0296 -33.2486)
		(width 0.2032)
		(layer "B.Cu")
		(net "VR_PVDDR_A_NTC")
	)
	(segment
		(start 185.7248 -32.9438)
		(end 185.7248 -32.9184)
		(width 0.2032)
		(layer "B.Cu")
		(net "VR_PVDDR_A_NTC")
	)
	(segment
		(start 186.69 -32.131)
		(end 186.5884 -32.2326)
		(width 0.2032)
		(layer "B.Cu")
		(net "VR_PVDDR_A_NTC")
	)
	(segment
		(start 186.5884 -32.2326)
		(end 186.5884 -33.2486)
		(width 0.2032)
		(layer "B.Cu")
		(net "VR_PVDDR_A_NTC")
	)
	(segment
		(start 186.0296 -33.2486)
		(end 185.7248 -32.9438)
		(width 0.2032)
		(layer "B.Cu")
		(net "VR_PVDDR_A_NTC")
	)
	(segment
		(start 110.335568 -50.685954)
		(end 110.335568 -50.9778)
		(width 0.1143)
		(layer "F.Cu")
		(net "M_A_MON2_P")
	)
	(segment
		(start 109.973618 -51.33975)
		(end 109.973618 -52.950618)
		(width 0.1143)
		(layer "F.Cu")
		(net "M_A_MON2_P")
	)
	(segment
		(start 110.184184 -53.161184)
		(end 110.184184 -55.193184)
		(width 0.1143)
		(layer "F.Cu")
		(net "M_A_MON2_P")
	)
	(segment
		(start 111.2012 -58.714386)
		(end 110.971584 -58.944002)
		(width 0.1143)
		(layer "F.Cu")
		(net "M_A_MON2_P")
	)
	(segment
		(start 110.617 -55.626)
		(end 111.2012 -56.2102)
		(width 0.1143)
		(layer "F.Cu")
		(net "M_A_MON2_P")
	)
	(segment
		(start 111.2012 -57.912)
		(end 111.2012 -58.714386)
		(width 0.1143)
		(layer "F.Cu")
		(net "M_A_MON2_P")
	)
	(segment
		(start 111.2012 -56.2102)
		(end 111.2012 -57.912)
		(width 0.1143)
		(layer "F.Cu")
		(net "M_A_MON2_P")
	)
	(segment
		(start 109.973618 -52.950618)
		(end 110.184184 -53.161184)
		(width 0.1143)
		(layer "F.Cu")
		(net "M_A_MON2_P")
	)
	(segment
		(start 110.335568 -50.9778)
		(end 109.973618 -51.33975)
		(width 0.1143)
		(layer "F.Cu")
		(net "M_A_MON2_P")
	)
	(segment
		(start 110.184184 -55.193184)
		(end 110.617 -55.626)
		(width 0.1143)
		(layer "F.Cu")
		(net "M_A_MON2_P")
	)
	(via
		(at 110.617 -55.626)
		(size 0.7112)
		(drill 0.3556)
		(layers "F.Cu" "B.Cu")
		(net "M_A_MON2_P")
	)
	(segment
		(start 99.6696 -25.3746)
		(end 99.922584 -25.627584)
		(width 0.1016)
		(layer "F.Cu")
		(net "M_B_DQ21")
	)
	(segment
		(start 100.711508 -26.769822)
		(end 100.711508 -27.050492)
		(width 0.1016)
		(layer "F.Cu")
		(net "M_B_DQ21")
	)
	(segment
		(start 139.750038 -2.614676)
		(end 140.1826 -3.047238)
		(width 0.1778)
		(layer "F.Cu")
		(net "M_B_DQ21")
	)
	(segment
		(start 140.1826 -3.532378)
		(end 140.4112 -3.760978)
		(width 0.1778)
		(layer "F.Cu")
		(net "M_B_DQ21")
	)
	(segment
		(start 99.2378 -22.7076)
		(end 99.6696 -23.1394)
		(width 0.1016)
		(layer "F.Cu")
		(net "M_B_DQ21")
	)
	(segment
		(start 100.6602 -26.188416)
		(end 100.6602 -26.718514)
		(width 0.1016)
		(layer "F.Cu")
		(net "M_B_DQ21")
	)
	(segment
		(start 99.2378 -22.6822)
		(end 99.2378 -22.7076)
		(width 0.1016)
		(layer "F.Cu")
		(net "M_B_DQ21")
	)
	(segment
		(start 100.573332 -25.627584)
		(end 100.736908 -25.79116)
		(width 0.1016)
		(layer "F.Cu")
		(net "M_B_DQ21")
	)
	(segment
		(start 100.6602 -26.718514)
		(end 100.711508 -26.769822)
		(width 0.1016)
		(layer "F.Cu")
		(net "M_B_DQ21")
	)
	(segment
		(start 99.6696 -23.1394)
		(end 99.6696 -25.3746)
		(width 0.1016)
		(layer "F.Cu")
		(net "M_B_DQ21")
	)
	(segment
		(start 100.736908 -26.111708)
		(end 100.6602 -26.188416)
		(width 0.1016)
		(layer "F.Cu")
		(net "M_B_DQ21")
	)
	(segment
		(start 100.711508 -27.050492)
		(end 100.457508 -27.304492)
		(width 0.1016)
		(layer "F.Cu")
		(net "M_B_DQ21")
	)
	(segment
		(start 139.750038 -1.68402)
		(end 139.750038 -2.614676)
		(width 0.1778)
		(layer "F.Cu")
		(net "M_B_DQ21")
	)
	(segment
		(start 99.922584 -25.627584)
		(end 100.573332 -25.627584)
		(width 0.1016)
		(layer "F.Cu")
		(net "M_B_DQ21")
	)
	(segment
		(start 100.736908 -25.79116)
		(end 100.736908 -26.111708)
		(width 0.1016)
		(layer "F.Cu")
		(net "M_B_DQ21")
	)
	(segment
		(start 100.457508 -27.304492)
		(end 100.457508 -27.658314)
		(width 0.1016)
		(layer "F.Cu")
		(net "M_B_DQ21")
	)
	(segment
		(start 140.1826 -3.047238)
		(end 140.1826 -3.532378)
		(width 0.1778)
		(layer "F.Cu")
		(net "M_B_DQ21")
	)
	(via
		(at 99.2378 -22.6822)
		(size 0.4318)
		(drill 0.2032)
		(layers "F.Cu" "B.Cu")
		(net "M_B_DQ21")
	)
	(via
		(at 140.4112 -3.760978)
		(size 0.4318)
		(drill 0.2032)
		(layers "F.Cu" "B.Cu")
		(net "M_B_DQ21")
	)
	(segment
		(start 140.21308 -2.915158)
		(end 140.21308 -3.562858)
		(width 0.1778)
		(layer "B.Cu")
		(net "M_B_DQ21")
	)
	(segment
		(start 140.21308 -3.562858)
		(end 140.4112 -3.760978)
		(width 0.1778)
		(layer "B.Cu")
		(net "M_B_DQ21")
	)
	(segment
		(start 140.64996 -2.478278)
		(end 140.21308 -2.915158)
		(width 0.1778)
		(layer "B.Cu")
		(net "M_B_DQ21")
	)
	(segment
		(start 140.64996 -1.690624)
		(end 140.64996 -2.478278)
		(width 0.1778)
		(layer "B.Cu")
		(net "M_B_DQ21")
	)
	(segment
		(start 137.805922 -7.126478)
		(end 132.5245 -7.126478)
		(width 0.1524)
		(layer "In4.Cu")
		(net "M_B_DQ21")
	)
	(segment
		(start 124.8664 -10.5918)
		(end 124.1298 -9.8552)
		(width 0.1524)
		(layer "In4.Cu")
		(net "M_B_DQ21")
	)
	(segment
		(start 99.2124 -19.647154)
		(end 99.2124 -22.6568)
		(width 0.1016)
		(layer "In4.Cu")
		(net "M_B_DQ21")
	)
	(segment
		(start 103.390954 -15.4686)
		(end 99.2124 -19.647154)
		(width 0.1524)
		(layer "In4.Cu")
		(net "M_B_DQ21")
	)
	(segment
		(start 132.5245 -7.126478)
		(end 129.059178 -10.5918)
		(width 0.1524)
		(layer "In4.Cu")
		(net "M_B_DQ21")
	)
	(segment
		(start 99.2124 -22.6568)
		(end 99.2378 -22.6822)
		(width 0.1016)
		(layer "In4.Cu")
		(net "M_B_DQ21")
	)
	(segment
		(start 114.599466 -9.8552)
		(end 108.986066 -15.4686)
		(width 0.1524)
		(layer "In4.Cu")
		(net "M_B_DQ21")
	)
	(segment
		(start 108.986066 -15.4686)
		(end 103.390954 -15.4686)
		(width 0.1524)
		(layer "In4.Cu")
		(net "M_B_DQ21")
	)
	(segment
		(start 124.1298 -9.8552)
		(end 114.599466 -9.8552)
		(width 0.1524)
		(layer "In4.Cu")
		(net "M_B_DQ21")
	)
	(segment
		(start 140.4112 -3.760978)
		(end 140.4112 -4.5212)
		(width 0.1524)
		(layer "In4.Cu")
		(net "M_B_DQ21")
	)
	(segment
		(start 140.4112 -4.5212)
		(end 137.805922 -7.126478)
		(width 0.1524)
		(layer "In4.Cu")
		(net "M_B_DQ21")
	)
	(segment
		(start 129.059178 -10.5918)
		(end 124.8664 -10.5918)
		(width 0.1524)
		(layer "In4.Cu")
		(net "M_B_DQ21")
	)
	(segment
		(start 191.04991 -8.722868)
		(end 191.2747 -8.498078)
		(width 0.1143)
		(layer "F.Cu")
		(net "SMB_M_B1_R_CLK")
	)
	(segment
		(start 194.917568 -10.199878)
		(end 198.291704 -10.199878)
		(width 0.1143)
		(layer "F.Cu")
		(net "SMB_M_B1_R_CLK")
	)
	(segment
		(start 193.215768 -8.498078)
		(end 194.917568 -10.199878)
		(width 0.1143)
		(layer "F.Cu")
		(net "SMB_M_B1_R_CLK")
	)
	(segment
		(start 191.04991 -9.897364)
		(end 191.04991 -8.722868)
		(width 0.1143)
		(layer "F.Cu")
		(net "SMB_M_B1_R_CLK")
	)
	(segment
		(start 191.2747 -8.498078)
		(end 193.215768 -8.498078)
		(width 0.1143)
		(layer "F.Cu")
		(net "SMB_M_B1_R_CLK")
	)
	(segment
		(start 198.755 -9.736582)
		(end 198.755 -9.704578)
		(width 0.1143)
		(layer "F.Cu")
		(net "SMB_M_B1_R_CLK")
	)
	(segment
		(start 198.291704 -10.199878)
		(end 198.755 -9.736582)
		(width 0.1143)
		(layer "F.Cu")
		(net "SMB_M_B1_R_CLK")
	)
	(segment
		(start 186.9694 -37.7825)
		(end 186.436 -38.3159)
		(width 0.2032)
		(layer "F.Cu")
		(net "VR_PVDDR_A_SVID_ADDR")
	)
	(segment
		(start 184.912 -39.4462)
		(end 184.912 -39.381176)
		(width 0.2032)
		(layer "F.Cu")
		(net "VR_PVDDR_A_SVID_ADDR")
	)
	(segment
		(start 186.3344 -38.4175)
		(end 186.436 -38.3159)
		(width 0.2032)
		(layer "F.Cu")
		(net "VR_PVDDR_A_SVID_ADDR")
	)
	(segment
		(start 186.9694 -37.466016)
		(end 186.9694 -37.7825)
		(width 0.2032)
		(layer "F.Cu")
		(net "VR_PVDDR_A_SVID_ADDR")
	)
	(segment
		(start 184.912 -39.381176)
		(end 185.875676 -38.4175)
		(width 0.2032)
		(layer "F.Cu")
		(net "VR_PVDDR_A_SVID_ADDR")
	)
	(segment
		(start 187.456318 -36.376102)
		(end 187.456318 -36.979098)
		(width 0.2032)
		(layer "F.Cu")
		(net "VR_PVDDR_A_SVID_ADDR")
	)
	(segment
		(start 187.456318 -36.979098)
		(end 186.9694 -37.466016)
		(width 0.2032)
		(layer "F.Cu")
		(net "VR_PVDDR_A_SVID_ADDR")
	)
	(segment
		(start 185.875676 -38.4175)
		(end 186.3344 -38.4175)
		(width 0.2032)
		(layer "F.Cu")
		(net "VR_PVDDR_A_SVID_ADDR")
	)
	(via
		(at 186.436 -38.3159)
		(size 0.7112)
		(drill 0.3556)
		(layers "F.Cu" "B.Cu")
		(net "VR_PVDDR_A_SVID_ADDR")
	)
	(segment
		(start 111.8616 -57.7088)
		(end 112.0648 -57.912)
		(width 0.1143)
		(layer "F.Cu")
		(net "M_A_MON2_N")
	)
	(segment
		(start 110.710218 -51.124104)
		(end 111.148368 -50.685954)
		(width 0.1143)
		(layer "F.Cu")
		(net "M_A_MON2_N")
	)
	(segment
		(start 111.8616 -56.896)
		(end 111.8616 -53.644546)
		(width 0.1143)
		(layer "F.Cu")
		(net "M_A_MON2_N")
	)
	(segment
		(start 111.8616 -56.896)
		(end 111.8616 -57.7088)
		(width 0.1143)
		(layer "F.Cu")
		(net "M_A_MON2_N")
	)
	(segment
		(start 110.710218 -52.493164)
		(end 110.710218 -51.124104)
		(width 0.1143)
		(layer "F.Cu")
		(net "M_A_MON2_N")
	)
	(segment
		(start 112.292384 -58.944002)
		(end 112.292384 -58.139584)
		(width 0.1143)
		(layer "F.Cu")
		(net "M_A_MON2_N")
	)
	(segment
		(start 111.8616 -53.644546)
		(end 110.710218 -52.493164)
		(width 0.1143)
		(layer "F.Cu")
		(net "M_A_MON2_N")
	)
	(segment
		(start 112.292384 -58.139584)
		(end 112.0648 -57.912)
		(width 0.1143)
		(layer "F.Cu")
		(net "M_A_MON2_N")
	)
	(via
		(at 111.8616 -56.896)
		(size 0.7112)
		(drill 0.3556)
		(layers "F.Cu" "B.Cu")
		(net "M_A_MON2_N")
	)
	(segment
		(start 50.57775 -19.58975)
		(end 49.784 -19.58975)
		(width 0.1143)
		(layer "F.Cu")
		(net "SO_GBE")
	)
	(segment
		(start 51.7779 -20.2946)
		(end 51.2826 -20.2946)
		(width 0.1143)
		(layer "F.Cu")
		(net "SO_GBE")
	)
	(segment
		(start 48.26 -20.5232)
		(end 49.19345 -19.58975)
		(width 0.1143)
		(layer "F.Cu")
		(net "SO_GBE")
	)
	(segment
		(start 49.19345 -19.58975)
		(end 49.784 -19.58975)
		(width 0.1143)
		(layer "F.Cu")
		(net "SO_GBE")
	)
	(segment
		(start 51.2826 -20.2946)
		(end 50.57775 -19.58975)
		(width 0.1143)
		(layer "F.Cu")
		(net "SO_GBE")
	)
	(via
		(at 49.784 -19.58975)
		(size 0.7112)
		(drill 0.3556)
		(layers "F.Cu" "B.Cu")
		(net "SO_GBE")
	)
	(segment
		(start 183.642 -28.6258)
		(end 183.388 -28.8798)
		(width 0.2032)
		(layer "F.Cu")
		(net "VR_PVDDR_A_FB_COMP")
	)
	(segment
		(start 184.2008 -29.591)
		(end 184.2008 -28.829)
		(width 0.2032)
		(layer "F.Cu")
		(net "VR_PVDDR_A_FB_COMP")
	)
	(segment
		(start 184.2008 -28.829)
		(end 183.9976 -28.6258)
		(width 0.2032)
		(layer "F.Cu")
		(net "VR_PVDDR_A_FB_COMP")
	)
	(segment
		(start 183.9976 -28.6258)
		(end 183.642 -28.6258)
		(width 0.2032)
		(layer "F.Cu")
		(net "VR_PVDDR_A_FB_COMP")
	)
	(segment
		(start 183.388 -28.8798)
		(end 183.388 -29.5656)
		(width 0.2032)
		(layer "F.Cu")
		(net "VR_PVDDR_A_FB_COMP")
	)
	(via
		(at 183.9976 -28.6258)
		(size 0.7112)
		(drill 0.3556)
		(layers "F.Cu" "B.Cu")
		(net "VR_PVDDR_A_FB_COMP")
	)
	(segment
		(start 98.4758 -47.919132)
		(end 98.928936 -48.372268)
		(width 0.1778)
		(layer "F.Cu")
		(net "M_A_VREF")
	)
	(segment
		(start 98.4758 -45.8978)
		(end 98.4758 -47.919132)
		(width 0.1778)
		(layer "F.Cu")
		(net "M_A_VREF")
	)
	(segment
		(start 98.067368 -45.354494)
		(end 98.067368 -45.489368)
		(width 0.1778)
		(layer "F.Cu")
		(net "M_A_VREF")
	)
	(segment
		(start 98.067368 -45.489368)
		(end 98.4758 -45.8978)
		(width 0.1778)
		(layer "F.Cu")
		(net "M_A_VREF")
	)
	(via
		(at 98.928936 -48.372268)
		(size 0.4318)
		(drill 0.2032)
		(layers "F.Cu" "B.Cu")
		(net "M_A_VREF")
	)
	(via
		(at 99.6442 -51.562)
		(size 0.7112)
		(drill 0.3556)
		(layers "F.Cu" "B.Cu")
		(net "M_A_VREF")
	)
	(segment
		(start 99.6442 -51.562)
		(end 99.6442 -52.4256)
		(width 0.1778)
		(layer "B.Cu")
		(net "M_A_VREF")
	)
	(segment
		(start 99.3648 -52.705)
		(end 99.3902 -52.7304)
		(width 0.1778)
		(layer "B.Cu")
		(net "M_A_VREF")
	)
	(segment
		(start 99.86518 -51.34102)
		(end 99.6442 -51.562)
		(width 0.1778)
		(layer "B.Cu")
		(net "M_A_VREF")
	)
	(segment
		(start 98.928936 -48.372268)
		(end 99.3394 -48.782732)
		(width 0.1778)
		(layer "B.Cu")
		(net "M_A_VREF")
	)
	(segment
		(start 99.6442 -52.4256)
		(end 99.3648 -52.705)
		(width 0.1778)
		(layer "B.Cu")
		(net "M_A_VREF")
	)
	(segment
		(start 99.86518 -50.064162)
		(end 99.86518 -51.34102)
		(width 0.1778)
		(layer "B.Cu")
		(net "M_A_VREF")
	)
	(segment
		(start 99.3902 -52.7304)
		(end 99.3902 -53.467)
		(width 0.1778)
		(layer "B.Cu")
		(net "M_A_VREF")
	)
	(segment
		(start 99.3394 -48.782732)
		(end 99.3394 -49.538382)
		(width 0.1778)
		(layer "B.Cu")
		(net "M_A_VREF")
	)
	(segment
		(start 99.3394 -49.538382)
		(end 99.86518 -50.064162)
		(width 0.1778)
		(layer "B.Cu")
		(net "M_A_VREF")
	)
	(segment
		(start 131.191 -9.01192)
		(end 131.191 -6.076442)
		(width 0.1778)
		(layer "F.Cu")
		(net "M_B_DQS_DN0")
	)
	(segment
		(start 91.7448 -22.9108)
		(end 92.185236 -23.351236)
		(width 0.1016)
		(layer "F.Cu")
		(net "M_B_DQS_DN0")
	)
	(segment
		(start 93.08846 -25.424384)
		(end 93.746828 -26.082752)
		(width 0.1016)
		(layer "F.Cu")
		(net "M_B_DQS_DN0")
	)
	(segment
		(start 93.848428 -26.6446)
		(end 94.082362 -26.6446)
		(width 0.1016)
		(layer "F.Cu")
		(net "M_B_DQS_DN0")
	)
	(segment
		(start 131.05003 -9.897364)
		(end 131.05003 -9.15289)
		(width 0.1778)
		(layer "F.Cu")
		(net "M_B_DQS_DN0")
	)
	(segment
		(start 131.191 -6.076442)
		(end 130.932936 -5.818378)
		(width 0.1778)
		(layer "F.Cu")
		(net "M_B_DQS_DN0")
	)
	(segment
		(start 94.082362 -26.6446)
		(end 94.165928 -26.561034)
		(width 0.1016)
		(layer "F.Cu")
		(net "M_B_DQS_DN0")
	)
	(segment
		(start 92.185236 -25.054052)
		(end 92.555568 -25.424384)
		(width 0.1016)
		(layer "F.Cu")
		(net "M_B_DQS_DN0")
	)
	(segment
		(start 92.555568 -25.424384)
		(end 93.08846 -25.424384)
		(width 0.1016)
		(layer "F.Cu")
		(net "M_B_DQS_DN0")
	)
	(segment
		(start 93.746828 -26.543)
		(end 93.848428 -26.6446)
		(width 0.1016)
		(layer "F.Cu")
		(net "M_B_DQS_DN0")
	)
	(segment
		(start 93.746828 -26.082752)
		(end 93.746828 -26.543)
		(width 0.1016)
		(layer "F.Cu")
		(net "M_B_DQS_DN0")
	)
	(segment
		(start 131.05003 -9.15289)
		(end 131.191 -9.01192)
		(width 0.1778)
		(layer "F.Cu")
		(net "M_B_DQS_DN0")
	)
	(segment
		(start 92.185236 -23.351236)
		(end 92.185236 -25.054052)
		(width 0.1016)
		(layer "F.Cu")
		(net "M_B_DQS_DN0")
	)
	(via
		(at 91.7448 -22.9108)
		(size 0.4318)
		(drill 0.2032)
		(layers "F.Cu" "B.Cu")
		(net "M_B_DQS_DN0")
	)
	(via
		(at 130.932936 -5.818378)
		(size 0.4318)
		(drill 0.2032)
		(layers "F.Cu" "B.Cu")
		(net "M_B_DQS_DN0")
	)
	(segment
		(start 131.05003 -2.451608)
		(end 131.197604 -2.599182)
		(width 0.1778)
		(layer "B.Cu")
		(net "M_B_DQS_DN0")
	)
	(segment
		(start 131.197604 -5.55371)
		(end 130.932936 -5.818378)
		(width 0.1778)
		(layer "B.Cu")
		(net "M_B_DQS_DN0")
	)
	(segment
		(start 131.05003 -1.690624)
		(end 131.05003 -2.451608)
		(width 0.1778)
		(layer "B.Cu")
		(net "M_B_DQS_DN0")
	)
	(segment
		(start 131.197604 -2.599182)
		(end 131.197604 -5.55371)
		(width 0.1778)
		(layer "B.Cu")
		(net "M_B_DQS_DN0")
	)
	(segment
		(start 124.87021 -8.850376)
		(end 125.186186 -8.5344)
		(width 0.1524)
		(layer "In7.Cu")
		(net "M_B_DQS_DN0")
	)
	(segment
		(start 130.72237 -6.86943)
		(end 131.210304 -6.381496)
		(width 0.1524)
		(layer "In7.Cu")
		(net "M_B_DQS_DN0")
	)
	(segment
		(start 126.976378 -8.518398)
		(end 127.522224 -8.518398)
		(width 0.1524)
		(layer "In7.Cu")
		(net "M_B_DQS_DN0")
	)
	(segment
		(start 126.0602 -9.6012)
		(end 126.1872 -9.7282)
		(width 0.1524)
		(layer "In7.Cu")
		(net "M_B_DQS_DN0")
	)
	(segment
		(start 126.0602 -8.850376)
		(end 126.0602 -9.6012)
		(width 0.1524)
		(layer "In7.Cu")
		(net "M_B_DQS_DN0")
	)
	(segment
		(start 130.72237 -9.166606)
		(end 130.72237 -6.86943)
		(width 0.1524)
		(layer "In7.Cu")
		(net "M_B_DQS_DN0")
	)
	(segment
		(start 121.8184 -8.5852)
		(end 121.9708 -8.7376)
		(width 0.1524)
		(layer "In7.Cu")
		(net "M_B_DQS_DN0")
	)
	(segment
		(start 121.502424 -7.5184)
		(end 121.8184 -7.834376)
		(width 0.1524)
		(layer "In7.Cu")
		(net "M_B_DQS_DN0")
	)
	(segment
		(start 118.65229 -8.7376)
		(end 119.10949 -8.7376)
		(width 0.1524)
		(layer "In7.Cu")
		(net "M_B_DQS_DN0")
	)
	(segment
		(start 130.059176 -9.8298)
		(end 130.72237 -9.166606)
		(width 0.1524)
		(layer "In7.Cu")
		(net "M_B_DQS_DN0")
	)
	(segment
		(start 115.276376 -8.7376)
		(end 116.78285 -8.7376)
		(width 0.1524)
		(layer "In7.Cu")
		(net "M_B_DQS_DN0")
	)
	(segment
		(start 91.9734 -22.6822)
		(end 91.7448 -22.9108)
		(width 0.1016)
		(layer "In7.Cu")
		(net "M_B_DQS_DN0")
	)
	(segment
		(start 118.07063 -8.61314)
		(end 118.52783 -8.61314)
		(width 0.1524)
		(layer "In7.Cu")
		(net "M_B_DQS_DN0")
	)
	(segment
		(start 121.8184 -7.834376)
		(end 121.8184 -8.5852)
		(width 0.1524)
		(layer "In7.Cu")
		(net "M_B_DQS_DN0")
	)
	(segment
		(start 120.4976 -8.7376)
		(end 120.65 -8.5852)
		(width 0.1524)
		(layer "In7.Cu")
		(net "M_B_DQS_DN0")
	)
	(segment
		(start 125.744224 -8.5344)
		(end 126.0602 -8.850376)
		(width 0.1524)
		(layer "In7.Cu")
		(net "M_B_DQS_DN0")
	)
	(segment
		(start 113.693448 -9.8298)
		(end 114.184176 -9.8298)
		(width 0.1524)
		(layer "In7.Cu")
		(net "M_B_DQS_DN0")
	)
	(segment
		(start 119.81561 -8.7376)
		(end 120.4976 -8.7376)
		(width 0.1524)
		(layer "In7.Cu")
		(net "M_B_DQS_DN0")
	)
	(segment
		(start 94.902528 -19.944588)
		(end 97.93986 -16.907256)
		(width 0.1524)
		(layer "In7.Cu")
		(net "M_B_DQS_DN0")
	)
	(segment
		(start 126.5174 -9.7282)
		(end 126.6698 -9.5758)
		(width 0.1524)
		(layer "In7.Cu")
		(net "M_B_DQS_DN0")
	)
	(segment
		(start 126.6698 -9.5758)
		(end 126.6698 -8.824976)
		(width 0.1524)
		(layer "In7.Cu")
		(net "M_B_DQS_DN0")
	)
	(segment
		(start 127.522224 -8.518398)
		(end 127.8382 -8.834374)
		(width 0.1524)
		(layer "In7.Cu")
		(net "M_B_DQS_DN0")
	)
	(segment
		(start 117.48897 -8.7376)
		(end 117.94617 -8.7376)
		(width 0.1524)
		(layer "In7.Cu")
		(net "M_B_DQS_DN0")
	)
	(segment
		(start 93.814646 -20.015454)
		(end 93.814392 -20.0152)
		(width 0.1016)
		(layer "In7.Cu")
		(net "M_B_DQS_DN0")
	)
	(segment
		(start 121.9708 -8.7376)
		(end 123.919234 -8.7376)
		(width 0.1524)
		(layer "In7.Cu")
		(net "M_B_DQS_DN0")
	)
	(segment
		(start 117.94617 -8.7376)
		(end 118.07063 -8.61314)
		(width 0.1524)
		(layer "In7.Cu")
		(net "M_B_DQS_DN0")
	)
	(segment
		(start 123.919234 -8.7376)
		(end 124.23521 -9.053576)
		(width 0.1524)
		(layer "In7.Cu")
		(net "M_B_DQS_DN0")
	)
	(segment
		(start 114.971576 -9.0424)
		(end 115.276376 -8.7376)
		(width 0.1524)
		(layer "In7.Cu")
		(net "M_B_DQS_DN0")
	)
	(segment
		(start 93.814392 -20.0152)
		(end 93.561916 -20.0152)
		(width 0.1016)
		(layer "In7.Cu")
		(net "M_B_DQS_DN0")
	)
	(segment
		(start 127.8382 -9.7536)
		(end 127.9144 -9.8298)
		(width 0.1524)
		(layer "In7.Cu")
		(net "M_B_DQS_DN0")
	)
	(segment
		(start 114.483388 -9.530588)
		(end 114.483388 -9.290812)
		(width 0.1524)
		(layer "In7.Cu")
		(net "M_B_DQS_DN0")
	)
	(segment
		(start 120.65 -7.834376)
		(end 120.965976 -7.5184)
		(width 0.1524)
		(layer "In7.Cu")
		(net "M_B_DQS_DN0")
	)
	(segment
		(start 124.38761 -9.779)
		(end 124.71781 -9.779)
		(width 0.1524)
		(layer "In7.Cu")
		(net "M_B_DQS_DN0")
	)
	(segment
		(start 127.9144 -9.8298)
		(end 128.1176 -9.8298)
		(width 0.1524)
		(layer "In7.Cu")
		(net "M_B_DQS_DN0")
	)
	(segment
		(start 119.69115 -8.61314)
		(end 119.81561 -8.7376)
		(width 0.1524)
		(layer "In7.Cu")
		(net "M_B_DQS_DN0")
	)
	(segment
		(start 124.23521 -9.053576)
		(end 124.23521 -9.6266)
		(width 0.1524)
		(layer "In7.Cu")
		(net "M_B_DQS_DN0")
	)
	(segment
		(start 128.24206 -9.70534)
		(end 128.69926 -9.70534)
		(width 0.1524)
		(layer "In7.Cu")
		(net "M_B_DQS_DN0")
	)
	(segment
		(start 116.90731 -8.61314)
		(end 117.36451 -8.61314)
		(width 0.1524)
		(layer "In7.Cu")
		(net "M_B_DQS_DN0")
	)
	(segment
		(start 94.902528 -19.944588)
		(end 94.831662 -20.015454)
		(width 0.1016)
		(layer "In7.Cu")
		(net "M_B_DQS_DN0")
	)
	(segment
		(start 128.1176 -9.8298)
		(end 128.24206 -9.70534)
		(width 0.1524)
		(layer "In7.Cu")
		(net "M_B_DQS_DN0")
	)
	(segment
		(start 116.78285 -8.7376)
		(end 116.90731 -8.61314)
		(width 0.1524)
		(layer "In7.Cu")
		(net "M_B_DQS_DN0")
	)
	(segment
		(start 120.965976 -7.5184)
		(end 121.502424 -7.5184)
		(width 0.1524)
		(layer "In7.Cu")
		(net "M_B_DQS_DN0")
	)
	(segment
		(start 131.210304 -6.381496)
		(end 131.210304 -6.095746)
		(width 0.1524)
		(layer "In7.Cu")
		(net "M_B_DQS_DN0")
	)
	(segment
		(start 126.6698 -8.824976)
		(end 126.976378 -8.518398)
		(width 0.1524)
		(layer "In7.Cu")
		(net "M_B_DQS_DN0")
	)
	(segment
		(start 125.186186 -8.5344)
		(end 125.744224 -8.5344)
		(width 0.1524)
		(layer "In7.Cu")
		(net "M_B_DQS_DN0")
	)
	(segment
		(start 114.483388 -9.290812)
		(end 114.7318 -9.0424)
		(width 0.1524)
		(layer "In7.Cu")
		(net "M_B_DQS_DN0")
	)
	(segment
		(start 114.7318 -9.0424)
		(end 114.971576 -9.0424)
		(width 0.1524)
		(layer "In7.Cu")
		(net "M_B_DQS_DN0")
	)
	(segment
		(start 126.1872 -9.7282)
		(end 126.5174 -9.7282)
		(width 0.1524)
		(layer "In7.Cu")
		(net "M_B_DQS_DN0")
	)
	(segment
		(start 124.23521 -9.6266)
		(end 124.38761 -9.779)
		(width 0.1524)
		(layer "In7.Cu")
		(net "M_B_DQS_DN0")
	)
	(segment
		(start 94.831662 -20.015454)
		(end 93.814646 -20.015454)
		(width 0.1016)
		(layer "In7.Cu")
		(net "M_B_DQS_DN0")
	)
	(segment
		(start 131.210304 -6.095746)
		(end 130.932936 -5.818378)
		(width 0.1524)
		(layer "In7.Cu")
		(net "M_B_DQS_DN0")
	)
	(segment
		(start 117.36451 -8.61314)
		(end 117.48897 -8.7376)
		(width 0.1524)
		(layer "In7.Cu")
		(net "M_B_DQS_DN0")
	)
	(segment
		(start 120.65 -8.5852)
		(end 120.65 -7.834376)
		(width 0.1524)
		(layer "In7.Cu")
		(net "M_B_DQS_DN0")
	)
	(segment
		(start 114.184176 -9.8298)
		(end 114.483388 -9.530588)
		(width 0.1524)
		(layer "In7.Cu")
		(net "M_B_DQS_DN0")
	)
	(segment
		(start 128.82372 -9.8298)
		(end 130.059176 -9.8298)
		(width 0.1524)
		(layer "In7.Cu")
		(net "M_B_DQS_DN0")
	)
	(segment
		(start 106.615992 -16.907256)
		(end 113.693448 -9.8298)
		(width 0.1524)
		(layer "In7.Cu")
		(net "M_B_DQS_DN0")
	)
	(segment
		(start 124.87021 -9.6266)
		(end 124.87021 -8.850376)
		(width 0.1524)
		(layer "In7.Cu")
		(net "M_B_DQS_DN0")
	)
	(segment
		(start 119.23395 -8.61314)
		(end 119.69115 -8.61314)
		(width 0.1524)
		(layer "In7.Cu")
		(net "M_B_DQS_DN0")
	)
	(segment
		(start 124.71781 -9.779)
		(end 124.87021 -9.6266)
		(width 0.1524)
		(layer "In7.Cu")
		(net "M_B_DQS_DN0")
	)
	(segment
		(start 97.93986 -16.907256)
		(end 106.615992 -16.907256)
		(width 0.1524)
		(layer "In7.Cu")
		(net "M_B_DQS_DN0")
	)
	(segment
		(start 127.8382 -8.834374)
		(end 127.8382 -9.7536)
		(width 0.1524)
		(layer "In7.Cu")
		(net "M_B_DQS_DN0")
	)
	(segment
		(start 93.561916 -20.0152)
		(end 91.9734 -21.603716)
		(width 0.1016)
		(layer "In7.Cu")
		(net "M_B_DQS_DN0")
	)
	(segment
		(start 119.10949 -8.7376)
		(end 119.23395 -8.61314)
		(width 0.1524)
		(layer "In7.Cu")
		(net "M_B_DQS_DN0")
	)
	(segment
		(start 118.52783 -8.61314)
		(end 118.65229 -8.7376)
		(width 0.1524)
		(layer "In7.Cu")
		(net "M_B_DQS_DN0")
	)
	(segment
		(start 91.9734 -21.603716)
		(end 91.9734 -22.6822)
		(width 0.1016)
		(layer "In7.Cu")
		(net "M_B_DQS_DN0")
	)
	(segment
		(start 128.69926 -9.70534)
		(end 128.82372 -9.8298)
		(width 0.1524)
		(layer "In7.Cu")
		(net "M_B_DQS_DN0")
	)
	(segment
		(start 99.022408 -46.065694)
		(end 99.022408 -47.535592)
		(width 0.1524)
		(layer "F.Cu")
		(net "M_A_CMDPU")
	)
	(segment
		(start 99.022408 -47.535592)
		(end 98.8822 -47.6758)
		(width 0.1524)
		(layer "F.Cu")
		(net "M_A_CMDPU")
	)
	(segment
		(start 99.352608 -45.735494)
		(end 99.022408 -46.065694)
		(width 0.1524)
		(layer "F.Cu")
		(net "M_A_CMDPU")
	)
	(via
		(at 98.92792 -50.04816)
		(size 0.7112)
		(drill 0.3556)
		(layers "F.Cu" "B.Cu")
		(net "M_A_CMDPU")
	)
	(via
		(at 98.8822 -47.6758)
		(size 0.4318)
		(drill 0.2032)
		(layers "F.Cu" "B.Cu")
		(net "M_A_CMDPU")
	)
	(segment
		(start 98.522536 -48.203866)
		(end 98.8822 -47.844202)
		(width 0.1778)
		(layer "B.Cu")
		(net "M_A_CMDPU")
	)
	(segment
		(start 98.98634 -50.10658)
		(end 98.92792 -50.04816)
		(width 0.1778)
		(layer "B.Cu")
		(net "M_A_CMDPU")
	)
	(segment
		(start 98.98634 -50.69586)
		(end 98.98634 -50.10658)
		(width 0.1778)
		(layer "B.Cu")
		(net "M_A_CMDPU")
	)
	(segment
		(start 98.522536 -49.642776)
		(end 98.522536 -48.203866)
		(width 0.1778)
		(layer "B.Cu")
		(net "M_A_CMDPU")
	)
	(segment
		(start 98.8822 -47.844202)
		(end 98.8822 -47.6758)
		(width 0.1778)
		(layer "B.Cu")
		(net "M_A_CMDPU")
	)
	(segment
		(start 98.679 -51.0032)
		(end 98.98634 -50.69586)
		(width 0.1778)
		(layer "B.Cu")
		(net "M_A_CMDPU")
	)
	(segment
		(start 98.92792 -50.04816)
		(end 98.522536 -49.642776)
		(width 0.1778)
		(layer "B.Cu")
		(net "M_A_CMDPU")
	)
	(segment
		(start 103.8352 -37.338)
		(end 104.190546 -36.982654)
		(width 0.1016)
		(layer "F.Cu")
		(net "M_B_DQ59")
	)
	(segment
		(start 104.190546 -36.982654)
		(end 104.242108 -36.982654)
		(width 0.1016)
		(layer "F.Cu")
		(net "M_B_DQ59")
	)
	(segment
		(start 188.649864 -9.897364)
		(end 188.649864 -8.540242)
		(width 0.1778)
		(layer "F.Cu")
		(net "M_B_DQ59")
	)
	(segment
		(start 188.649864 -8.540242)
		(end 188.4934 -8.383778)
		(width 0.1778)
		(layer "F.Cu")
		(net "M_B_DQ59")
	)
	(via
		(at 103.8352 -37.338)
		(size 0.4318)
		(drill 0.2032)
		(layers "F.Cu" "B.Cu")
		(net "M_B_DQ59")
	)
	(via
		(at 188.4934 -8.383778)
		(size 0.4318)
		(drill 0.2032)
		(layers "F.Cu" "B.Cu")
		(net "M_B_DQ59")
	)
	(segment
		(start 188.34989 -8.527288)
		(end 188.4934 -8.383778)
		(width 0.1778)
		(layer "B.Cu")
		(net "M_B_DQ59")
	)
	(segment
		(start 188.34989 -9.89076)
		(end 188.34989 -8.527288)
		(width 0.1778)
		(layer "B.Cu")
		(net "M_B_DQ59")
	)
	(segment
		(start 106.0196 -38.9636)
		(end 105.6386 -38.8112)
		(width 0.1016)
		(layer "In2.Cu")
		(net "M_B_DQ59")
	)
	(segment
		(start 158.320486 -39.7256)
		(end 113.3856 -39.7256)
		(width 0.1524)
		(layer "In2.Cu")
		(net "M_B_DQ59")
	)
	(segment
		(start 107.1626 -39.7256)
		(end 106.426 -39.37)
		(width 0.1016)
		(layer "In2.Cu")
		(net "M_B_DQ59")
	)
	(segment
		(start 183.6928 -14.5034)
		(end 166.548816 -31.49727)
		(width 0.1524)
		(layer "In2.Cu")
		(net "M_B_DQ59")
	)
	(segment
		(start 105.6386 -38.8112)
		(end 105.0925 -38.5953)
		(width 0.1016)
		(layer "In2.Cu")
		(net "M_B_DQ59")
	)
	(segment
		(start 106.426 -39.37)
		(end 106.0196 -38.9636)
		(width 0.1016)
		(layer "In2.Cu")
		(net "M_B_DQ59")
	)
	(segment
		(start 188.4934 -8.383778)
		(end 188.4934 -10.2616)
		(width 0.1524)
		(layer "In2.Cu")
		(net "M_B_DQ59")
	)
	(segment
		(start 188.4934 -10.2616)
		(end 184.2516 -14.5034)
		(width 0.1524)
		(layer "In2.Cu")
		(net "M_B_DQ59")
	)
	(segment
		(start 105.0925 -38.5953)
		(end 103.8352 -37.338)
		(width 0.1016)
		(layer "In2.Cu")
		(net "M_B_DQ59")
	)
	(segment
		(start 166.548816 -31.49727)
		(end 158.320486 -39.7256)
		(width 0.1524)
		(layer "In2.Cu")
		(net "M_B_DQ59")
	)
	(segment
		(start 184.2516 -14.5034)
		(end 183.6928 -14.5034)
		(width 0.1524)
		(layer "In2.Cu")
		(net "M_B_DQ59")
	)
	(segment
		(start 113.3856 -39.7256)
		(end 107.1626 -39.7256)
		(width 0.1016)
		(layer "In2.Cu")
		(net "M_B_DQ59")
	)
	(segment
		(start 183.3626 -31.2928)
		(end 183.388 -31.2674)
		(width 0.2032)
		(layer "F.Cu")
		(net "VR_PVDDR_A_COMP")
	)
	(segment
		(start 182.4736 -29.5656)
		(end 182.4736 -28.6512)
		(width 0.2032)
		(layer "F.Cu")
		(net "VR_PVDDR_A_COMP")
	)
	(segment
		(start 182.5498 -31.2928)
		(end 183.3118 -31.2928)
		(width 0.2032)
		(layer "F.Cu")
		(net "VR_PVDDR_A_COMP")
	)
	(segment
		(start 185.252868 -31.17342)
		(end 184.21858 -31.17342)
		(width 0.2032)
		(layer "F.Cu")
		(net "VR_PVDDR_A_COMP")
	)
	(segment
		(start 184.1246 -31.2674)
		(end 184.0738 -31.2674)
		(width 0.2032)
		(layer "F.Cu")
		(net "VR_PVDDR_A_COMP")
	)
	(segment
		(start 184.21858 -31.17342)
		(end 184.1246 -31.2674)
		(width 0.2032)
		(layer "F.Cu")
		(net "VR_PVDDR_A_COMP")
	)
	(segment
		(start 182.4736 -30.4038)
		(end 182.4736 -29.5656)
		(width 0.2032)
		(layer "F.Cu")
		(net "VR_PVDDR_A_COMP")
	)
	(segment
		(start 183.388 -31.2674)
		(end 184.0738 -31.2674)
		(width 0.2032)
		(layer "F.Cu")
		(net "VR_PVDDR_A_COMP")
	)
	(segment
		(start 183.3118 -31.2928)
		(end 183.3626 -31.2928)
		(width 0.2032)
		(layer "F.Cu")
		(net "VR_PVDDR_A_COMP")
	)
	(segment
		(start 186.856116 -32.175704)
		(end 186.43981 -32.175704)
		(width 0.2032)
		(layer "F.Cu")
		(net "VR_PVDDR_A_COMP")
	)
	(segment
		(start 186.43981 -32.175704)
		(end 185.912506 -31.6484)
		(width 0.2032)
		(layer "F.Cu")
		(net "VR_PVDDR_A_COMP")
	)
	(segment
		(start 182.4736 -31.2166)
		(end 182.5498 -31.2928)
		(width 0.2032)
		(layer "F.Cu")
		(net "VR_PVDDR_A_COMP")
	)
	(segment
		(start 182.4736 -30.4038)
		(end 182.4736 -31.2166)
		(width 0.2032)
		(layer "F.Cu")
		(net "VR_PVDDR_A_COMP")
	)
	(segment
		(start 185.727848 -31.6484)
		(end 185.252868 -31.17342)
		(width 0.2032)
		(layer "F.Cu")
		(net "VR_PVDDR_A_COMP")
	)
	(segment
		(start 185.912506 -31.6484)
		(end 185.727848 -31.6484)
		(width 0.2032)
		(layer "F.Cu")
		(net "VR_PVDDR_A_COMP")
	)
	(via
		(at 182.4736 -28.6512)
		(size 0.7112)
		(drill 0.3556)
		(layers "F.Cu" "B.Cu")
		(net "VR_PVDDR_A_COMP")
	)
	(segment
		(start 152.649936 -9.897364)
		(end 151.678386 -9.897364)
		(width 0.1778)
		(layer "F.Cu")
		(net "M_B_ECC1")
	)
	(segment
		(start 104.907588 -26.896314)
		(end 104.745028 -26.733754)
		(width 0.1016)
		(layer "F.Cu")
		(net "M_B_ECC1")
	)
	(segment
		(start 104.8766 -22.1488)
		(end 104.4702 -21.7424)
		(width 0.1016)
		(layer "F.Cu")
		(net "M_B_ECC1")
	)
	(segment
		(start 104.4448 -25.917398)
		(end 104.4448 -25.146)
		(width 0.1016)
		(layer "F.Cu")
		(net "M_B_ECC1")
	)
	(segment
		(start 104.8766 -24.7142)
		(end 104.8766 -22.1488)
		(width 0.1016)
		(layer "F.Cu")
		(net "M_B_ECC1")
	)
	(segment
		(start 104.745028 -26.217626)
		(end 104.4448 -25.917398)
		(width 0.1016)
		(layer "F.Cu")
		(net "M_B_ECC1")
	)
	(segment
		(start 104.745028 -26.733754)
		(end 104.745028 -26.217626)
		(width 0.1016)
		(layer "F.Cu")
		(net "M_B_ECC1")
	)
	(segment
		(start 104.4448 -25.146)
		(end 104.8766 -24.7142)
		(width 0.1016)
		(layer "F.Cu")
		(net "M_B_ECC1")
	)
	(segment
		(start 151.678386 -9.897364)
		(end 150.9776 -9.196578)
		(width 0.1778)
		(layer "F.Cu")
		(net "M_B_ECC1")
	)
	(via
		(at 150.9776 -9.196578)
		(size 0.4318)
		(drill 0.2032)
		(layers "F.Cu" "B.Cu")
		(net "M_B_ECC1")
	)
	(via
		(at 104.4702 -21.7424)
		(size 0.4318)
		(drill 0.2032)
		(layers "F.Cu" "B.Cu")
		(net "M_B_ECC1")
	)
	(segment
		(start 150.283418 -9.89076)
		(end 150.9776 -9.196578)
		(width 0.1778)
		(layer "B.Cu")
		(net "M_B_ECC1")
	)
	(segment
		(start 149.349968 -9.89076)
		(end 150.283418 -9.89076)
		(width 0.1778)
		(layer "B.Cu")
		(net "M_B_ECC1")
	)
	(segment
		(start 150.9776 -17.85239)
		(end 149.98319 -18.8468)
		(width 0.1524)
		(layer "In2.Cu")
		(net "M_B_ECC1")
	)
	(segment
		(start 121.6914 -20.8534)
		(end 121.539 -21.0058)
		(width 0.1524)
		(layer "In2.Cu")
		(net "M_B_ECC1")
	)
	(segment
		(start 115.995196 -21.0058)
		(end 115.842796 -20.8534)
		(width 0.1524)
		(layer "In2.Cu")
		(net "M_B_ECC1")
	)
	(segment
		(start 104.8512 -21.3614)
		(end 110.109 -21.3614)
		(width 0.1016)
		(layer "In2.Cu")
		(net "M_B_ECC1")
	)
	(segment
		(start 125.069092 -18.8468)
		(end 123.799346 -20.116546)
		(width 0.1524)
		(layer "In2.Cu")
		(net "M_B_ECC1")
	)
	(segment
		(start 121.8438 -20.243546)
		(end 121.6914 -20.395946)
		(width 0.1524)
		(layer "In2.Cu")
		(net "M_B_ECC1")
	)
	(segment
		(start 116.604796 -20.2438)
		(end 116.452396 -20.3962)
		(width 0.1524)
		(layer "In2.Cu")
		(net "M_B_ECC1")
	)
	(segment
		(start 116.452396 -20.8534)
		(end 116.299996 -21.0058)
		(width 0.1524)
		(layer "In2.Cu")
		(net "M_B_ECC1")
	)
	(segment
		(start 111.226854 -20.243546)
		(end 110.109 -21.3614)
		(width 0.1524)
		(layer "In2.Cu")
		(net "M_B_ECC1")
	)
	(segment
		(start 122.8598 -21.0058)
		(end 122.5042 -21.0058)
		(width 0.1524)
		(layer "In2.Cu")
		(net "M_B_ECC1")
	)
	(segment
		(start 123.0122 -20.8534)
		(end 122.8598 -21.0058)
		(width 0.1524)
		(layer "In2.Cu")
		(net "M_B_ECC1")
	)
	(segment
		(start 123.1646 -20.116546)
		(end 123.0122 -20.268946)
		(width 0.1524)
		(layer "In2.Cu")
		(net "M_B_ECC1")
	)
	(segment
		(start 123.799346 -20.116546)
		(end 123.1646 -20.116546)
		(width 0.1524)
		(layer "In2.Cu")
		(net "M_B_ECC1")
	)
	(segment
		(start 104.4702 -21.7424)
		(end 104.8512 -21.3614)
		(width 0.1016)
		(layer "In2.Cu")
		(net "M_B_ECC1")
	)
	(segment
		(start 115.233196 -20.8534)
		(end 115.080796 -21.0058)
		(width 0.1524)
		(layer "In2.Cu")
		(net "M_B_ECC1")
	)
	(segment
		(start 120.7516 -20.243546)
		(end 120.3706 -20.243546)
		(width 0.1524)
		(layer "In2.Cu")
		(net "M_B_ECC1")
	)
	(segment
		(start 150.9776 -9.196578)
		(end 150.9776 -17.85239)
		(width 0.1524)
		(layer "In2.Cu")
		(net "M_B_ECC1")
	)
	(segment
		(start 115.842796 -20.3962)
		(end 115.690396 -20.2438)
		(width 0.1524)
		(layer "In2.Cu")
		(net "M_B_ECC1")
	)
	(segment
		(start 115.842796 -20.8534)
		(end 115.842796 -20.3962)
		(width 0.1524)
		(layer "In2.Cu")
		(net "M_B_ECC1")
	)
	(segment
		(start 117.061996 -20.8534)
		(end 117.061996 -20.3962)
		(width 0.1524)
		(layer "In2.Cu")
		(net "M_B_ECC1")
	)
	(segment
		(start 114.344196 -20.8534)
		(end 114.344196 -20.395946)
		(width 0.1524)
		(layer "In2.Cu")
		(net "M_B_ECC1")
	)
	(segment
		(start 115.690396 -20.2438)
		(end 115.385596 -20.2438)
		(width 0.1524)
		(layer "In2.Cu")
		(net "M_B_ECC1")
	)
	(segment
		(start 120.904 -20.395946)
		(end 120.7516 -20.243546)
		(width 0.1524)
		(layer "In2.Cu")
		(net "M_B_ECC1")
	)
	(segment
		(start 120.904 -20.8534)
		(end 120.904 -20.395946)
		(width 0.1524)
		(layer "In2.Cu")
		(net "M_B_ECC1")
	)
	(segment
		(start 120.3706 -20.243546)
		(end 120.2182 -20.395946)
		(width 0.1524)
		(layer "In2.Cu")
		(net "M_B_ECC1")
	)
	(segment
		(start 116.909596 -20.2438)
		(end 116.604796 -20.2438)
		(width 0.1524)
		(layer "In2.Cu")
		(net "M_B_ECC1")
	)
	(segment
		(start 115.080796 -21.0058)
		(end 114.496596 -21.0058)
		(width 0.1524)
		(layer "In2.Cu")
		(net "M_B_ECC1")
	)
	(segment
		(start 120.0658 -21.0058)
		(end 117.214396 -21.0058)
		(width 0.1524)
		(layer "In2.Cu")
		(net "M_B_ECC1")
	)
	(segment
		(start 114.191796 -20.243546)
		(end 111.226854 -20.243546)
		(width 0.1524)
		(layer "In2.Cu")
		(net "M_B_ECC1")
	)
	(segment
		(start 122.3518 -20.395946)
		(end 122.1994 -20.243546)
		(width 0.1524)
		(layer "In2.Cu")
		(net "M_B_ECC1")
	)
	(segment
		(start 121.539 -21.0058)
		(end 121.0564 -21.0058)
		(width 0.1524)
		(layer "In2.Cu")
		(net "M_B_ECC1")
	)
	(segment
		(start 123.0122 -20.268946)
		(end 123.0122 -20.8534)
		(width 0.1524)
		(layer "In2.Cu")
		(net "M_B_ECC1")
	)
	(segment
		(start 117.061996 -20.3962)
		(end 116.909596 -20.2438)
		(width 0.1524)
		(layer "In2.Cu")
		(net "M_B_ECC1")
	)
	(segment
		(start 116.452396 -20.3962)
		(end 116.452396 -20.8534)
		(width 0.1524)
		(layer "In2.Cu")
		(net "M_B_ECC1")
	)
	(segment
		(start 116.299996 -21.0058)
		(end 115.995196 -21.0058)
		(width 0.1524)
		(layer "In2.Cu")
		(net "M_B_ECC1")
	)
	(segment
		(start 120.2182 -20.8534)
		(end 120.0658 -21.0058)
		(width 0.1524)
		(layer "In2.Cu")
		(net "M_B_ECC1")
	)
	(segment
		(start 114.496596 -21.0058)
		(end 114.344196 -20.8534)
		(width 0.1524)
		(layer "In2.Cu")
		(net "M_B_ECC1")
	)
	(segment
		(start 122.5042 -21.0058)
		(end 122.3518 -20.8534)
		(width 0.1524)
		(layer "In2.Cu")
		(net "M_B_ECC1")
	)
	(segment
		(start 121.0564 -21.0058)
		(end 120.904 -20.8534)
		(width 0.1524)
		(layer "In2.Cu")
		(net "M_B_ECC1")
	)
	(segment
		(start 115.233196 -20.3962)
		(end 115.233196 -20.8534)
		(width 0.1524)
		(layer "In2.Cu")
		(net "M_B_ECC1")
	)
	(segment
		(start 114.344196 -20.395946)
		(end 114.191796 -20.243546)
		(width 0.1524)
		(layer "In2.Cu")
		(net "M_B_ECC1")
	)
	(segment
		(start 121.6914 -20.395946)
		(end 121.6914 -20.8534)
		(width 0.1524)
		(layer "In2.Cu")
		(net "M_B_ECC1")
	)
	(segment
		(start 115.385596 -20.2438)
		(end 115.233196 -20.3962)
		(width 0.1524)
		(layer "In2.Cu")
		(net "M_B_ECC1")
	)
	(segment
		(start 149.98319 -18.8468)
		(end 125.069092 -18.8468)
		(width 0.1524)
		(layer "In2.Cu")
		(net "M_B_ECC1")
	)
	(segment
		(start 120.2182 -20.395946)
		(end 120.2182 -20.8534)
		(width 0.1524)
		(layer "In2.Cu")
		(net "M_B_ECC1")
	)
	(segment
		(start 122.3518 -20.8534)
		(end 122.3518 -20.395946)
		(width 0.1524)
		(layer "In2.Cu")
		(net "M_B_ECC1")
	)
	(segment
		(start 122.1994 -20.243546)
		(end 121.8438 -20.243546)
		(width 0.1524)
		(layer "In2.Cu")
		(net "M_B_ECC1")
	)
	(segment
		(start 117.214396 -21.0058)
		(end 117.061996 -20.8534)
		(width 0.1524)
		(layer "In2.Cu")
		(net "M_B_ECC1")
	)
	(segment
		(start 184.923684 -36.77285)
		(end 185.667904 -36.02863)
		(width 0.1143)
		(layer "F.Cu")
		(net "SVID_CLK_A")
	)
	(segment
		(start 184.0738 -37.338)
		(end 184.0738 -37.2618)
		(width 0.1143)
		(layer "F.Cu")
		(net "SVID_CLK_A")
	)
	(segment
		(start 185.667904 -35.468306)
		(end 185.835544 -35.300666)
		(width 0.1143)
		(layer "F.Cu")
		(net "SVID_CLK_A")
	)
	(segment
		(start 184.0738 -37.2618)
		(end 184.56275 -36.77285)
		(width 0.1143)
		(layer "F.Cu")
		(net "SVID_CLK_A")
	)
	(segment
		(start 186.856116 -34.9758)
		(end 186.16041 -34.9758)
		(width 0.1143)
		(layer "F.Cu")
		(net "SVID_CLK_A")
	)
	(segment
		(start 186.16041 -34.9758)
		(end 185.835544 -35.300666)
		(width 0.1143)
		(layer "F.Cu")
		(net "SVID_CLK_A")
	)
	(segment
		(start 184.56275 -36.77285)
		(end 184.923684 -36.77285)
		(width 0.1143)
		(layer "F.Cu")
		(net "SVID_CLK_A")
	)
	(segment
		(start 185.667904 -36.02863)
		(end 185.667904 -35.468306)
		(width 0.1143)
		(layer "F.Cu")
		(net "SVID_CLK_A")
	)
	(via
		(at 185.835544 -35.300666)
		(size 0.7112)
		(drill 0.3556)
		(layers "F.Cu" "B.Cu")
		(net "SVID_CLK_A")
	)
	(segment
		(start 108.839 -56.896)
		(end 108.839 -57.5818)
		(width 0.1143)
		(layer "F.Cu")
		(net "M_A_MON1_P")
	)
	(segment
		(start 108.839 -57.5818)
		(end 109.1692 -57.912)
		(width 0.1143)
		(layer "F.Cu")
		(net "M_A_MON1_P")
	)
	(segment
		(start 109.1692 -57.912)
		(end 109.1692 -58.333386)
		(width 0.1143)
		(layer "F.Cu")
		(net "M_A_MON1_P")
	)
	(segment
		(start 108.989368 -56.745632)
		(end 108.989368 -52.590954)
		(width 0.1143)
		(layer "F.Cu")
		(net "M_A_MON1_P")
	)
	(segment
		(start 108.839 -56.896)
		(end 108.989368 -56.745632)
		(width 0.1143)
		(layer "F.Cu")
		(net "M_A_MON1_P")
	)
	(segment
		(start 109.1692 -58.333386)
		(end 108.558584 -58.944002)
		(width 0.1143)
		(layer "F.Cu")
		(net "M_A_MON1_P")
	)
	(segment
		(start 108.989368 -52.590954)
		(end 108.709968 -52.311554)
		(width 0.1143)
		(layer "F.Cu")
		(net "M_A_MON1_P")
	)
	(via
		(at 108.839 -56.896)
		(size 0.7112)
		(drill 0.3556)
		(layers "F.Cu" "B.Cu")
		(net "M_A_MON1_P")
	)
	(segment
		(start 170.949874 -3.28422)
		(end 171.27728 -3.611626)
		(width 0.1778)
		(layer "F.Cu")
		(net "M_B_DQ37")
	)
	(segment
		(start 170.949874 -1.68402)
		(end 170.949874 -3.28422)
		(width 0.1778)
		(layer "F.Cu")
		(net "M_B_DQ37")
	)
	(segment
		(start 105.339642 -33.3756)
		(end 105.004108 -33.711134)
		(width 0.1016)
		(layer "F.Cu")
		(net "M_B_DQ37")
	)
	(segment
		(start 105.41 -33.3756)
		(end 105.339642 -33.3756)
		(width 0.1016)
		(layer "F.Cu")
		(net "M_B_DQ37")
	)
	(via
		(at 171.27728 -3.611626)
		(size 0.4318)
		(drill 0.2032)
		(layers "F.Cu" "B.Cu")
		(net "M_B_DQ37")
	)
	(via
		(at 105.41 -33.3756)
		(size 0.4318)
		(drill 0.2032)
		(layers "F.Cu" "B.Cu")
		(net "M_B_DQ37")
	)
	(segment
		(start 171.249848 -1.690624)
		(end 171.249848 -2.99593)
		(width 0.1778)
		(layer "B.Cu")
		(net "M_B_DQ37")
	)
	(segment
		(start 171.0944 -3.151378)
		(end 171.0944 -3.428746)
		(width 0.1778)
		(layer "B.Cu")
		(net "M_B_DQ37")
	)
	(segment
		(start 171.249848 -2.99593)
		(end 171.0944 -3.151378)
		(width 0.1778)
		(layer "B.Cu")
		(net "M_B_DQ37")
	)
	(segment
		(start 171.0944 -3.428746)
		(end 171.27728 -3.611626)
		(width 0.1778)
		(layer "B.Cu")
		(net "M_B_DQ37")
	)
	(segment
		(start 164.3634 -15.5448)
		(end 166.693342 -15.5448)
		(width 0.1524)
		(layer "In4.Cu")
		(net "M_B_DQ37")
	)
	(segment
		(start 171.0182 -3.862578)
		(end 171.269152 -3.611626)
		(width 0.1524)
		(layer "In4.Cu")
		(net "M_B_DQ37")
	)
	(segment
		(start 115.3668 -26.0604)
		(end 115.5446 -25.8826)
		(width 0.1524)
		(layer "In4.Cu")
		(net "M_B_DQ37")
	)
	(segment
		(start 106.266488 -29.177488)
		(end 106.266488 -29.772356)
		(width 0.1016)
		(layer "In4.Cu")
		(net "M_B_DQ37")
	)
	(segment
		(start 169.8244 -6.250178)
		(end 171.0182 -5.056378)
		(width 0.1524)
		(layer "In4.Cu")
		(net "M_B_DQ37")
	)
	(segment
		(start 166.693342 -15.5448)
		(end 169.8244 -12.413742)
		(width 0.1524)
		(layer "In4.Cu")
		(net "M_B_DQ37")
	)
	(segment
		(start 106.2609 -30.222444)
		(end 106.261916 -30.22346)
		(width 0.1016)
		(layer "In4.Cu")
		(net "M_B_DQ37")
	)
	(segment
		(start 106.266488 -29.772356)
		(end 106.2609 -29.777944)
		(width 0.1016)
		(layer "In4.Cu")
		(net "M_B_DQ37")
	)
	(segment
		(start 105.6132 -31.7754)
		(end 104.971088 -32.417512)
		(width 0.1016)
		(layer "In4.Cu")
		(net "M_B_DQ37")
	)
	(segment
		(start 105.3592 -33.3756)
		(end 105.41 -33.3756)
		(width 0.1016)
		(layer "In4.Cu")
		(net "M_B_DQ37")
	)
	(segment
		(start 171.269152 -3.611626)
		(end 171.27728 -3.611626)
		(width 0.1524)
		(layer "In4.Cu")
		(net "M_B_DQ37")
	)
	(segment
		(start 106.209084 -28.666948)
		(end 106.209084 -29.120084)
		(width 0.1016)
		(layer "In4.Cu")
		(net "M_B_DQ37")
	)
	(segment
		(start 106.554016 -28.322016)
		(end 106.209084 -28.666948)
		(width 0.1016)
		(layer "In4.Cu")
		(net "M_B_DQ37")
	)
	(segment
		(start 115.5446 -25.8826)
		(end 154.0256 -25.8826)
		(width 0.1524)
		(layer "In4.Cu")
		(net "M_B_DQ37")
	)
	(segment
		(start 107.186984 -28.322016)
		(end 106.554016 -28.322016)
		(width 0.1016)
		(layer "In4.Cu")
		(net "M_B_DQ37")
	)
	(segment
		(start 106.261916 -30.22346)
		(end 106.261916 -31.355284)
		(width 0.1016)
		(layer "In4.Cu")
		(net "M_B_DQ37")
	)
	(segment
		(start 154.0256 -25.8826)
		(end 164.3634 -15.5448)
		(width 0.1524)
		(layer "In4.Cu")
		(net "M_B_DQ37")
	)
	(segment
		(start 107.2388 -28.2702)
		(end 107.186984 -28.322016)
		(width 0.1016)
		(layer "In4.Cu")
		(net "M_B_DQ37")
	)
	(segment
		(start 105.8418 -31.7754)
		(end 105.6132 -31.7754)
		(width 0.1016)
		(layer "In4.Cu")
		(net "M_B_DQ37")
	)
	(segment
		(start 106.261916 -31.355284)
		(end 105.8418 -31.7754)
		(width 0.1016)
		(layer "In4.Cu")
		(net "M_B_DQ37")
	)
	(segment
		(start 109.7026 -27.7876)
		(end 111.4298 -26.0604)
		(width 0.1524)
		(layer "In4.Cu")
		(net "M_B_DQ37")
	)
	(segment
		(start 106.209084 -29.120084)
		(end 106.266488 -29.177488)
		(width 0.1016)
		(layer "In4.Cu")
		(net "M_B_DQ37")
	)
	(segment
		(start 169.8244 -12.413742)
		(end 169.8244 -6.250178)
		(width 0.1524)
		(layer "In4.Cu")
		(net "M_B_DQ37")
	)
	(segment
		(start 106.2609 -29.777944)
		(end 106.2609 -30.222444)
		(width 0.1016)
		(layer "In4.Cu")
		(net "M_B_DQ37")
	)
	(segment
		(start 104.971088 -32.417512)
		(end 104.971088 -32.987488)
		(width 0.1016)
		(layer "In4.Cu")
		(net "M_B_DQ37")
	)
	(segment
		(start 171.0182 -5.056378)
		(end 171.0182 -3.862578)
		(width 0.1524)
		(layer "In4.Cu")
		(net "M_B_DQ37")
	)
	(segment
		(start 107.2388 -28.2702)
		(end 107.7214 -27.7876)
		(width 0.1524)
		(layer "In4.Cu")
		(net "M_B_DQ37")
	)
	(segment
		(start 107.7214 -27.7876)
		(end 109.7026 -27.7876)
		(width 0.1524)
		(layer "In4.Cu")
		(net "M_B_DQ37")
	)
	(segment
		(start 104.971088 -32.987488)
		(end 105.3592 -33.3756)
		(width 0.1016)
		(layer "In4.Cu")
		(net "M_B_DQ37")
	)
	(segment
		(start 111.4298 -26.0604)
		(end 115.3668 -26.0604)
		(width 0.1524)
		(layer "In4.Cu")
		(net "M_B_DQ37")
	)
	(segment
		(start 15.4178 -59.1312)
		(end 15.385796 -59.1312)
		(width 0.1143)
		(layer "F.Cu")
		(net "SVID_CPU_CLK")
	)
	(segment
		(start 14.43355 -60.083446)
		(end 14.43355 -61.772546)
		(width 0.1143)
		(layer "F.Cu")
		(net "SVID_CPU_CLK")
	)
	(segment
		(start 13.341604 -60.5028)
		(end 14.28115 -61.442346)
		(width 0.1143)
		(layer "F.Cu")
		(net "SVID_CPU_CLK")
	)
	(segment
		(start 181.5338 -37.338)
		(end 182.4228 -37.338)
		(width 0.1143)
		(layer "F.Cu")
		(net "SVID_CPU_CLK")
	)
	(segment
		(start 14.43355 -61.772546)
		(end 14.407896 -61.7982)
		(width 0.1143)
		(layer "F.Cu")
		(net "SVID_CPU_CLK")
	)
	(segment
		(start 15.385796 -59.1312)
		(end 14.43355 -60.083446)
		(width 0.1143)
		(layer "F.Cu")
		(net "SVID_CPU_CLK")
	)
	(segment
		(start 14.28115 -61.442346)
		(end 14.28115 -61.671454)
		(width 0.1143)
		(layer "F.Cu")
		(net "SVID_CPU_CLK")
	)
	(segment
		(start 13.335 -60.5028)
		(end 13.341604 -60.5028)
		(width 0.1143)
		(layer "F.Cu")
		(net "SVID_CPU_CLK")
	)
	(segment
		(start 12.573 -60.5028)
		(end 13.335 -60.5028)
		(width 0.1143)
		(layer "F.Cu")
		(net "SVID_CPU_CLK")
	)
	(segment
		(start 14.28115 -61.671454)
		(end 14.407896 -61.7982)
		(width 0.1143)
		(layer "F.Cu")
		(net "SVID_CPU_CLK")
	)
	(segment
		(start 182.4228 -37.338)
		(end 183.2102 -37.338)
		(width 0.1143)
		(layer "F.Cu")
		(net "SVID_CPU_CLK")
	)
	(via
		(at 81.915 -64.5668)
		(size 0.508)
		(drill 0.254)
		(layers "F.Cu" "B.Cu")
		(net "SVID_CPU_CLK")
	)
	(via
		(at 14.407896 -61.7982)
		(size 0.508)
		(drill 0.254)
		(layers "F.Cu" "B.Cu")
		(net "SVID_CPU_CLK")
	)
	(via
		(at 182.587138 -36.449)
		(size 0.7112)
		(drill 0.3556)
		(layers "F.Cu" "B.Cu")
		(net "SVID_CPU_CLK")
	)
	(via
		(at 182.4228 -37.338)
		(size 0.508)
		(drill 0.254)
		(layers "F.Cu" "B.Cu")
		(net "SVID_CPU_CLK")
	)
	(segment
		(start 81.915 -65.3542)
		(end 81.915 -64.5668)
		(width 0.1143)
		(layer "B.Cu")
		(net "SVID_CPU_CLK")
	)
	(segment
		(start 182.4228 -36.6268)
		(end 182.4228 -37.338)
		(width 0.1143)
		(layer "B.Cu")
		(net "SVID_CPU_CLK")
	)
	(segment
		(start 182.587138 -36.449)
		(end 182.587138 -36.462462)
		(width 0.1143)
		(layer "B.Cu")
		(net "SVID_CPU_CLK")
	)
	(segment
		(start 182.587138 -36.462462)
		(end 182.4228 -36.6268)
		(width 0.1143)
		(layer "B.Cu")
		(net "SVID_CPU_CLK")
	)
	(segment
		(start 81.915 -63.6778)
		(end 81.915 -64.5668)
		(width 0.1143)
		(layer "B.Cu")
		(net "SVID_CPU_CLK")
	)
	(segment
		(start 194.840098 -69.027548)
		(end 194.840352 -69.027802)
		(width 0.0889)
		(layer "In4.Cu")
		(net "SVID_CPU_CLK")
	)
	(segment
		(start 74.99985 -69.72935)
		(end 73.939908 -70.789292)
		(width 0.0889)
		(layer "In4.Cu")
		(net "SVID_CPU_CLK")
	)
	(segment
		(start 83.931252 -69.72935)
		(end 74.99985 -69.72935)
		(width 0.0889)
		(layer "In4.Cu")
		(net "SVID_CPU_CLK")
	)
	(segment
		(start 59.840622 -70.789292)
		(end 58.37428 -69.32295)
		(width 0.0889)
		(layer "In4.Cu")
		(net "SVID_CPU_CLK")
	)
	(segment
		(start 194.840352 -69.027802)
		(end 194.840352 -69.385434)
		(width 0.0889)
		(layer "In4.Cu")
		(net "SVID_CPU_CLK")
	)
	(segment
		(start 44.45889 -71.74865)
		(end 16.549116 -71.74865)
		(width 0.0889)
		(layer "In4.Cu")
		(net "SVID_CPU_CLK")
	)
	(segment
		(start 84.325206 -70.123304)
		(end 83.931252 -69.72935)
		(width 0.0889)
		(layer "In4.Cu")
		(net "SVID_CPU_CLK")
	)
	(segment
		(start 191.308482 -72.917304)
		(end 90.642694 -72.917304)
		(width 0.0889)
		(layer "In4.Cu")
		(net "SVID_CPU_CLK")
	)
	(segment
		(start 191.8462 -52.1716)
		(end 194.840098 -55.165498)
		(width 0.0889)
		(layer "In4.Cu")
		(net "SVID_CPU_CLK")
	)
	(segment
		(start 183.134 -38.0492)
		(end 183.134 -45.146214)
		(width 0.0889)
		(layer "In4.Cu")
		(net "SVID_CPU_CLK")
	)
	(segment
		(start 190.159386 -52.1716)
		(end 191.8462 -52.1716)
		(width 0.0889)
		(layer "In4.Cu")
		(net "SVID_CPU_CLK")
	)
	(segment
		(start 85.040978 -70.123304)
		(end 84.325206 -70.123304)
		(width 0.0889)
		(layer "In4.Cu")
		(net "SVID_CPU_CLK")
	)
	(segment
		(start 90.642694 -72.917304)
		(end 87.84844 -70.12305)
		(width 0.0889)
		(layer "In4.Cu")
		(net "SVID_CPU_CLK")
	)
	(segment
		(start 16.549116 -71.74865)
		(end 13.21435 -68.413884)
		(width 0.0889)
		(layer "In4.Cu")
		(net "SVID_CPU_CLK")
	)
	(segment
		(start 73.939908 -70.789292)
		(end 59.840622 -70.789292)
		(width 0.0889)
		(layer "In4.Cu")
		(net "SVID_CPU_CLK")
	)
	(segment
		(start 182.4228 -37.338)
		(end 183.134 -38.0492)
		(width 0.0889)
		(layer "In4.Cu")
		(net "SVID_CPU_CLK")
	)
	(segment
		(start 87.84844 -70.12305)
		(end 85.041232 -70.12305)
		(width 0.0889)
		(layer "In4.Cu")
		(net "SVID_CPU_CLK")
	)
	(segment
		(start 194.840352 -69.385434)
		(end 191.308482 -72.917304)
		(width 0.0889)
		(layer "In4.Cu")
		(net "SVID_CPU_CLK")
	)
	(segment
		(start 183.134 -45.146214)
		(end 190.159386 -52.1716)
		(width 0.0889)
		(layer "In4.Cu")
		(net "SVID_CPU_CLK")
	)
	(segment
		(start 13.21435 -68.413884)
		(end 13.21435 -62.991746)
		(width 0.0889)
		(layer "In4.Cu")
		(net "SVID_CPU_CLK")
	)
	(segment
		(start 13.21435 -62.991746)
		(end 14.407896 -61.7982)
		(width 0.0889)
		(layer "In4.Cu")
		(net "SVID_CPU_CLK")
	)
	(segment
		(start 46.88459 -69.32295)
		(end 44.45889 -71.74865)
		(width 0.0889)
		(layer "In4.Cu")
		(net "SVID_CPU_CLK")
	)
	(segment
		(start 58.37428 -69.32295)
		(end 46.88459 -69.32295)
		(width 0.0889)
		(layer "In4.Cu")
		(net "SVID_CPU_CLK")
	)
	(segment
		(start 85.041232 -70.12305)
		(end 85.040978 -70.123304)
		(width 0.0889)
		(layer "In4.Cu")
		(net "SVID_CPU_CLK")
	)
	(segment
		(start 194.840098 -55.165498)
		(end 194.840098 -69.027548)
		(width 0.0889)
		(layer "In4.Cu")
		(net "SVID_CPU_CLK")
	)
	(segment
		(start 15.24 -66.2686)
		(end 13.9446 -64.9732)
		(width 0.0889)
		(layer "In7.Cu")
		(net "SVID_CPU_CLK")
	)
	(segment
		(start 14.407896 -62.122304)
		(end 14.407896 -61.7982)
		(width 0.0889)
		(layer "In7.Cu")
		(net "SVID_CPU_CLK")
	)
	(segment
		(start 13.9446 -62.5856)
		(end 14.407896 -62.122304)
		(width 0.0889)
		(layer "In7.Cu")
		(net "SVID_CPU_CLK")
	)
	(segment
		(start 81.915 -64.5668)
		(end 80.4672 -66.0146)
		(width 0.0889)
		(layer "In7.Cu")
		(net "SVID_CPU_CLK")
	)
	(segment
		(start 17.018 -69.092318)
		(end 17.018 -69.088)
		(width 0.0889)
		(layer "In7.Cu")
		(net "SVID_CPU_CLK")
	)
	(segment
		(start 44.88815 -71.69785)
		(end 19.623532 -71.69785)
		(width 0.0889)
		(layer "In7.Cu")
		(net "SVID_CPU_CLK")
	)
	(segment
		(start 66.2559 -69.4817)
		(end 47.1043 -69.4817)
		(width 0.0889)
		(layer "In7.Cu")
		(net "SVID_CPU_CLK")
	)
	(segment
		(start 17.018 -69.088)
		(end 15.24 -67.31)
		(width 0.0889)
		(layer "In7.Cu")
		(net "SVID_CPU_CLK")
	)
	(segment
		(start 13.9446 -64.9732)
		(end 13.9446 -62.5856)
		(width 0.0889)
		(layer "In7.Cu")
		(net "SVID_CPU_CLK")
	)
	(segment
		(start 19.623532 -71.69785)
		(end 17.018 -69.092318)
		(width 0.0889)
		(layer "In7.Cu")
		(net "SVID_CPU_CLK")
	)
	(segment
		(start 80.4672 -66.0146)
		(end 69.723 -66.0146)
		(width 0.0889)
		(layer "In7.Cu")
		(net "SVID_CPU_CLK")
	)
	(segment
		(start 69.723 -66.0146)
		(end 66.2559 -69.4817)
		(width 0.0889)
		(layer "In7.Cu")
		(net "SVID_CPU_CLK")
	)
	(segment
		(start 15.24 -67.31)
		(end 15.24 -66.2686)
		(width 0.0889)
		(layer "In7.Cu")
		(net "SVID_CPU_CLK")
	)
	(segment
		(start 47.1043 -69.4817)
		(end 44.88815 -71.69785)
		(width 0.0889)
		(layer "In7.Cu")
		(net "SVID_CPU_CLK")
	)
	(segment
		(start 103.685086 -44.630594)
		(end 104.29748 -44.0182)
		(width 0.1778)
		(layer "F.Cu")
		(net "M_A_ODTPU")
	)
	(segment
		(start 103.182928 -44.630594)
		(end 103.685086 -44.630594)
		(width 0.1778)
		(layer "F.Cu")
		(net "M_A_ODTPU")
	)
	(segment
		(start 102.652068 -44.701714)
		(end 103.111808 -44.701714)
		(width 0.1778)
		(layer "F.Cu")
		(net "M_A_ODTPU")
	)
	(segment
		(start 103.111808 -44.701714)
		(end 103.182928 -44.630594)
		(width 0.1778)
		(layer "F.Cu")
		(net "M_A_ODTPU")
	)
	(via
		(at 104.29748 -44.0182)
		(size 0.4318)
		(drill 0.2032)
		(layers "F.Cu" "B.Cu")
		(net "M_A_ODTPU")
	)
	(via
		(at 104.7369 -44.5897)
		(size 0.7112)
		(drill 0.3556)
		(layers "F.Cu" "B.Cu")
		(net "M_A_ODTPU")
	)
	(segment
		(start 105.63606 -44.593002)
		(end 104.793542 -44.593002)
		(width 0.1778)
		(layer "B.Cu")
		(net "M_A_ODTPU")
	)
	(segment
		(start 104.79024 -44.5897)
		(end 104.7369 -44.5897)
		(width 0.1778)
		(layer "B.Cu")
		(net "M_A_ODTPU")
	)
	(segment
		(start 104.793542 -44.593002)
		(end 104.79024 -44.5897)
		(width 0.1778)
		(layer "B.Cu")
		(net "M_A_ODTPU")
	)
	(segment
		(start 105.6513 -44.608242)
		(end 105.63606 -44.593002)
		(width 0.1778)
		(layer "B.Cu")
		(net "M_A_ODTPU")
	)
	(segment
		(start 104.29748 -44.15028)
		(end 104.29748 -44.0182)
		(width 0.1778)
		(layer "B.Cu")
		(net "M_A_ODTPU")
	)
	(segment
		(start 104.7369 -44.5897)
		(end 104.29748 -44.15028)
		(width 0.1778)
		(layer "B.Cu")
		(net "M_A_ODTPU")
	)
	(segment
		(start 188.5188 -28.2194)
		(end 188.5188 -28.2956)
		(width 0.2032)
		(layer "F.Cu")
		(net "VR_PVDDR_A_SUMN")
	)
	(segment
		(start 189.2554 -29.0322)
		(end 189.2554 -29.1846)
		(width 0.2032)
		(layer "F.Cu")
		(net "VR_PVDDR_A_SUMN")
	)
	(segment
		(start 188.595 -27.4574)
		(end 188.595 -28.1432)
		(width 0.2032)
		(layer "F.Cu")
		(net "VR_PVDDR_A_SUMN")
	)
	(segment
		(start 190.256414 -30.261814)
		(end 189.2554 -29.2608)
		(width 0.2032)
		(layer "F.Cu")
		(net "VR_PVDDR_A_SUMN")
	)
	(segment
		(start 189.2554 -29.2608)
		(end 189.2554 -29.1846)
		(width 0.2032)
		(layer "F.Cu")
		(net "VR_PVDDR_A_SUMN")
	)
	(segment
		(start 190.256414 -31.575502)
		(end 190.256414 -30.261814)
		(width 0.2032)
		(layer "F.Cu")
		(net "VR_PVDDR_A_SUMN")
	)
	(segment
		(start 188.5188 -28.2956)
		(end 189.2554 -29.0322)
		(width 0.2032)
		(layer "F.Cu")
		(net "VR_PVDDR_A_SUMN")
	)
	(segment
		(start 188.595 -28.1432)
		(end 188.5188 -28.2194)
		(width 0.2032)
		(layer "F.Cu")
		(net "VR_PVDDR_A_SUMN")
	)
	(via
		(at 189.2554 -29.1846)
		(size 0.7112)
		(drill 0.3556)
		(layers "F.Cu" "B.Cu")
		(net "VR_PVDDR_A_SUMN")
	)
	(segment
		(start 90.3986 -25.3746)
		(end 90.7034 -25.6794)
		(width 0.1016)
		(layer "F.Cu")
		(net "M_B_DQ0")
	)
	(segment
		(start 91.694 -25.7302)
		(end 91.9988 -25.7302)
		(width 0.1016)
		(layer "F.Cu")
		(net "M_B_DQ0")
	)
	(segment
		(start 92.955618 -26.275284)
		(end 93.238828 -26.558494)
		(width 0.1016)
		(layer "F.Cu")
		(net "M_B_DQ0")
	)
	(segment
		(start 91.9988 -25.7302)
		(end 92.543884 -26.275284)
		(width 0.1016)
		(layer "F.Cu")
		(net "M_B_DQ0")
	)
	(segment
		(start 90.3986 -23.7744)
		(end 90.3986 -25.3746)
		(width 0.1016)
		(layer "F.Cu")
		(net "M_B_DQ0")
	)
	(segment
		(start 90.7034 -25.6794)
		(end 91.2876 -25.6794)
		(width 0.1016)
		(layer "F.Cu")
		(net "M_B_DQ0")
	)
	(segment
		(start 91.567 -25.6032)
		(end 91.694 -25.7302)
		(width 0.1016)
		(layer "F.Cu")
		(net "M_B_DQ0")
	)
	(segment
		(start 92.543884 -26.275284)
		(end 92.955618 -26.275284)
		(width 0.1016)
		(layer "F.Cu")
		(net "M_B_DQ0")
	)
	(segment
		(start 129.249932 -9.897364)
		(end 129.249932 -7.970774)
		(width 0.1778)
		(layer "F.Cu")
		(net "M_B_DQ0")
	)
	(segment
		(start 90.861134 -23.311866)
		(end 90.3986 -23.7744)
		(width 0.1016)
		(layer "F.Cu")
		(net "M_B_DQ0")
	)
	(segment
		(start 91.2876 -25.6794)
		(end 91.3638 -25.6032)
		(width 0.1016)
		(layer "F.Cu")
		(net "M_B_DQ0")
	)
	(segment
		(start 91.3638 -25.6032)
		(end 91.567 -25.6032)
		(width 0.1016)
		(layer "F.Cu")
		(net "M_B_DQ0")
	)
	(segment
		(start 129.249932 -7.970774)
		(end 128.991106 -7.711948)
		(width 0.1778)
		(layer "F.Cu")
		(net "M_B_DQ0")
	)
	(via
		(at 90.861134 -23.311866)
		(size 0.4318)
		(drill 0.2032)
		(layers "F.Cu" "B.Cu")
		(net "M_B_DQ0")
	)
	(via
		(at 128.991106 -7.711948)
		(size 0.4318)
		(drill 0.2032)
		(layers "F.Cu" "B.Cu")
		(net "M_B_DQ0")
	)
	(segment
		(start 129.549906 -9.89076)
		(end 129.549906 -8.800084)
		(width 0.1778)
		(layer "B.Cu")
		(net "M_B_DQ0")
	)
	(segment
		(start 129.549906 -8.800084)
		(end 129.286 -8.536178)
		(width 0.1778)
		(layer "B.Cu")
		(net "M_B_DQ0")
	)
	(segment
		(start 129.286 -8.536178)
		(end 129.286 -8.006842)
		(width 0.1778)
		(layer "B.Cu")
		(net "M_B_DQ0")
	)
	(segment
		(start 129.286 -8.006842)
		(end 128.991106 -7.711948)
		(width 0.1778)
		(layer "B.Cu")
		(net "M_B_DQ0")
	)
	(segment
		(start 128.991106 -7.711948)
		(end 128.991106 -7.2136)
		(width 0.1524)
		(layer "In7.Cu")
		(net "M_B_DQ0")
	)
	(segment
		(start 122.2248 -6.6802)
		(end 120.2436 -6.6802)
		(width 0.1524)
		(layer "In7.Cu")
		(net "M_B_DQ0")
	)
	(segment
		(start 117.4242 -6.6294)
		(end 117.2718 -6.7818)
		(width 0.1524)
		(layer "In7.Cu")
		(net "M_B_DQ0")
	)
	(segment
		(start 119.253 -8.0264)
		(end 119.1006 -7.874)
		(width 0.1524)
		(layer "In7.Cu")
		(net "M_B_DQ0")
	)
	(segment
		(start 97.557082 -16.323056)
		(end 94.118938 -19.7612)
		(width 0.1524)
		(layer "In7.Cu")
		(net "M_B_DQ0")
	)
	(segment
		(start 118.491 -7.87654)
		(end 118.3386 -8.02894)
		(width 0.1524)
		(layer "In7.Cu")
		(net "M_B_DQ0")
	)
	(segment
		(start 118.0338 -8.02894)
		(end 117.8814 -7.87654)
		(width 0.1524)
		(layer "In7.Cu")
		(net "M_B_DQ0")
	)
	(segment
		(start 117.2718 -6.7818)
		(end 117.2718 -7.87654)
		(width 0.1524)
		(layer "In7.Cu")
		(net "M_B_DQ0")
	)
	(segment
		(start 90.861134 -22.067266)
		(end 93.1672 -19.7612)
		(width 0.1016)
		(layer "In7.Cu")
		(net "M_B_DQ0")
	)
	(segment
		(start 90.861134 -23.311866)
		(end 90.861134 -22.067266)
		(width 0.1016)
		(layer "In7.Cu")
		(net "M_B_DQ0")
	)
	(segment
		(start 123.0884 -7.9756)
		(end 122.936 -8.128)
		(width 0.1524)
		(layer "In7.Cu")
		(net "M_B_DQ0")
	)
	(segment
		(start 124.714 -8.128)
		(end 123.9012 -8.128)
		(width 0.1524)
		(layer "In7.Cu")
		(net "M_B_DQ0")
	)
	(segment
		(start 128.082802 -7.934198)
		(end 124.907802 -7.934198)
		(width 0.1524)
		(layer "In7.Cu")
		(net "M_B_DQ0")
	)
	(segment
		(start 119.1006 -6.8326)
		(end 118.9482 -6.6802)
		(width 0.1524)
		(layer "In7.Cu")
		(net "M_B_DQ0")
	)
	(segment
		(start 117.1194 -8.02894)
		(end 114.668046 -8.02894)
		(width 0.1524)
		(layer "In7.Cu")
		(net "M_B_DQ0")
	)
	(segment
		(start 118.6434 -6.6802)
		(end 118.491 -6.8326)
		(width 0.1524)
		(layer "In7.Cu")
		(net "M_B_DQ0")
	)
	(segment
		(start 122.428 -6.8834)
		(end 122.2248 -6.6802)
		(width 0.1524)
		(layer "In7.Cu")
		(net "M_B_DQ0")
	)
	(segment
		(start 118.9482 -6.6802)
		(end 118.6434 -6.6802)
		(width 0.1524)
		(layer "In7.Cu")
		(net "M_B_DQ0")
	)
	(segment
		(start 123.7488 -6.3246)
		(end 123.5964 -6.1722)
		(width 0.1524)
		(layer "In7.Cu")
		(net "M_B_DQ0")
	)
	(segment
		(start 118.3386 -8.02894)
		(end 118.0338 -8.02894)
		(width 0.1524)
		(layer "In7.Cu")
		(net "M_B_DQ0")
	)
	(segment
		(start 114.668046 -8.02894)
		(end 106.37393 -16.323056)
		(width 0.1524)
		(layer "In7.Cu")
		(net "M_B_DQ0")
	)
	(segment
		(start 119.1006 -7.874)
		(end 119.1006 -6.8326)
		(width 0.1524)
		(layer "In7.Cu")
		(net "M_B_DQ0")
	)
	(segment
		(start 117.729 -6.6294)
		(end 117.4242 -6.6294)
		(width 0.1524)
		(layer "In7.Cu")
		(net "M_B_DQ0")
	)
	(segment
		(start 123.2408 -6.1722)
		(end 123.0884 -6.3246)
		(width 0.1524)
		(layer "In7.Cu")
		(net "M_B_DQ0")
	)
	(segment
		(start 128.991106 -7.2136)
		(end 128.838706 -7.0612)
		(width 0.1524)
		(layer "In7.Cu")
		(net "M_B_DQ0")
	)
	(segment
		(start 123.5964 -6.1722)
		(end 123.2408 -6.1722)
		(width 0.1524)
		(layer "In7.Cu")
		(net "M_B_DQ0")
	)
	(segment
		(start 118.491 -6.8326)
		(end 118.491 -7.87654)
		(width 0.1524)
		(layer "In7.Cu")
		(net "M_B_DQ0")
	)
	(segment
		(start 128.27 -7.747)
		(end 128.082802 -7.934198)
		(width 0.1524)
		(layer "In7.Cu")
		(net "M_B_DQ0")
	)
	(segment
		(start 128.838706 -7.0612)
		(end 128.4224 -7.0612)
		(width 0.1524)
		(layer "In7.Cu")
		(net "M_B_DQ0")
	)
	(segment
		(start 128.27 -7.2136)
		(end 128.27 -7.747)
		(width 0.1524)
		(layer "In7.Cu")
		(net "M_B_DQ0")
	)
	(segment
		(start 124.907802 -7.934198)
		(end 124.714 -8.128)
		(width 0.1524)
		(layer "In7.Cu")
		(net "M_B_DQ0")
	)
	(segment
		(start 119.888 -8.0264)
		(end 119.253 -8.0264)
		(width 0.1524)
		(layer "In7.Cu")
		(net "M_B_DQ0")
	)
	(segment
		(start 117.8814 -6.7818)
		(end 117.729 -6.6294)
		(width 0.1524)
		(layer "In7.Cu")
		(net "M_B_DQ0")
	)
	(segment
		(start 120.2436 -6.6802)
		(end 120.0404 -6.8834)
		(width 0.1524)
		(layer "In7.Cu")
		(net "M_B_DQ0")
	)
	(segment
		(start 128.4224 -7.0612)
		(end 128.27 -7.2136)
		(width 0.1524)
		(layer "In7.Cu")
		(net "M_B_DQ0")
	)
	(segment
		(start 93.1672 -19.7612)
		(end 94.118938 -19.7612)
		(width 0.1016)
		(layer "In7.Cu")
		(net "M_B_DQ0")
	)
	(segment
		(start 117.8814 -7.87654)
		(end 117.8814 -6.7818)
		(width 0.1524)
		(layer "In7.Cu")
		(net "M_B_DQ0")
	)
	(segment
		(start 123.9012 -8.128)
		(end 123.7488 -7.9756)
		(width 0.1524)
		(layer "In7.Cu")
		(net "M_B_DQ0")
	)
	(segment
		(start 120.0404 -6.8834)
		(end 120.0404 -7.874)
		(width 0.1524)
		(layer "In7.Cu")
		(net "M_B_DQ0")
	)
	(segment
		(start 123.0884 -6.3246)
		(end 123.0884 -7.9756)
		(width 0.1524)
		(layer "In7.Cu")
		(net "M_B_DQ0")
	)
	(segment
		(start 117.2718 -7.87654)
		(end 117.1194 -8.02894)
		(width 0.1524)
		(layer "In7.Cu")
		(net "M_B_DQ0")
	)
	(segment
		(start 122.5804 -8.128)
		(end 122.428 -7.9756)
		(width 0.1524)
		(layer "In7.Cu")
		(net "M_B_DQ0")
	)
	(segment
		(start 123.7488 -7.9756)
		(end 123.7488 -6.3246)
		(width 0.1524)
		(layer "In7.Cu")
		(net "M_B_DQ0")
	)
	(segment
		(start 120.0404 -7.874)
		(end 119.888 -8.0264)
		(width 0.1524)
		(layer "In7.Cu")
		(net "M_B_DQ0")
	)
	(segment
		(start 122.936 -8.128)
		(end 122.5804 -8.128)
		(width 0.1524)
		(layer "In7.Cu")
		(net "M_B_DQ0")
	)
	(segment
		(start 122.428 -7.9756)
		(end 122.428 -6.8834)
		(width 0.1524)
		(layer "In7.Cu")
		(net "M_B_DQ0")
	)
	(segment
		(start 106.37393 -16.323056)
		(end 97.557082 -16.323056)
		(width 0.1524)
		(layer "In7.Cu")
		(net "M_B_DQ0")
	)
	(segment
		(start 188.256418 -38.862)
		(end 188.256418 -36.376102)
		(width 0.2032)
		(layer "F.Cu")
		(net "VR_PVDDR_A_IAUTO")
	)
	(segment
		(start 187.697618 -39.4208)
		(end 187.198 -39.4208)
		(width 0.2032)
		(layer "F.Cu")
		(net "VR_PVDDR_A_IAUTO")
	)
	(segment
		(start 186.436 -39.4462)
		(end 187.1726 -39.4462)
		(width 0.2032)
		(layer "F.Cu")
		(net "VR_PVDDR_A_IAUTO")
	)
	(segment
		(start 187.1726 -39.4462)
		(end 187.198 -39.4208)
		(width 0.2032)
		(layer "F.Cu")
		(net "VR_PVDDR_A_IAUTO")
	)
	(segment
		(start 188.256418 -38.862)
		(end 187.697618 -39.4208)
		(width 0.2032)
		(layer "F.Cu")
		(net "VR_PVDDR_A_IAUTO")
	)
	(via
		(at 188.256418 -38.862)
		(size 0.7112)
		(drill 0.3556)
		(layers "F.Cu" "B.Cu")
		(net "VR_PVDDR_A_IAUTO")
	)
	(segment
		(start 172.749972 -2.436876)
		(end 172.602398 -2.58445)
		(width 0.1778)
		(layer "F.Cu")
		(net "M_B_DQS_DP4")
	)
	(segment
		(start 107.6706 -33.401)
		(end 107.6452 -33.4264)
		(width 0.1016)
		(layer "F.Cu")
		(net "M_B_DQS_DP4")
	)
	(segment
		(start 107.611164 -33.4264)
		(end 107.32643 -33.711134)
		(width 0.1016)
		(layer "F.Cu")
		(net "M_B_DQS_DP4")
	)
	(segment
		(start 172.749972 -1.68402)
		(end 172.749972 -2.436876)
		(width 0.1778)
		(layer "F.Cu")
		(net "M_B_DQS_DP4")
	)
	(segment
		(start 172.602398 -2.58445)
		(end 172.602398 -5.528056)
		(width 0.1778)
		(layer "F.Cu")
		(net "M_B_DQS_DP4")
	)
	(segment
		(start 107.32643 -33.711134)
		(end 107.290108 -33.711134)
		(width 0.1016)
		(layer "F.Cu")
		(net "M_B_DQS_DP4")
	)
	(segment
		(start 172.602398 -5.528056)
		(end 172.86732 -5.792978)
		(width 0.1778)
		(layer "F.Cu")
		(net "M_B_DQS_DP4")
	)
	(segment
		(start 107.6452 -33.4264)
		(end 107.611164 -33.4264)
		(width 0.1016)
		(layer "F.Cu")
		(net "M_B_DQS_DP4")
	)
	(via
		(at 172.86732 -5.792978)
		(size 0.4318)
		(drill 0.2032)
		(layers "F.Cu" "B.Cu")
		(net "M_B_DQS_DP4")
	)
	(via
		(at 107.6706 -33.401)
		(size 0.4318)
		(drill 0.2032)
		(layers "F.Cu" "B.Cu")
		(net "M_B_DQS_DP4")
	)
	(segment
		(start 172.602398 -8.977376)
		(end 172.602398 -6.0579)
		(width 0.1778)
		(layer "B.Cu")
		(net "M_B_DQS_DP4")
	)
	(segment
		(start 172.602398 -6.0579)
		(end 172.86732 -5.792978)
		(width 0.1778)
		(layer "B.Cu")
		(net "M_B_DQS_DP4")
	)
	(segment
		(start 172.749972 -9.12495)
		(end 172.602398 -8.977376)
		(width 0.1778)
		(layer "B.Cu")
		(net "M_B_DQS_DP4")
	)
	(segment
		(start 172.749972 -9.89076)
		(end 172.749972 -9.12495)
		(width 0.1778)
		(layer "B.Cu")
		(net "M_B_DQS_DP4")
	)
	(segment
		(start 114.2746 -27.9654)
		(end 114.0206 -28.2194)
		(width 0.1524)
		(layer "In4.Cu")
		(net "M_B_DQS_DP4")
	)
	(segment
		(start 110.105952 -30.495494)
		(end 110.105952 -28.7909)
		(width 0.1016)
		(layer "In4.Cu")
		(net "M_B_DQS_DP4")
	)
	(segment
		(start 114.0206 -28.2194)
		(end 111.76 -28.2194)
		(width 0.1524)
		(layer "In4.Cu")
		(net "M_B_DQS_DP4")
	)
	(segment
		(start 109.445044 -31.156402)
		(end 110.105952 -30.495494)
		(width 0.1016)
		(layer "In4.Cu")
		(net "M_B_DQS_DP4")
	)
	(segment
		(start 172.589698 -12.522454)
		(end 167.535352 -17.5768)
		(width 0.1524)
		(layer "In4.Cu")
		(net "M_B_DQS_DP4")
	)
	(segment
		(start 167.535352 -17.5768)
		(end 166.585138 -17.5768)
		(width 0.1524)
		(layer "In4.Cu")
		(net "M_B_DQS_DP4")
	)
	(segment
		(start 107.6706 -33.401)
		(end 107.3912 -33.1216)
		(width 0.1016)
		(layer "In4.Cu")
		(net "M_B_DQS_DP4")
	)
	(segment
		(start 111.726726 -28.186126)
		(end 111.76 -28.2194)
		(width 0.1016)
		(layer "In4.Cu")
		(net "M_B_DQS_DP4")
	)
	(segment
		(start 107.3912 -33.1216)
		(end 107.3912 -32.9692)
		(width 0.1016)
		(layer "In4.Cu")
		(net "M_B_DQS_DP4")
	)
	(segment
		(start 108.738416 -31.156402)
		(end 109.445044 -31.156402)
		(width 0.1016)
		(layer "In4.Cu")
		(net "M_B_DQS_DP4")
	)
	(segment
		(start 107.305348 -31.4706)
		(end 108.424218 -31.4706)
		(width 0.1016)
		(layer "In4.Cu")
		(net "M_B_DQS_DP4")
	)
	(segment
		(start 156.774134 -26.88209)
		(end 156.774134 -27.387804)
		(width 0.1524)
		(layer "In4.Cu")
		(net "M_B_DQS_DP4")
	)
	(segment
		(start 110.105952 -28.7909)
		(end 110.710726 -28.186126)
		(width 0.1016)
		(layer "In4.Cu")
		(net "M_B_DQS_DP4")
	)
	(segment
		(start 107.3912 -32.9692)
		(end 106.8832 -32.4612)
		(width 0.1016)
		(layer "In4.Cu")
		(net "M_B_DQS_DP4")
	)
	(segment
		(start 156.774134 -27.387804)
		(end 156.196538 -27.9654)
		(width 0.1524)
		(layer "In4.Cu")
		(net "M_B_DQS_DP4")
	)
	(segment
		(start 106.8832 -32.4612)
		(end 106.8832 -31.892748)
		(width 0.1016)
		(layer "In4.Cu")
		(net "M_B_DQS_DP4")
	)
	(segment
		(start 172.86732 -5.792978)
		(end 172.589698 -6.0706)
		(width 0.1524)
		(layer "In4.Cu")
		(net "M_B_DQS_DP4")
	)
	(segment
		(start 108.424218 -31.4706)
		(end 108.738416 -31.156402)
		(width 0.1016)
		(layer "In4.Cu")
		(net "M_B_DQS_DP4")
	)
	(segment
		(start 172.589698 -6.0706)
		(end 172.589698 -12.522454)
		(width 0.1524)
		(layer "In4.Cu")
		(net "M_B_DQS_DP4")
	)
	(segment
		(start 166.585138 -17.5768)
		(end 157.574488 -26.58745)
		(width 0.1524)
		(layer "In4.Cu")
		(net "M_B_DQS_DP4")
	)
	(segment
		(start 106.8832 -31.892748)
		(end 107.305348 -31.4706)
		(width 0.1016)
		(layer "In4.Cu")
		(net "M_B_DQS_DP4")
	)
	(segment
		(start 110.710726 -28.186126)
		(end 111.726726 -28.186126)
		(width 0.1016)
		(layer "In4.Cu")
		(net "M_B_DQS_DP4")
	)
	(segment
		(start 157.574488 -26.58745)
		(end 157.068774 -26.58745)
		(width 0.1524)
		(layer "In4.Cu")
		(net "M_B_DQS_DP4")
	)
	(segment
		(start 157.068774 -26.58745)
		(end 156.774134 -26.88209)
		(width 0.1524)
		(layer "In4.Cu")
		(net "M_B_DQS_DP4")
	)
	(segment
		(start 156.196538 -27.9654)
		(end 114.2746 -27.9654)
		(width 0.1524)
		(layer "In4.Cu")
		(net "M_B_DQS_DP4")
	)
	(segment
		(start 87.62492 -33.426654)
		(end 87.673688 -33.426654)
		(width 0.1143)
		(layer "F.Cu")
		(net "SPI_CLK_GBE")
	)
	(segment
		(start 61.339984 -18.117312)
		(end 61.002672 -17.78)
		(width 0.1143)
		(layer "F.Cu")
		(net "SPI_CLK_GBE")
	)
	(segment
		(start 61.002672 -17.78)
		(end 60.2488 -17.78)
		(width 0.1143)
		(layer "F.Cu")
		(net "SPI_CLK_GBE")
	)
	(segment
		(start 87.14232 -33.909)
		(end 87.62492 -33.426654)
		(width 0.1143)
		(layer "F.Cu")
		(net "SPI_CLK_GBE")
	)
	(segment
		(start 61.7728 -18.550128)
		(end 61.339984 -18.117312)
		(width 0.1143)
		(layer "F.Cu")
		(net "SPI_CLK_GBE")
	)
	(segment
		(start 61.7728 -18.7198)
		(end 61.7728 -18.550128)
		(width 0.1143)
		(layer "F.Cu")
		(net "SPI_CLK_GBE")
	)
	(segment
		(start 87.003382 -33.990788)
		(end 87.060532 -33.990788)
		(width 0.1143)
		(layer "F.Cu")
		(net "SPI_CLK_GBE")
	)
	(segment
		(start 87.060532 -33.990788)
		(end 87.14232 -33.909)
		(width 0.1143)
		(layer "F.Cu")
		(net "SPI_CLK_GBE")
	)
	(via
		(at 61.339984 -18.117312)
		(size 0.7112)
		(drill 0.3556)
		(layers "F.Cu" "B.Cu")
		(net "SPI_CLK_GBE")
	)
	(via
		(at 87.003382 -33.990788)
		(size 0.4318)
		(drill 0.2032)
		(layers "F.Cu" "B.Cu")
		(net "SPI_CLK_GBE")
	)
	(via
		(at 61.7728 -18.7198)
		(size 0.508)
		(drill 0.254)
		(layers "F.Cu" "B.Cu")
		(net "SPI_CLK_GBE")
	)
	(segment
		(start 86.308692 -33.984692)
		(end 85.916262 -33.592262)
		(width 0.0889)
		(layer "In7.Cu")
		(net "SPI_CLK_GBE")
	)
	(segment
		(start 66.781172 -21.8821)
		(end 64.812418 -21.8821)
		(width 0.0889)
		(layer "In7.Cu")
		(net "SPI_CLK_GBE")
	)
	(segment
		(start 87.003382 -33.990788)
		(end 86.997286 -33.984692)
		(width 0.0889)
		(layer "In7.Cu")
		(net "SPI_CLK_GBE")
	)
	(segment
		(start 61.7728 -18.842482)
		(end 61.7728 -18.7198)
		(width 0.0889)
		(layer "In7.Cu")
		(net "SPI_CLK_GBE")
	)
	(segment
		(start 82.510376 -33.407858)
		(end 82.402172 -33.516062)
		(width 0.0889)
		(layer "In7.Cu")
		(net "SPI_CLK_GBE")
	)
	(segment
		(start 76.720446 -28.528772)
		(end 74.741024 -26.54935)
		(width 0.0889)
		(layer "In7.Cu")
		(net "SPI_CLK_GBE")
	)
	(segment
		(start 74.741024 -26.54935)
		(end 71.448422 -26.54935)
		(width 0.0889)
		(layer "In7.Cu")
		(net "SPI_CLK_GBE")
	)
	(segment
		(start 79.644494 -32.766)
		(end 79.142082 -32.766)
		(width 0.0889)
		(layer "In7.Cu")
		(net "SPI_CLK_GBE")
	)
	(segment
		(start 82.968592 -33.407858)
		(end 82.510376 -33.407858)
		(width 0.0889)
		(layer "In7.Cu")
		(net "SPI_CLK_GBE")
	)
	(segment
		(start 71.448422 -26.54935)
		(end 66.781172 -21.8821)
		(width 0.0889)
		(layer "In7.Cu")
		(net "SPI_CLK_GBE")
	)
	(segment
		(start 83.152996 -33.592262)
		(end 82.968592 -33.407858)
		(width 0.0889)
		(layer "In7.Cu")
		(net "SPI_CLK_GBE")
	)
	(segment
		(start 64.812418 -21.8821)
		(end 61.7728 -18.842482)
		(width 0.0889)
		(layer "In7.Cu")
		(net "SPI_CLK_GBE")
	)
	(segment
		(start 86.997286 -33.984692)
		(end 86.308692 -33.984692)
		(width 0.0889)
		(layer "In7.Cu")
		(net "SPI_CLK_GBE")
	)
	(segment
		(start 85.916262 -33.592262)
		(end 83.152996 -33.592262)
		(width 0.0889)
		(layer "In7.Cu")
		(net "SPI_CLK_GBE")
	)
	(segment
		(start 82.402172 -33.516062)
		(end 80.394556 -33.516062)
		(width 0.0889)
		(layer "In7.Cu")
		(net "SPI_CLK_GBE")
	)
	(segment
		(start 79.142082 -32.766)
		(end 76.720446 -30.344364)
		(width 0.0889)
		(layer "In7.Cu")
		(net "SPI_CLK_GBE")
	)
	(segment
		(start 76.720446 -30.344364)
		(end 76.720446 -28.528772)
		(width 0.0889)
		(layer "In7.Cu")
		(net "SPI_CLK_GBE")
	)
	(segment
		(start 80.394556 -33.516062)
		(end 79.644494 -32.766)
		(width 0.0889)
		(layer "In7.Cu")
		(net "SPI_CLK_GBE")
	)
	(segment
		(start 189.456314 -36.376102)
		(end 189.456314 -36.802314)
		(width 0.2032)
		(layer "F.Cu")
		(net "VR_PVDDR_A_PROG2")
	)
	(segment
		(start 189.456314 -36.802314)
		(end 191.135 -38.481)
		(width 0.2032)
		(layer "F.Cu")
		(net "VR_PVDDR_A_PROG2")
	)
	(segment
		(start 191.643 -38.989)
		(end 191.135 -38.481)
		(width 0.2032)
		(layer "F.Cu")
		(net "VR_PVDDR_A_PROG2")
	)
	(segment
		(start 191.643 -39.4462)
		(end 191.643 -38.989)
		(width 0.2032)
		(layer "F.Cu")
		(net "VR_PVDDR_A_PROG2")
	)
	(via
		(at 191.135 -38.481)
		(size 0.7112)
		(drill 0.3556)
		(layers "F.Cu" "B.Cu")
		(net "VR_PVDDR_A_PROG2")
	)
	(segment
		(start 107.76585 -25.770078)
		(end 107.744768 -25.79116)
		(width 0.1016)
		(layer "F.Cu")
		(net "M_B_ECC2")
	)
	(segment
		(start 107.744768 -25.83561)
		(end 107.312968 -26.26741)
		(width 0.1016)
		(layer "F.Cu")
		(net "M_B_ECC2")
	)
	(segment
		(start 107.312968 -26.26741)
		(end 107.312968 -26.741374)
		(width 0.1016)
		(layer "F.Cu")
		(net "M_B_ECC2")
	)
	(segment
		(start 154.450034 -9.028684)
		(end 154.747976 -8.730488)
		(width 0.1778)
		(layer "F.Cu")
		(net "M_B_ECC2")
	)
	(segment
		(start 107.76585 -23.76805)
		(end 107.76585 -25.770078)
		(width 0.1016)
		(layer "F.Cu")
		(net "M_B_ECC2")
	)
	(segment
		(start 107.188 -23.1902)
		(end 107.76585 -23.76805)
		(width 0.1016)
		(layer "F.Cu")
		(net "M_B_ECC2")
	)
	(segment
		(start 154.450034 -9.897364)
		(end 154.450034 -9.028684)
		(width 0.1778)
		(layer "F.Cu")
		(net "M_B_ECC2")
	)
	(segment
		(start 107.312968 -26.741374)
		(end 106.754168 -27.300174)
		(width 0.1016)
		(layer "F.Cu")
		(net "M_B_ECC2")
	)
	(segment
		(start 154.747976 -8.730488)
		(end 154.747976 -8.242554)
		(width 0.1778)
		(layer "F.Cu")
		(net "M_B_ECC2")
	)
	(segment
		(start 154.747976 -8.242554)
		(end 154.3812 -7.875778)
		(width 0.1778)
		(layer "F.Cu")
		(net "M_B_ECC2")
	)
	(segment
		(start 154.3812 -7.875778)
		(end 154.3812 -7.723378)
		(width 0.1778)
		(layer "F.Cu")
		(net "M_B_ECC2")
	)
	(segment
		(start 107.744768 -25.79116)
		(end 107.744768 -25.83561)
		(width 0.1016)
		(layer "F.Cu")
		(net "M_B_ECC2")
	)
	(via
		(at 107.188 -23.1902)
		(size 0.4318)
		(drill 0.2032)
		(layers "F.Cu" "B.Cu")
		(net "M_B_ECC2")
	)
	(via
		(at 154.3812 -7.723378)
		(size 0.4318)
		(drill 0.2032)
		(layers "F.Cu" "B.Cu")
		(net "M_B_ECC2")
	)
	(segment
		(start 154.747976 -8.645652)
		(end 154.747976 -8.090154)
		(width 0.1778)
		(layer "B.Cu")
		(net "M_B_ECC2")
	)
	(segment
		(start 154.750008 -8.647684)
		(end 154.747976 -8.645652)
		(width 0.1778)
		(layer "B.Cu")
		(net "M_B_ECC2")
	)
	(segment
		(start 154.747976 -8.090154)
		(end 154.3812 -7.723378)
		(width 0.1778)
		(layer "B.Cu")
		(net "M_B_ECC2")
	)
	(segment
		(start 154.750008 -9.89076)
		(end 154.750008 -8.647684)
		(width 0.1778)
		(layer "B.Cu")
		(net "M_B_ECC2")
	)
	(segment
		(start 126.153164 -21.463)
		(end 151.257 -21.463)
		(width 0.1524)
		(layer "In2.Cu")
		(net "M_B_ECC2")
	)
	(segment
		(start 110.871 -23.954486)
		(end 123.661678 -23.954486)
		(width 0.1524)
		(layer "In2.Cu")
		(net "M_B_ECC2")
	)
	(segment
		(start 154.3558 -12.4206)
		(end 153.9494 -12.0142)
		(width 0.1524)
		(layer "In2.Cu")
		(net "M_B_ECC2")
	)
	(segment
		(start 110.871 -23.954486)
		(end 110.030514 -23.114)
		(width 0.1016)
		(layer "In2.Cu")
		(net "M_B_ECC2")
	)
	(segment
		(start 154.5082 -15.459964)
		(end 154.5082 -15.155164)
		(width 0.1524)
		(layer "In2.Cu")
		(net "M_B_ECC2")
	)
	(segment
		(start 154.1018 -16.221964)
		(end 153.9494 -16.069564)
		(width 0.1524)
		(layer "In2.Cu")
		(net "M_B_ECC2")
	)
	(segment
		(start 153.9494 -16.069564)
		(end 153.9494 -15.764764)
		(width 0.1524)
		(layer "In2.Cu")
		(net "M_B_ECC2")
	)
	(segment
		(start 110.030514 -23.114)
		(end 107.2642 -23.114)
		(width 0.1016)
		(layer "In2.Cu")
		(net "M_B_ECC2")
	)
	(segment
		(start 154.5082 -14.240764)
		(end 154.5082 -13.935964)
		(width 0.1524)
		(layer "In2.Cu")
		(net "M_B_ECC2")
	)
	(segment
		(start 154.3558 -15.612364)
		(end 154.5082 -15.459964)
		(width 0.1524)
		(layer "In2.Cu")
		(net "M_B_ECC2")
	)
	(segment
		(start 154.1018 -16.831564)
		(end 154.3558 -16.831564)
		(width 0.1524)
		(layer "In2.Cu")
		(net "M_B_ECC2")
	)
	(segment
		(start 153.9494 -13.631164)
		(end 153.9494 -13.2588)
		(width 0.1524)
		(layer "In2.Cu")
		(net "M_B_ECC2")
	)
	(segment
		(start 153.9494 -13.2588)
		(end 154.3558 -12.8524)
		(width 0.1524)
		(layer "In2.Cu")
		(net "M_B_ECC2")
	)
	(segment
		(start 154.3558 -15.002764)
		(end 154.1018 -15.002764)
		(width 0.1524)
		(layer "In2.Cu")
		(net "M_B_ECC2")
	)
	(segment
		(start 154.5082 -16.374364)
		(end 154.3558 -16.221964)
		(width 0.1524)
		(layer "In2.Cu")
		(net "M_B_ECC2")
	)
	(segment
		(start 154.3558 -12.8524)
		(end 154.3558 -12.4206)
		(width 0.1524)
		(layer "In2.Cu")
		(net "M_B_ECC2")
	)
	(segment
		(start 154.3558 -14.393164)
		(end 154.5082 -14.240764)
		(width 0.1524)
		(layer "In2.Cu")
		(net "M_B_ECC2")
	)
	(segment
		(start 154.3558 -13.783564)
		(end 154.1018 -13.783564)
		(width 0.1524)
		(layer "In2.Cu")
		(net "M_B_ECC2")
	)
	(segment
		(start 154.1018 -13.783564)
		(end 153.9494 -13.631164)
		(width 0.1524)
		(layer "In2.Cu")
		(net "M_B_ECC2")
	)
	(segment
		(start 154.3558 -16.831564)
		(end 154.5082 -16.679164)
		(width 0.1524)
		(layer "In2.Cu")
		(net "M_B_ECC2")
	)
	(segment
		(start 154.75204 -8.72236)
		(end 154.75204 -8.246618)
		(width 0.1524)
		(layer "In2.Cu")
		(net "M_B_ECC2")
	)
	(segment
		(start 123.661678 -23.954486)
		(end 126.153164 -21.463)
		(width 0.1524)
		(layer "In2.Cu")
		(net "M_B_ECC2")
	)
	(segment
		(start 153.9494 -15.764764)
		(end 154.1018 -15.612364)
		(width 0.1524)
		(layer "In2.Cu")
		(net "M_B_ECC2")
	)
	(segment
		(start 154.1018 -15.612364)
		(end 154.3558 -15.612364)
		(width 0.1524)
		(layer "In2.Cu")
		(net "M_B_ECC2")
	)
	(segment
		(start 107.2642 -23.114)
		(end 107.188 -23.1902)
		(width 0.1016)
		(layer "In2.Cu")
		(net "M_B_ECC2")
	)
	(segment
		(start 154.3558 -16.221964)
		(end 154.1018 -16.221964)
		(width 0.1524)
		(layer "In2.Cu")
		(net "M_B_ECC2")
	)
	(segment
		(start 154.5082 -13.935964)
		(end 154.3558 -13.783564)
		(width 0.1524)
		(layer "In2.Cu")
		(net "M_B_ECC2")
	)
	(segment
		(start 151.257 -21.463)
		(end 153.9494 -18.7706)
		(width 0.1524)
		(layer "In2.Cu")
		(net "M_B_ECC2")
	)
	(segment
		(start 154.75204 -8.246618)
		(end 154.3812 -7.875778)
		(width 0.1524)
		(layer "In2.Cu")
		(net "M_B_ECC2")
	)
	(segment
		(start 153.9494 -12.0142)
		(end 153.9494 -9.525)
		(width 0.1524)
		(layer "In2.Cu")
		(net "M_B_ECC2")
	)
	(segment
		(start 153.9494 -14.850364)
		(end 153.9494 -14.545564)
		(width 0.1524)
		(layer "In2.Cu")
		(net "M_B_ECC2")
	)
	(segment
		(start 153.9494 -14.545564)
		(end 154.1018 -14.393164)
		(width 0.1524)
		(layer "In2.Cu")
		(net "M_B_ECC2")
	)
	(segment
		(start 153.9494 -16.983964)
		(end 154.1018 -16.831564)
		(width 0.1524)
		(layer "In2.Cu")
		(net "M_B_ECC2")
	)
	(segment
		(start 154.5082 -16.679164)
		(end 154.5082 -16.374364)
		(width 0.1524)
		(layer "In2.Cu")
		(net "M_B_ECC2")
	)
	(segment
		(start 153.9494 -9.525)
		(end 154.75204 -8.72236)
		(width 0.1524)
		(layer "In2.Cu")
		(net "M_B_ECC2")
	)
	(segment
		(start 153.9494 -18.7706)
		(end 153.9494 -16.983964)
		(width 0.1524)
		(layer "In2.Cu")
		(net "M_B_ECC2")
	)
	(segment
		(start 154.1018 -14.393164)
		(end 154.3558 -14.393164)
		(width 0.1524)
		(layer "In2.Cu")
		(net "M_B_ECC2")
	)
	(segment
		(start 154.5082 -15.155164)
		(end 154.3558 -15.002764)
		(width 0.1524)
		(layer "In2.Cu")
		(net "M_B_ECC2")
	)
	(segment
		(start 154.3812 -7.875778)
		(end 154.3812 -7.723378)
		(width 0.1524)
		(layer "In2.Cu")
		(net "M_B_ECC2")
	)
	(segment
		(start 154.1018 -15.002764)
		(end 153.9494 -14.850364)
		(width 0.1524)
		(layer "In2.Cu")
		(net "M_B_ECC2")
	)
	(via
		(at 202.9968 -26.1112)
		(size 0.7112)
		(drill 0.4064)
		(layers "F.Cu" "B.Cu")
		(net "PVDDR_VIN")
	)
	(via
		(at 198.882 -23.622)
		(size 0.7112)
		(drill 0.4064)
		(layers "F.Cu" "B.Cu")
		(net "PVDDR_VIN")
	)
	(via
		(at 202.946 -27.2034)
		(size 0.7112)
		(drill 0.4064)
		(layers "F.Cu" "B.Cu")
		(net "PVDDR_VIN")
	)
	(via
		(at 202.9968 -25.0444)
		(size 0.7112)
		(drill 0.4064)
		(layers "F.Cu" "B.Cu")
		(net "PVDDR_VIN")
	)
	(via
		(at 200.025 -23.622)
		(size 0.7112)
		(drill 0.4064)
		(layers "F.Cu" "B.Cu")
		(net "PVDDR_VIN")
	)
	(via
		(at 204.089 -29.6418)
		(size 0.7112)
		(drill 0.4064)
		(layers "F.Cu" "B.Cu")
		(net "PVDDR_VIN")
	)
	(via
		(at 204.089 -28.575)
		(size 0.7112)
		(drill 0.4064)
		(layers "F.Cu" "B.Cu")
		(net "PVDDR_VIN")
	)
	(via
		(at 204.216 -24.765)
		(size 0.7112)
		(drill 0.3556)
		(layers "F.Cu" "B.Cu")
		(net "PVDDR_VIN")
	)
	(via
		(at 203.9874 -26.924)
		(size 0.7112)
		(drill 0.4064)
		(layers "F.Cu" "B.Cu")
		(net "PVDDR_VIN")
	)
	(via
		(at 202.946 -29.4894)
		(size 0.7112)
		(drill 0.4064)
		(layers "F.Cu" "B.Cu")
		(net "PVDDR_VIN")
	)
	(via
		(at 202.946 -28.4226)
		(size 0.7112)
		(drill 0.4064)
		(layers "F.Cu" "B.Cu")
		(net "PVDDR_VIN")
	)
	(segment
		(start 180.550058 -3.243326)
		(end 180.894228 -3.587496)
		(width 0.1778)
		(layer "F.Cu")
		(net "M_B_DQ53")
	)
	(segment
		(start 105.385108 -35.697414)
		(end 105.019094 -35.3314)
		(width 0.1016)
		(layer "F.Cu")
		(net "M_B_DQ53")
	)
	(segment
		(start 105.019094 -35.3314)
		(end 104.9782 -35.3314)
		(width 0.1016)
		(layer "F.Cu")
		(net "M_B_DQ53")
	)
	(segment
		(start 180.550058 -1.68402)
		(end 180.550058 -3.243326)
		(width 0.1778)
		(layer "F.Cu")
		(net "M_B_DQ53")
	)
	(via
		(at 180.894228 -3.587496)
		(size 0.4318)
		(drill 0.2032)
		(layers "F.Cu" "B.Cu")
		(net "M_B_DQ53")
	)
	(via
		(at 104.9782 -35.3314)
		(size 0.4318)
		(drill 0.2032)
		(layers "F.Cu" "B.Cu")
		(net "M_B_DQ53")
	)
	(segment
		(start 180.850032 -1.690624)
		(end 180.850032 -3.5433)
		(width 0.1778)
		(layer "B.Cu")
		(net "M_B_DQ53")
	)
	(segment
		(start 180.850032 -3.5433)
		(end 180.894228 -3.587496)
		(width 0.1778)
		(layer "B.Cu")
		(net "M_B_DQ53")
	)
	(segment
		(start 114.1476 -33.8582)
		(end 110.869476 -33.8582)
		(width 0.1524)
		(layer "In9.Cu")
		(net "M_B_DQ53")
	)
	(segment
		(start 148.7678 -32.5882)
		(end 148.3614 -32.1818)
		(width 0.1524)
		(layer "In9.Cu")
		(net "M_B_DQ53")
	)
	(segment
		(start 105.029 -35.2806)
		(end 105.029 -34.544)
		(width 0.1016)
		(layer "In9.Cu")
		(net "M_B_DQ53")
	)
	(segment
		(start 109.609128 -33.8582)
		(end 110.869476 -33.8582)
		(width 0.1016)
		(layer "In9.Cu")
		(net "M_B_DQ53")
	)
	(segment
		(start 119.507 -34.4678)
		(end 114.7572 -34.4678)
		(width 0.1524)
		(layer "In9.Cu")
		(net "M_B_DQ53")
	)
	(segment
		(start 140.5636 -31.9786)
		(end 140.2588 -31.9786)
		(width 0.1524)
		(layer "In9.Cu")
		(net "M_B_DQ53")
	)
	(segment
		(start 145.7198 -31.9786)
		(end 144.511776 -31.9786)
		(width 0.1524)
		(layer "In9.Cu")
		(net "M_B_DQ53")
	)
	(segment
		(start 144.206976 -32.2834)
		(end 143.902176 -32.2834)
		(width 0.1524)
		(layer "In9.Cu")
		(net "M_B_DQ53")
	)
	(segment
		(start 141.3256 -32.474662)
		(end 141.1732 -32.627062)
		(width 0.1524)
		(layer "In9.Cu")
		(net "M_B_DQ53")
	)
	(segment
		(start 139.4968 -32.131)
		(end 139.3444 -31.9786)
		(width 0.1524)
		(layer "In9.Cu")
		(net "M_B_DQ53")
	)
	(segment
		(start 137.1854 -33.5534)
		(end 120.4214 -33.5534)
		(width 0.1524)
		(layer "In9.Cu")
		(net "M_B_DQ53")
	)
	(segment
		(start 147.5232 -32.1818)
		(end 147.1168 -32.5882)
		(width 0.1524)
		(layer "In9.Cu")
		(net "M_B_DQ53")
	)
	(segment
		(start 177.5206 -9.977628)
		(end 176.271428 -11.2268)
		(width 0.1524)
		(layer "In9.Cu")
		(net "M_B_DQ53")
	)
	(segment
		(start 140.716 -32.474662)
		(end 140.716 -32.131)
		(width 0.1524)
		(layer "In9.Cu")
		(net "M_B_DQ53")
	)
	(segment
		(start 141.3256 -32.131)
		(end 141.3256 -32.474662)
		(width 0.1524)
		(layer "In9.Cu")
		(net "M_B_DQ53")
	)
	(segment
		(start 141.1732 -32.627062)
		(end 140.8684 -32.627062)
		(width 0.1524)
		(layer "In9.Cu")
		(net "M_B_DQ53")
	)
	(segment
		(start 105.5624 -34.0106)
		(end 109.456728 -34.0106)
		(width 0.1016)
		(layer "In9.Cu")
		(net "M_B_DQ53")
	)
	(segment
		(start 153.808684 -32.3342)
		(end 153.808684 -32.4358)
		(width 0.1524)
		(layer "In9.Cu")
		(net "M_B_DQ53")
	)
	(segment
		(start 139.954 -32.627062)
		(end 139.6492 -32.627062)
		(width 0.1524)
		(layer "In9.Cu")
		(net "M_B_DQ53")
	)
	(segment
		(start 140.716 -32.131)
		(end 140.5636 -31.9786)
		(width 0.1524)
		(layer "In9.Cu")
		(net "M_B_DQ53")
	)
	(segment
		(start 154.570684 -32.5882)
		(end 154.418284 -32.4358)
		(width 0.1524)
		(layer "In9.Cu")
		(net "M_B_DQ53")
	)
	(segment
		(start 154.265884 -32.1818)
		(end 153.961084 -32.1818)
		(width 0.1524)
		(layer "In9.Cu")
		(net "M_B_DQ53")
	)
	(segment
		(start 140.1064 -32.131)
		(end 140.1064 -32.474662)
		(width 0.1524)
		(layer "In9.Cu")
		(net "M_B_DQ53")
	)
	(segment
		(start 146.3294 -32.5882)
		(end 145.7198 -31.9786)
		(width 0.1524)
		(layer "In9.Cu")
		(net "M_B_DQ53")
	)
	(segment
		(start 140.8684 -32.627062)
		(end 140.716 -32.474662)
		(width 0.1524)
		(layer "In9.Cu")
		(net "M_B_DQ53")
	)
	(segment
		(start 177.5206 -7.520178)
		(end 177.5206 -9.977628)
		(width 0.1524)
		(layer "In9.Cu")
		(net "M_B_DQ53")
	)
	(segment
		(start 141.478 -31.9786)
		(end 141.3256 -32.131)
		(width 0.1524)
		(layer "In9.Cu")
		(net "M_B_DQ53")
	)
	(segment
		(start 114.7572 -34.4678)
		(end 114.1476 -33.8582)
		(width 0.1524)
		(layer "In9.Cu")
		(net "M_B_DQ53")
	)
	(segment
		(start 139.3444 -31.9786)
		(end 138.7602 -31.9786)
		(width 0.1524)
		(layer "In9.Cu")
		(net "M_B_DQ53")
	)
	(segment
		(start 176.271428 -11.2268)
		(end 176.271428 -14.901418)
		(width 0.1524)
		(layer "In9.Cu")
		(net "M_B_DQ53")
	)
	(segment
		(start 140.2588 -31.9786)
		(end 140.1064 -32.131)
		(width 0.1524)
		(layer "In9.Cu")
		(net "M_B_DQ53")
	)
	(segment
		(start 148.3614 -32.1818)
		(end 147.5232 -32.1818)
		(width 0.1524)
		(layer "In9.Cu")
		(net "M_B_DQ53")
	)
	(segment
		(start 104.9782 -35.3314)
		(end 105.029 -35.2806)
		(width 0.1016)
		(layer "In9.Cu")
		(net "M_B_DQ53")
	)
	(segment
		(start 139.4968 -32.474662)
		(end 139.4968 -32.131)
		(width 0.1524)
		(layer "In9.Cu")
		(net "M_B_DQ53")
	)
	(segment
		(start 180.6702 -3.811778)
		(end 180.6702 -4.370578)
		(width 0.1524)
		(layer "In9.Cu")
		(net "M_B_DQ53")
	)
	(segment
		(start 153.961084 -32.1818)
		(end 153.808684 -32.3342)
		(width 0.1524)
		(layer "In9.Cu")
		(net "M_B_DQ53")
	)
	(segment
		(start 138.7602 -31.9786)
		(end 137.1854 -33.5534)
		(width 0.1524)
		(layer "In9.Cu")
		(net "M_B_DQ53")
	)
	(segment
		(start 180.894228 -3.587496)
		(end 180.894228 -3.58775)
		(width 0.1524)
		(layer "In9.Cu")
		(net "M_B_DQ53")
	)
	(segment
		(start 153.808684 -32.4358)
		(end 153.656284 -32.5882)
		(width 0.1524)
		(layer "In9.Cu")
		(net "M_B_DQ53")
	)
	(segment
		(start 143.597376 -31.9786)
		(end 141.478 -31.9786)
		(width 0.1524)
		(layer "In9.Cu")
		(net "M_B_DQ53")
	)
	(segment
		(start 147.1168 -32.5882)
		(end 146.3294 -32.5882)
		(width 0.1524)
		(layer "In9.Cu")
		(net "M_B_DQ53")
	)
	(segment
		(start 158.584646 -32.5882)
		(end 154.570684 -32.5882)
		(width 0.1524)
		(layer "In9.Cu")
		(net "M_B_DQ53")
	)
	(segment
		(start 139.6492 -32.627062)
		(end 139.4968 -32.474662)
		(width 0.1524)
		(layer "In9.Cu")
		(net "M_B_DQ53")
	)
	(segment
		(start 143.902176 -32.2834)
		(end 143.597376 -31.9786)
		(width 0.1524)
		(layer "In9.Cu")
		(net "M_B_DQ53")
	)
	(segment
		(start 180.6702 -4.370578)
		(end 177.5206 -7.520178)
		(width 0.1524)
		(layer "In9.Cu")
		(net "M_B_DQ53")
	)
	(segment
		(start 154.418284 -32.3342)
		(end 154.265884 -32.1818)
		(width 0.1524)
		(layer "In9.Cu")
		(net "M_B_DQ53")
	)
	(segment
		(start 154.418284 -32.4358)
		(end 154.418284 -32.3342)
		(width 0.1524)
		(layer "In9.Cu")
		(net "M_B_DQ53")
	)
	(segment
		(start 153.656284 -32.5882)
		(end 148.7678 -32.5882)
		(width 0.1524)
		(layer "In9.Cu")
		(net "M_B_DQ53")
	)
	(segment
		(start 120.4214 -33.5534)
		(end 119.507 -34.4678)
		(width 0.1524)
		(layer "In9.Cu")
		(net "M_B_DQ53")
	)
	(segment
		(start 140.1064 -32.474662)
		(end 139.954 -32.627062)
		(width 0.1524)
		(layer "In9.Cu")
		(net "M_B_DQ53")
	)
	(segment
		(start 144.511776 -31.9786)
		(end 144.206976 -32.2834)
		(width 0.1524)
		(layer "In9.Cu")
		(net "M_B_DQ53")
	)
	(segment
		(start 105.029 -34.544)
		(end 105.5624 -34.0106)
		(width 0.1016)
		(layer "In9.Cu")
		(net "M_B_DQ53")
	)
	(segment
		(start 109.456728 -34.0106)
		(end 109.609128 -33.8582)
		(width 0.1016)
		(layer "In9.Cu")
		(net "M_B_DQ53")
	)
	(segment
		(start 180.894228 -3.58775)
		(end 180.6702 -3.811778)
		(width 0.1524)
		(layer "In9.Cu")
		(net "M_B_DQ53")
	)
	(segment
		(start 176.271428 -14.901418)
		(end 158.584646 -32.5882)
		(width 0.1524)
		(layer "In9.Cu")
		(net "M_B_DQ53")
	)
	(segment
		(start 192.5574 -36.6014)
		(end 192.9638 -37.0078)
		(width 0.4572)
		(layer "F.Cu")
		(net "VR_PVDDR_A_VDDP")
	)
	(segment
		(start 193.8782 -37.0586)
		(end 193.8782 -37.7698)
		(width 0.4572)
		(layer "F.Cu")
		(net "VR_PVDDR_A_VDDP")
	)
	(segment
		(start 192.9638 -37.0078)
		(end 192.9638 -37.0586)
		(width 0.4572)
		(layer "F.Cu")
		(net "VR_PVDDR_A_VDDP")
	)
	(segment
		(start 192.278 -36.322)
		(end 192.5574 -36.6014)
		(width 0.2032)
		(layer "F.Cu")
		(net "VR_PVDDR_A_VDDP")
	)
	(segment
		(start 192.278 -35.614356)
		(end 192.278 -36.322)
		(width 0.2032)
		(layer "F.Cu")
		(net "VR_PVDDR_A_VDDP")
	)
	(segment
		(start 193.8782 -37.7698)
		(end 194.183 -38.0746)
		(width 0.4572)
		(layer "F.Cu")
		(net "VR_PVDDR_A_VDDP")
	)
	(segment
		(start 191.656716 -35.37585)
		(end 192.039494 -35.37585)
		(width 0.2032)
		(layer "F.Cu")
		(net "VR_PVDDR_A_VDDP")
	)
	(segment
		(start 192.9638 -37.0586)
		(end 193.8782 -37.0586)
		(width 0.4572)
		(layer "F.Cu")
		(net "VR_PVDDR_A_VDDP")
	)
	(segment
		(start 192.039494 -35.37585)
		(end 192.278 -35.614356)
		(width 0.2032)
		(layer "F.Cu")
		(net "VR_PVDDR_A_VDDP")
	)
	(via
		(at 192.9638 -37.0586)
		(size 0.7112)
		(drill 0.3556)
		(layers "F.Cu" "B.Cu")
		(net "VR_PVDDR_A_VDDP")
	)
	(segment
		(start 42.6466 -27.1018)
		(end 42.51833 -26.97353)
		(width 0.1397)
		(layer "B.Cu")
		(net "CLK_100M_CLKBUFF_PCIE_R_DP")
	)
	(segment
		(start 42.51833 -26.97353)
		(end 42.51833 -25.8445)
		(width 0.1397)
		(layer "B.Cu")
		(net "CLK_100M_CLKBUFF_PCIE_R_DP")
	)
	(segment
		(start 193.421 -36.2966)
		(end 192.9638 -35.8394)
		(width 0.2032)
		(layer "F.Cu")
		(net "VR_PVDDR_A_PWM3")
	)
	(segment
		(start 192.10655 -34.9758)
		(end 192.9638 -35.83305)
		(width 0.2032)
		(layer "F.Cu")
		(net "VR_PVDDR_A_PWM3")
	)
	(segment
		(start 193.8782 -36.2966)
		(end 193.421 -36.2966)
		(width 0.2032)
		(layer "F.Cu")
		(net "VR_PVDDR_A_PWM3")
	)
	(segment
		(start 191.656716 -34.9758)
		(end 192.10655 -34.9758)
		(width 0.2032)
		(layer "F.Cu")
		(net "VR_PVDDR_A_PWM3")
	)
	(segment
		(start 192.9638 -35.83305)
		(end 192.9638 -35.8394)
		(width 0.2032)
		(layer "F.Cu")
		(net "VR_PVDDR_A_PWM3")
	)
	(via
		(at 192.9638 -35.8394)
		(size 0.7112)
		(drill 0.3556)
		(layers "F.Cu" "B.Cu")
		(net "VR_PVDDR_A_PWM3")
	)
	(segment
		(start 106.528108 -33.711134)
		(end 106.56443 -33.711134)
		(width 0.1016)
		(layer "F.Cu")
		(net "M_B_DQS_DN4")
	)
	(segment
		(start 172.150024 -2.402332)
		(end 172.297598 -2.549906)
		(width 0.1778)
		(layer "F.Cu")
		(net "M_B_DQS_DN4")
	)
	(segment
		(start 172.150024 -1.68402)
		(end 172.150024 -2.402332)
		(width 0.1778)
		(layer "F.Cu")
		(net "M_B_DQS_DN4")
	)
	(segment
		(start 106.56443 -33.711134)
		(end 106.919268 -33.356296)
		(width 0.1016)
		(layer "F.Cu")
		(net "M_B_DQS_DN4")
	)
	(segment
		(start 172.297598 -2.549906)
		(end 172.297598 -5.52831)
		(width 0.1778)
		(layer "F.Cu")
		(net "M_B_DQS_DN4")
	)
	(segment
		(start 172.297598 -5.52831)
		(end 172.03293 -5.792978)
		(width 0.1778)
		(layer "F.Cu")
		(net "M_B_DQS_DN4")
	)
	(via
		(at 106.919268 -33.356296)
		(size 0.4318)
		(drill 0.2032)
		(layers "F.Cu" "B.Cu")
		(net "M_B_DQS_DN4")
	)
	(via
		(at 172.03293 -5.792978)
		(size 0.4318)
		(drill 0.2032)
		(layers "F.Cu" "B.Cu")
		(net "M_B_DQS_DN4")
	)
	(segment
		(start 172.297598 -6.057646)
		(end 172.03293 -5.792978)
		(width 0.1778)
		(layer "B.Cu")
		(net "M_B_DQS_DN4")
	)
	(segment
		(start 172.150024 -9.156954)
		(end 172.297598 -9.00938)
		(width 0.1778)
		(layer "B.Cu")
		(net "M_B_DQS_DN4")
	)
	(segment
		(start 172.150024 -9.89076)
		(end 172.150024 -9.156954)
		(width 0.1778)
		(layer "B.Cu")
		(net "M_B_DQS_DN4")
	)
	(segment
		(start 172.297598 -9.00938)
		(end 172.297598 -6.057646)
		(width 0.1778)
		(layer "B.Cu")
		(net "M_B_DQS_DN4")
	)
	(segment
		(start 114.158776 -27.686)
		(end 113.904776 -27.94)
		(width 0.1524)
		(layer "In4.Cu")
		(net "M_B_DQS_DN4")
	)
	(segment
		(start 107.22102 -31.2674)
		(end 108.33989 -31.2674)
		(width 0.1016)
		(layer "In4.Cu")
		(net "M_B_DQS_DN4")
	)
	(segment
		(start 113.904776 -27.94)
		(end 111.76 -27.94)
		(width 0.1524)
		(layer "In4.Cu")
		(net "M_B_DQS_DN4")
	)
	(segment
		(start 106.68 -32.545528)
		(end 106.68 -31.80842)
		(width 0.1016)
		(layer "In4.Cu")
		(net "M_B_DQS_DN4")
	)
	(segment
		(start 108.654088 -30.953202)
		(end 109.360716 -30.953202)
		(width 0.1016)
		(layer "In4.Cu")
		(net "M_B_DQS_DN4")
	)
	(segment
		(start 172.310298 -12.40663)
		(end 167.419528 -17.2974)
		(width 0.1524)
		(layer "In4.Cu")
		(net "M_B_DQS_DN4")
	)
	(segment
		(start 156.080714 -27.686)
		(end 114.158776 -27.686)
		(width 0.1524)
		(layer "In4.Cu")
		(net "M_B_DQS_DN4")
	)
	(segment
		(start 106.68 -31.80842)
		(end 107.22102 -31.2674)
		(width 0.1016)
		(layer "In4.Cu")
		(net "M_B_DQS_DN4")
	)
	(segment
		(start 166.469314 -17.2974)
		(end 157.458664 -26.30805)
		(width 0.1524)
		(layer "In4.Cu")
		(net "M_B_DQS_DN4")
	)
	(segment
		(start 106.919268 -33.356296)
		(end 107.0356 -33.356296)
		(width 0.1016)
		(layer "In4.Cu")
		(net "M_B_DQS_DN4")
	)
	(segment
		(start 108.33989 -31.2674)
		(end 108.654088 -30.953202)
		(width 0.1016)
		(layer "In4.Cu")
		(net "M_B_DQS_DN4")
	)
	(segment
		(start 109.360716 -30.953202)
		(end 109.902752 -30.411166)
		(width 0.1016)
		(layer "In4.Cu")
		(net "M_B_DQS_DN4")
	)
	(segment
		(start 109.902752 -30.411166)
		(end 109.902752 -28.706572)
		(width 0.1016)
		(layer "In4.Cu")
		(net "M_B_DQS_DN4")
	)
	(segment
		(start 172.03293 -5.792978)
		(end 172.310298 -6.070346)
		(width 0.1524)
		(layer "In4.Cu")
		(net "M_B_DQS_DN4")
	)
	(segment
		(start 156.95295 -26.30805)
		(end 156.494734 -26.766266)
		(width 0.1524)
		(layer "In4.Cu")
		(net "M_B_DQS_DN4")
	)
	(segment
		(start 107.188 -33.203896)
		(end 107.188 -33.053528)
		(width 0.1016)
		(layer "In4.Cu")
		(net "M_B_DQS_DN4")
	)
	(segment
		(start 156.494734 -27.27198)
		(end 156.080714 -27.686)
		(width 0.1524)
		(layer "In4.Cu")
		(net "M_B_DQS_DN4")
	)
	(segment
		(start 110.626398 -27.982926)
		(end 111.717074 -27.982926)
		(width 0.1016)
		(layer "In4.Cu")
		(net "M_B_DQS_DN4")
	)
	(segment
		(start 167.419528 -17.2974)
		(end 166.469314 -17.2974)
		(width 0.1524)
		(layer "In4.Cu")
		(net "M_B_DQS_DN4")
	)
	(segment
		(start 172.310298 -6.070346)
		(end 172.310298 -12.40663)
		(width 0.1524)
		(layer "In4.Cu")
		(net "M_B_DQS_DN4")
	)
	(segment
		(start 107.0356 -33.356296)
		(end 107.188 -33.203896)
		(width 0.1016)
		(layer "In4.Cu")
		(net "M_B_DQS_DN4")
	)
	(segment
		(start 109.902752 -28.706572)
		(end 110.626398 -27.982926)
		(width 0.1016)
		(layer "In4.Cu")
		(net "M_B_DQS_DN4")
	)
	(segment
		(start 111.717074 -27.982926)
		(end 111.76 -27.94)
		(width 0.1016)
		(layer "In4.Cu")
		(net "M_B_DQS_DN4")
	)
	(segment
		(start 156.494734 -26.766266)
		(end 156.494734 -27.27198)
		(width 0.1524)
		(layer "In4.Cu")
		(net "M_B_DQS_DN4")
	)
	(segment
		(start 107.188 -33.053528)
		(end 106.68 -32.545528)
		(width 0.1016)
		(layer "In4.Cu")
		(net "M_B_DQS_DN4")
	)
	(segment
		(start 157.458664 -26.30805)
		(end 156.95295 -26.30805)
		(width 0.1524)
		(layer "In4.Cu")
		(net "M_B_DQS_DN4")
	)
	(segment
		(start 41.8846 -27.1018)
		(end 42.01795 -26.96845)
		(width 0.1397)
		(layer "B.Cu")
		(net "CLK_100M_CLKBUFF_PCIE_R_DN")
	)
	(segment
		(start 42.01795 -26.96845)
		(end 42.01795 -25.8445)
		(width 0.1397)
		(layer "B.Cu")
		(net "CLK_100M_CLKBUFF_PCIE_R_DN")
	)
	(segment
		(start 186.0042 -28.956)
		(end 187.0202 -29.972)
		(width 0.2032)
		(layer "F.Cu")
		(net "ISENSE_PVDDR_A_ISEN1")
	)
	(segment
		(start 186.0042 -27.2542)
		(end 186.0042 -28.956)
		(width 0.2032)
		(layer "F.Cu")
		(net "ISENSE_PVDDR_A_ISEN1")
	)
	(segment
		(start 189.056518 -31.575502)
		(end 189.056518 -31.11373)
		(width 0.2032)
		(layer "F.Cu")
		(net "ISENSE_PVDDR_A_ISEN1")
	)
	(segment
		(start 187.0202 -29.999432)
		(end 187.0202 -29.972)
		(width 0.2032)
		(layer "F.Cu")
		(net "ISENSE_PVDDR_A_ISEN1")
	)
	(segment
		(start 189.056518 -31.11373)
		(end 188.524388 -30.5816)
		(width 0.2032)
		(layer "F.Cu")
		(net "ISENSE_PVDDR_A_ISEN1")
	)
	(segment
		(start 187.602368 -30.5816)
		(end 187.0202 -29.999432)
		(width 0.2032)
		(layer "F.Cu")
		(net "ISENSE_PVDDR_A_ISEN1")
	)
	(segment
		(start 188.524388 -30.5816)
		(end 187.602368 -30.5816)
		(width 0.2032)
		(layer "F.Cu")
		(net "ISENSE_PVDDR_A_ISEN1")
	)
	(via
		(at 184.531 -28.3464)
		(size 0.7112)
		(drill 0.3556)
		(layers "F.Cu" "B.Cu")
		(net "ISENSE_PVDDR_A_ISEN1")
	)
	(via
		(at 187.0202 -29.972)
		(size 0.508)
		(drill 0.254)
		(layers "F.Cu" "B.Cu")
		(net "ISENSE_PVDDR_A_ISEN1")
	)
	(segment
		(start 186.8424 -29.972)
		(end 185.674 -28.8036)
		(width 0.2032)
		(layer "B.Cu")
		(net "ISENSE_PVDDR_A_ISEN1")
	)
	(segment
		(start 184.9882 -28.8036)
		(end 184.531 -28.3464)
		(width 0.2032)
		(layer "B.Cu")
		(net "ISENSE_PVDDR_A_ISEN1")
	)
	(segment
		(start 187.0202 -29.972)
		(end 186.8424 -29.972)
		(width 0.2032)
		(layer "B.Cu")
		(net "ISENSE_PVDDR_A_ISEN1")
	)
	(segment
		(start 185.674 -28.8036)
		(end 184.9882 -28.8036)
		(width 0.2032)
		(layer "B.Cu")
		(net "ISENSE_PVDDR_A_ISEN1")
	)
	(segment
		(start 184.4548 -26.797)
		(end 184.4548 -28.2702)
		(width 0.2032)
		(layer "B.Cu")
		(net "ISENSE_PVDDR_A_ISEN1")
	)
	(segment
		(start 184.4548 -28.2702)
		(end 184.531 -28.3464)
		(width 0.2032)
		(layer "B.Cu")
		(net "ISENSE_PVDDR_A_ISEN1")
	)
	(segment
		(start 106.449368 -27.594814)
		(end 106.850688 -27.996134)
		(width 0.1016)
		(layer "F.Cu")
		(net "M_B_ECC3")
	)
	(segment
		(start 106.449368 -27.173682)
		(end 106.449368 -27.594814)
		(width 0.1016)
		(layer "F.Cu")
		(net "M_B_ECC3")
	)
	(segment
		(start 106.627676 -26.995374)
		(end 106.449368 -27.173682)
		(width 0.1016)
		(layer "F.Cu")
		(net "M_B_ECC3")
	)
	(segment
		(start 155.049982 -9.897364)
		(end 155.049982 -8.596376)
		(width 0.1778)
		(layer "F.Cu")
		(net "M_B_ECC3")
	)
	(segment
		(start 106.74096 -26.995374)
		(end 106.627676 -26.995374)
		(width 0.1016)
		(layer "F.Cu")
		(net "M_B_ECC3")
	)
	(segment
		(start 107.109768 -26.183082)
		(end 107.109768 -26.626566)
		(width 0.1016)
		(layer "F.Cu")
		(net "M_B_ECC3")
	)
	(segment
		(start 155.049982 -8.596376)
		(end 155.179776 -8.466582)
		(width 0.1778)
		(layer "F.Cu")
		(net "M_B_ECC3")
	)
	(segment
		(start 107.109768 -26.626566)
		(end 106.74096 -26.995374)
		(width 0.1016)
		(layer "F.Cu")
		(net "M_B_ECC3")
	)
	(segment
		(start 107.315 -25.97785)
		(end 107.109768 -26.183082)
		(width 0.1016)
		(layer "F.Cu")
		(net "M_B_ECC3")
	)
	(segment
		(start 107.207812 -24.810212)
		(end 107.315 -24.9174)
		(width 0.1016)
		(layer "F.Cu")
		(net "M_B_ECC3")
	)
	(segment
		(start 107.315 -24.9174)
		(end 107.315 -25.97785)
		(width 0.1016)
		(layer "F.Cu")
		(net "M_B_ECC3")
	)
	(via
		(at 107.207812 -24.810212)
		(size 0.4318)
		(drill 0.2032)
		(layers "F.Cu" "B.Cu")
		(net "M_B_ECC3")
	)
	(via
		(at 155.179776 -8.466582)
		(size 0.4318)
		(drill 0.2032)
		(layers "F.Cu" "B.Cu")
		(net "M_B_ECC3")
	)
	(segment
		(start 155.349956 -8.636762)
		(end 155.179776 -8.466582)
		(width 0.1778)
		(layer "B.Cu")
		(net "M_B_ECC3")
	)
	(segment
		(start 155.349956 -9.89076)
		(end 155.349956 -8.636762)
		(width 0.1778)
		(layer "B.Cu")
		(net "M_B_ECC3")
	)
	(segment
		(start 155.332176 -16.410686)
		(end 155.179776 -16.563086)
		(width 0.1524)
		(layer "In2.Cu")
		(net "M_B_ECC3")
	)
	(segment
		(start 155.4988 -15.801086)
		(end 155.6512 -15.953486)
		(width 0.1524)
		(layer "In2.Cu")
		(net "M_B_ECC3")
	)
	(segment
		(start 155.179776 -8.466582)
		(end 155.179776 -10.425176)
		(width 0.1524)
		(layer "In2.Cu")
		(net "M_B_ECC3")
	)
	(segment
		(start 129.011426 -22.0472)
		(end 129.0066 -22.052026)
		(width 0.1524)
		(layer "In2.Cu")
		(net "M_B_ECC3")
	)
	(segment
		(start 155.6512 -16.258286)
		(end 155.4988 -16.410686)
		(width 0.1524)
		(layer "In2.Cu")
		(net "M_B_ECC3")
	)
	(segment
		(start 155.332176 -13.362686)
		(end 155.4988 -13.362686)
		(width 0.1524)
		(layer "In2.Cu")
		(net "M_B_ECC3")
	)
	(segment
		(start 109.33684 -23.38324)
		(end 110.492286 -24.538686)
		(width 0.1016)
		(layer "In2.Cu")
		(net "M_B_ECC3")
	)
	(segment
		(start 155.179776 -10.425176)
		(end 155.6512 -10.8966)
		(width 0.1524)
		(layer "In2.Cu")
		(net "M_B_ECC3")
	)
	(segment
		(start 155.4988 -11.533886)
		(end 155.332176 -11.533886)
		(width 0.1524)
		(layer "In2.Cu")
		(net "M_B_ECC3")
	)
	(segment
		(start 155.179776 -11.686286)
		(end 155.179776 -11.991086)
		(width 0.1524)
		(layer "In2.Cu")
		(net "M_B_ECC3")
	)
	(segment
		(start 155.6512 -13.515086)
		(end 155.6512 -13.819886)
		(width 0.1524)
		(layer "In2.Cu")
		(net "M_B_ECC3")
	)
	(segment
		(start 155.179776 -17.782286)
		(end 155.179776 -18.366486)
		(width 0.1524)
		(layer "In2.Cu")
		(net "M_B_ECC3")
	)
	(segment
		(start 155.332176 -11.533886)
		(end 155.179776 -11.686286)
		(width 0.1524)
		(layer "In2.Cu")
		(net "M_B_ECC3")
	)
	(segment
		(start 155.4988 -17.020286)
		(end 155.6512 -17.172686)
		(width 0.1524)
		(layer "In2.Cu")
		(net "M_B_ECC3")
	)
	(segment
		(start 155.332176 -14.581886)
		(end 155.4988 -14.581886)
		(width 0.1524)
		(layer "In2.Cu")
		(net "M_B_ECC3")
	)
	(segment
		(start 155.4988 -14.581886)
		(end 155.6512 -14.734286)
		(width 0.1524)
		(layer "In2.Cu")
		(net "M_B_ECC3")
	)
	(segment
		(start 155.332176 -13.972286)
		(end 155.179776 -14.124686)
		(width 0.1524)
		(layer "In2.Cu")
		(net "M_B_ECC3")
	)
	(segment
		(start 155.179776 -16.867886)
		(end 155.332176 -17.020286)
		(width 0.1524)
		(layer "In2.Cu")
		(net "M_B_ECC3")
	)
	(segment
		(start 155.179776 -13.210286)
		(end 155.332176 -13.362686)
		(width 0.1524)
		(layer "In2.Cu")
		(net "M_B_ECC3")
	)
	(segment
		(start 155.4988 -13.972286)
		(end 155.332176 -13.972286)
		(width 0.1524)
		(layer "In2.Cu")
		(net "M_B_ECC3")
	)
	(segment
		(start 155.6512 -17.477486)
		(end 155.4988 -17.629886)
		(width 0.1524)
		(layer "In2.Cu")
		(net "M_B_ECC3")
	)
	(segment
		(start 155.6512 -13.819886)
		(end 155.4988 -13.972286)
		(width 0.1524)
		(layer "In2.Cu")
		(net "M_B_ECC3")
	)
	(segment
		(start 155.179776 -14.124686)
		(end 155.179776 -14.429486)
		(width 0.1524)
		(layer "In2.Cu")
		(net "M_B_ECC3")
	)
	(segment
		(start 155.8036 -12.600686)
		(end 155.6512 -12.753086)
		(width 0.1524)
		(layer "In2.Cu")
		(net "M_B_ECC3")
	)
	(segment
		(start 155.6512 -14.734286)
		(end 155.6512 -15.039086)
		(width 0.1524)
		(layer "In2.Cu")
		(net "M_B_ECC3")
	)
	(segment
		(start 155.332176 -12.143486)
		(end 155.6512 -12.143486)
		(width 0.1524)
		(layer "In2.Cu")
		(net "M_B_ECC3")
	)
	(segment
		(start 155.6512 -12.143486)
		(end 155.8036 -12.295886)
		(width 0.1524)
		(layer "In2.Cu")
		(net "M_B_ECC3")
	)
	(segment
		(start 126.3904 -22.052026)
		(end 123.90374 -24.538686)
		(width 0.1524)
		(layer "In2.Cu")
		(net "M_B_ECC3")
	)
	(segment
		(start 155.179776 -14.429486)
		(end 155.332176 -14.581886)
		(width 0.1524)
		(layer "In2.Cu")
		(net "M_B_ECC3")
	)
	(segment
		(start 155.6512 -11.381486)
		(end 155.4988 -11.533886)
		(width 0.1524)
		(layer "In2.Cu")
		(net "M_B_ECC3")
	)
	(segment
		(start 107.207812 -24.810212)
		(end 108.634784 -23.38324)
		(width 0.1016)
		(layer "In2.Cu")
		(net "M_B_ECC3")
	)
	(segment
		(start 155.332176 -15.801086)
		(end 155.4988 -15.801086)
		(width 0.1524)
		(layer "In2.Cu")
		(net "M_B_ECC3")
	)
	(segment
		(start 123.90374 -24.538686)
		(end 110.492286 -24.538686)
		(width 0.1524)
		(layer "In2.Cu")
		(net "M_B_ECC3")
	)
	(segment
		(start 155.179776 -12.905486)
		(end 155.179776 -13.210286)
		(width 0.1524)
		(layer "In2.Cu")
		(net "M_B_ECC3")
	)
	(segment
		(start 155.179776 -11.991086)
		(end 155.332176 -12.143486)
		(width 0.1524)
		(layer "In2.Cu")
		(net "M_B_ECC3")
	)
	(segment
		(start 155.179776 -15.648686)
		(end 155.332176 -15.801086)
		(width 0.1524)
		(layer "In2.Cu")
		(net "M_B_ECC3")
	)
	(segment
		(start 155.4988 -16.410686)
		(end 155.332176 -16.410686)
		(width 0.1524)
		(layer "In2.Cu")
		(net "M_B_ECC3")
	)
	(segment
		(start 155.6512 -15.953486)
		(end 155.6512 -16.258286)
		(width 0.1524)
		(layer "In2.Cu")
		(net "M_B_ECC3")
	)
	(segment
		(start 155.332176 -17.020286)
		(end 155.4988 -17.020286)
		(width 0.1524)
		(layer "In2.Cu")
		(net "M_B_ECC3")
	)
	(segment
		(start 155.179776 -15.343886)
		(end 155.179776 -15.648686)
		(width 0.1524)
		(layer "In2.Cu")
		(net "M_B_ECC3")
	)
	(segment
		(start 155.179776 -18.366486)
		(end 151.499062 -22.0472)
		(width 0.1524)
		(layer "In2.Cu")
		(net "M_B_ECC3")
	)
	(segment
		(start 155.6512 -15.039086)
		(end 155.4988 -15.191486)
		(width 0.1524)
		(layer "In2.Cu")
		(net "M_B_ECC3")
	)
	(segment
		(start 155.8036 -12.295886)
		(end 155.8036 -12.600686)
		(width 0.1524)
		(layer "In2.Cu")
		(net "M_B_ECC3")
	)
	(segment
		(start 155.6512 -10.8966)
		(end 155.6512 -11.381486)
		(width 0.1524)
		(layer "In2.Cu")
		(net "M_B_ECC3")
	)
	(segment
		(start 155.6512 -17.172686)
		(end 155.6512 -17.477486)
		(width 0.1524)
		(layer "In2.Cu")
		(net "M_B_ECC3")
	)
	(segment
		(start 108.634784 -23.38324)
		(end 109.33684 -23.38324)
		(width 0.1016)
		(layer "In2.Cu")
		(net "M_B_ECC3")
	)
	(segment
		(start 155.4988 -15.191486)
		(end 155.332176 -15.191486)
		(width 0.1524)
		(layer "In2.Cu")
		(net "M_B_ECC3")
	)
	(segment
		(start 129.0066 -22.052026)
		(end 126.3904 -22.052026)
		(width 0.1524)
		(layer "In2.Cu")
		(net "M_B_ECC3")
	)
	(segment
		(start 155.332176 -17.629886)
		(end 155.179776 -17.782286)
		(width 0.1524)
		(layer "In2.Cu")
		(net "M_B_ECC3")
	)
	(segment
		(start 155.179776 -16.563086)
		(end 155.179776 -16.867886)
		(width 0.1524)
		(layer "In2.Cu")
		(net "M_B_ECC3")
	)
	(segment
		(start 155.332176 -12.753086)
		(end 155.179776 -12.905486)
		(width 0.1524)
		(layer "In2.Cu")
		(net "M_B_ECC3")
	)
	(segment
		(start 155.332176 -15.191486)
		(end 155.179776 -15.343886)
		(width 0.1524)
		(layer "In2.Cu")
		(net "M_B_ECC3")
	)
	(segment
		(start 155.4988 -17.629886)
		(end 155.332176 -17.629886)
		(width 0.1524)
		(layer "In2.Cu")
		(net "M_B_ECC3")
	)
	(segment
		(start 151.499062 -22.0472)
		(end 129.011426 -22.0472)
		(width 0.1524)
		(layer "In2.Cu")
		(net "M_B_ECC3")
	)
	(segment
		(start 155.4988 -13.362686)
		(end 155.6512 -13.515086)
		(width 0.1524)
		(layer "In2.Cu")
		(net "M_B_ECC3")
	)
	(segment
		(start 155.6512 -12.753086)
		(end 155.332176 -12.753086)
		(width 0.1524)
		(layer "In2.Cu")
		(net "M_B_ECC3")
	)
	(segment
		(start 82.504788 -34.757614)
		(end 82.504788 -34.195004)
		(width 0.1143)
		(layer "F.Cu")
		(net "SPI_MISO_R_GBE")
	)
	(segment
		(start 82.504788 -34.195004)
		(end 82.739484 -33.960308)
		(width 0.1143)
		(layer "F.Cu")
		(net "SPI_MISO_R_GBE")
	)
	(segment
		(start 48.26 -21.3868)
		(end 47.752 -21.3868)
		(width 0.1143)
		(layer "F.Cu")
		(net "SPI_MISO_R_GBE")
	)
	(segment
		(start 50.971196 -22.098)
		(end 50.621946 -21.74875)
		(width 0.1143)
		(layer "F.Cu")
		(net "SPI_MISO_R_GBE")
	)
	(segment
		(start 53.9242 -21.717)
		(end 53.5432 -22.098)
		(width 0.1143)
		(layer "F.Cu")
		(net "SPI_MISO_R_GBE")
	)
	(segment
		(start 53.5432 -22.098)
		(end 50.971196 -22.098)
		(width 0.1143)
		(layer "F.Cu")
		(net "SPI_MISO_R_GBE")
	)
	(segment
		(start 47.752 -21.3868)
		(end 47.371 -21.0058)
		(width 0.1143)
		(layer "F.Cu")
		(net "SPI_MISO_R_GBE")
	)
	(segment
		(start 50.621946 -21.74875)
		(end 48.62195 -21.74875)
		(width 0.1143)
		(layer "F.Cu")
		(net "SPI_MISO_R_GBE")
	)
	(segment
		(start 48.62195 -21.74875)
		(end 48.26 -21.3868)
		(width 0.1143)
		(layer "F.Cu")
		(net "SPI_MISO_R_GBE")
	)
	(via
		(at 47.371 -21.0058)
		(size 0.7112)
		(drill 0.3556)
		(layers "F.Cu" "B.Cu")
		(net "SPI_MISO_R_GBE")
	)
	(via
		(at 82.739484 -33.960308)
		(size 0.4318)
		(drill 0.2032)
		(layers "F.Cu" "B.Cu")
		(net "SPI_MISO_R_GBE")
	)
	(via
		(at 53.9242 -21.717)
		(size 0.508)
		(drill 0.254)
		(layers "F.Cu" "B.Cu")
		(net "SPI_MISO_R_GBE")
	)
	(segment
		(start 59.657742 -20.66925)
		(end 57.428892 -18.4404)
		(width 0.0889)
		(layer "In7.Cu")
		(net "SPI_MISO_R_GBE")
	)
	(segment
		(start 82.739484 -33.960308)
		(end 80.299814 -33.960308)
		(width 0.0889)
		(layer "In7.Cu")
		(net "SPI_MISO_R_GBE")
	)
	(segment
		(start 57.428892 -18.4404)
		(end 54.563518 -18.4404)
		(width 0.0889)
		(layer "In7.Cu")
		(net "SPI_MISO_R_GBE")
	)
	(segment
		(start 79.486506 -33.147)
		(end 78.984094 -33.147)
		(width 0.0889)
		(layer "In7.Cu")
		(net "SPI_MISO_R_GBE")
	)
	(segment
		(start 54.3052 -21.336)
		(end 53.9242 -21.717)
		(width 0.0889)
		(layer "In7.Cu")
		(net "SPI_MISO_R_GBE")
	)
	(segment
		(start 76.339446 -29.257498)
		(end 74.571098 -27.48915)
		(width 0.0889)
		(layer "In7.Cu")
		(net "SPI_MISO_R_GBE")
	)
	(segment
		(start 80.299814 -33.960308)
		(end 79.486506 -33.147)
		(width 0.0889)
		(layer "In7.Cu")
		(net "SPI_MISO_R_GBE")
	)
	(segment
		(start 54.3052 -18.698718)
		(end 54.3052 -21.336)
		(width 0.0889)
		(layer "In7.Cu")
		(net "SPI_MISO_R_GBE")
	)
	(segment
		(start 78.984094 -33.147)
		(end 76.339446 -30.502352)
		(width 0.0889)
		(layer "In7.Cu")
		(net "SPI_MISO_R_GBE")
	)
	(segment
		(start 62.138814 -20.66925)
		(end 59.657742 -20.66925)
		(width 0.0889)
		(layer "In7.Cu")
		(net "SPI_MISO_R_GBE")
	)
	(segment
		(start 71.058786 -27.48915)
		(end 66.391536 -22.8219)
		(width 0.0889)
		(layer "In7.Cu")
		(net "SPI_MISO_R_GBE")
	)
	(segment
		(start 64.291464 -22.8219)
		(end 62.138814 -20.66925)
		(width 0.0889)
		(layer "In7.Cu")
		(net "SPI_MISO_R_GBE")
	)
	(segment
		(start 74.571098 -27.48915)
		(end 71.058786 -27.48915)
		(width 0.0889)
		(layer "In7.Cu")
		(net "SPI_MISO_R_GBE")
	)
	(segment
		(start 54.563518 -18.4404)
		(end 54.3052 -18.698718)
		(width 0.0889)
		(layer "In7.Cu")
		(net "SPI_MISO_R_GBE")
	)
	(segment
		(start 66.391536 -22.8219)
		(end 64.291464 -22.8219)
		(width 0.0889)
		(layer "In7.Cu")
		(net "SPI_MISO_R_GBE")
	)
	(segment
		(start 76.339446 -30.502352)
		(end 76.339446 -29.257498)
		(width 0.0889)
		(layer "In7.Cu")
		(net "SPI_MISO_R_GBE")
	)
	(segment
		(start 187.833 -28.2194)
		(end 187.833 -27.432)
		(width 0.2032)
		(layer "F.Cu")
		(net "VSENSE_PVDDR_A_VRTN")
	)
	(segment
		(start 185.674 -24.765)
		(end 182.675022 -24.765)
		(width 0.2032)
		(layer "F.Cu")
		(net "VSENSE_PVDDR_A_VRTN")
	)
	(segment
		(start 154.305 -13.412978)
		(end 154.305 -14.953742)
		(width 0.2032)
		(layer "F.Cu")
		(net "VSENSE_PVDDR_A_VRTN")
	)
	(segment
		(start 188.341 -28.974034)
		(end 187.833 -28.466034)
		(width 0.2032)
		(layer "F.Cu")
		(net "VSENSE_PVDDR_A_VRTN")
	)
	(segment
		(start 187.840366 -27.432)
		(end 189.4586 -25.813766)
		(width 0.2032)
		(layer "F.Cu")
		(net "VSENSE_PVDDR_A_VRTN")
	)
	(segment
		(start 187.833 -28.466034)
		(end 187.833 -28.2194)
		(width 0.2032)
		(layer "F.Cu")
		(net "VSENSE_PVDDR_A_VRTN")
	)
	(segment
		(start 187.833 -27.432)
		(end 187.840366 -27.432)
		(width 0.2032)
		(layer "F.Cu")
		(net "VSENSE_PVDDR_A_VRTN")
	)
	(segment
		(start 154.5082 -13.209778)
		(end 154.305 -13.412978)
		(width 0.2032)
		(layer "F.Cu")
		(net "VSENSE_PVDDR_A_VRTN")
	)
	(segment
		(start 178.826922 -20.9169)
		(end 162.9029 -20.9169)
		(width 0.2032)
		(layer "F.Cu")
		(net "VSENSE_PVDDR_A_VRTN")
	)
	(segment
		(start 188.341 -29.151834)
		(end 188.341 -28.974034)
		(width 0.2032)
		(layer "F.Cu")
		(net "VSENSE_PVDDR_A_VRTN")
	)
	(segment
		(start 182.675022 -24.765)
		(end 178.826922 -20.9169)
		(width 0.2032)
		(layer "F.Cu")
		(net "VSENSE_PVDDR_A_VRTN")
	)
	(segment
		(start 154.305 -14.953742)
		(end 157.639258 -18.288)
		(width 0.2032)
		(layer "F.Cu")
		(net "VSENSE_PVDDR_A_VRTN")
	)
	(segment
		(start 162.9029 -20.9169)
		(end 160.274 -18.288)
		(width 0.2032)
		(layer "F.Cu")
		(net "VSENSE_PVDDR_A_VRTN")
	)
	(segment
		(start 157.639258 -18.288)
		(end 160.02 -18.288)
		(width 0.2032)
		(layer "F.Cu")
		(net "VSENSE_PVDDR_A_VRTN")
	)
	(segment
		(start 189.4586 -25.813766)
		(end 189.4586 -25.060402)
		(width 0.2032)
		(layer "F.Cu")
		(net "VSENSE_PVDDR_A_VRTN")
	)
	(segment
		(start 188.401198 -24.003)
		(end 186.436 -24.003)
		(width 0.2032)
		(layer "F.Cu")
		(net "VSENSE_PVDDR_A_VRTN")
	)
	(segment
		(start 160.274 -18.288)
		(end 160.02 -18.288)
		(width 0.2032)
		(layer "F.Cu")
		(net "VSENSE_PVDDR_A_VRTN")
	)
	(segment
		(start 189.4586 -25.060402)
		(end 188.401198 -24.003)
		(width 0.2032)
		(layer "F.Cu")
		(net "VSENSE_PVDDR_A_VRTN")
	)
	(segment
		(start 189.856364 -30.667198)
		(end 188.341 -29.151834)
		(width 0.2032)
		(layer "F.Cu")
		(net "VSENSE_PVDDR_A_VRTN")
	)
	(segment
		(start 189.856364 -31.575502)
		(end 189.856364 -30.667198)
		(width 0.2032)
		(layer "F.Cu")
		(net "VSENSE_PVDDR_A_VRTN")
	)
	(segment
		(start 186.436 -24.003)
		(end 185.674 -24.765)
		(width 0.2032)
		(layer "F.Cu")
		(net "VSENSE_PVDDR_A_VRTN")
	)
	(via
		(at 160.02 -18.288)
		(size 0.7112)
		(drill 0.3556)
		(layers "F.Cu" "B.Cu")
		(net "VSENSE_PVDDR_A_VRTN")
	)
	(segment
		(start 162.849814 -9.054084)
		(end 162.578034 -8.782304)
		(width 0.2413)
		(layer "F.Cu")
		(net "M_B_BS1")
	)
	(segment
		(start 162.657028 -6.08584)
		(end 162.657028 -5.72262)
		(width 0.2413)
		(layer "F.Cu")
		(net "M_B_BS1")
	)
	(segment
		(start 162.578034 -8.782304)
		(end 162.578034 -7.697978)
		(width 0.2413)
		(layer "F.Cu")
		(net "M_B_BS1")
	)
	(segment
		(start 162.654234 -7.621778)
		(end 162.654234 -6.088634)
		(width 0.2413)
		(layer "F.Cu")
		(net "M_B_BS1")
	)
	(segment
		(start 103.935784 -29.98851)
		(end 103.935784 -30.02153)
		(width 0.1016)
		(layer "F.Cu")
		(net "M_B_BS1")
	)
	(segment
		(start 103.563928 -29.616654)
		(end 103.935784 -29.98851)
		(width 0.1016)
		(layer "F.Cu")
		(net "M_B_BS1")
	)
	(segment
		(start 162.654234 -6.088634)
		(end 162.657028 -6.08584)
		(width 0.2413)
		(layer "F.Cu")
		(net "M_B_BS1")
	)
	(segment
		(start 163.12007 -5.259578)
		(end 163.182554 -5.259578)
		(width 0.2413)
		(layer "F.Cu")
		(net "M_B_BS1")
	)
	(segment
		(start 162.657028 -5.72262)
		(end 163.12007 -5.259578)
		(width 0.2413)
		(layer "F.Cu")
		(net "M_B_BS1")
	)
	(segment
		(start 162.849814 -9.897364)
		(end 162.849814 -9.054084)
		(width 0.2413)
		(layer "F.Cu")
		(net "M_B_BS1")
	)
	(segment
		(start 162.578034 -7.697978)
		(end 162.654234 -7.621778)
		(width 0.2413)
		(layer "F.Cu")
		(net "M_B_BS1")
	)
	(via
		(at 103.935784 -30.02153)
		(size 0.4318)
		(drill 0.2032)
		(layers "F.Cu" "B.Cu")
		(net "M_B_BS1")
	)
	(via
		(at 163.182554 -5.259578)
		(size 0.4318)
		(drill 0.2032)
		(layers "F.Cu" "B.Cu")
		(net "M_B_BS1")
	)
	(segment
		(start 162.849814 -1.690624)
		(end 162.849814 -2.621026)
		(width 0.2413)
		(layer "B.Cu")
		(net "M_B_BS1")
	)
	(segment
		(start 162.52698 -2.94386)
		(end 162.52698 -3.372358)
		(width 0.2413)
		(layer "B.Cu")
		(net "M_B_BS1")
	)
	(segment
		(start 162.52698 -3.372358)
		(end 163.169854 -4.015232)
		(width 0.2413)
		(layer "B.Cu")
		(net "M_B_BS1")
	)
	(segment
		(start 163.169854 -4.015232)
		(end 163.169854 -5.246878)
		(width 0.2413)
		(layer "B.Cu")
		(net "M_B_BS1")
	)
	(segment
		(start 163.169854 -5.246878)
		(end 163.182554 -5.259578)
		(width 0.2413)
		(layer "B.Cu")
		(net "M_B_BS1")
	)
	(segment
		(start 162.849814 -2.621026)
		(end 162.52698 -2.94386)
		(width 0.2413)
		(layer "B.Cu")
		(net "M_B_BS1")
	)
	(segment
		(start 155.01747 -22.245828)
		(end 154.74823 -22.245828)
		(width 0.1905)
		(layer "In7.Cu")
		(net "M_B_BS1")
	)
	(segment
		(start 156.095446 -21.167852)
		(end 155.826206 -21.167852)
		(width 0.1905)
		(layer "In7.Cu")
		(net "M_B_BS1")
	)
	(segment
		(start 155.082494 -22.310852)
		(end 155.01747 -22.245828)
		(width 0.1905)
		(layer "In7.Cu")
		(net "M_B_BS1")
	)
	(segment
		(start 161.98215 -12.065)
		(end 161.9885 -12.07135)
		(width 0.1905)
		(layer "In7.Cu")
		(net "M_B_BS1")
	)
	(segment
		(start 154.004518 -23.388828)
		(end 153.939494 -23.323804)
		(width 0.1905)
		(layer "In7.Cu")
		(net "M_B_BS1")
	)
	(segment
		(start 163.182554 -5.259578)
		(end 163.155884 -5.259578)
		(width 0.1905)
		(layer "In7.Cu")
		(net "M_B_BS1")
	)
	(segment
		(start 162.540696 -6.955282)
		(end 162.540696 -10.765282)
		(width 0.1905)
		(layer "In7.Cu")
		(net "M_B_BS1")
	)
	(segment
		(start 155.351734 -22.310852)
		(end 155.082494 -22.310852)
		(width 0.1905)
		(layer "In7.Cu")
		(net "M_B_BS1")
	)
	(segment
		(start 154.478482 -22.784816)
		(end 154.543506 -22.84984)
		(width 0.1905)
		(layer "In7.Cu")
		(net "M_B_BS1")
	)
	(segment
		(start 154.478482 -22.515576)
		(end 154.478482 -22.784816)
		(width 0.1905)
		(layer "In7.Cu")
		(net "M_B_BS1")
	)
	(segment
		(start 106.934 -27.6352)
		(end 109.3978 -27.6352)
		(width 0.1016)
		(layer "In7.Cu")
		(net "M_B_BS1")
	)
	(segment
		(start 111.3409 -26.5557)
		(end 113.1697 -26.5557)
		(width 0.1016)
		(layer "In7.Cu")
		(net "M_B_BS1")
	)
	(segment
		(start 161.9885 -12.07135)
		(end 161.9885 -15.674086)
		(width 0.1905)
		(layer "In7.Cu")
		(net "M_B_BS1")
	)
	(segment
		(start 154.273758 -23.388828)
		(end 154.004518 -23.388828)
		(width 0.1905)
		(layer "In7.Cu")
		(net "M_B_BS1")
	)
	(segment
		(start 161.754566 -15.907766)
		(end 161.754566 -15.90802)
		(width 0.1905)
		(layer "In7.Cu")
		(net "M_B_BS1")
	)
	(segment
		(start 154.543506 -22.84984)
		(end 154.543506 -23.11908)
		(width 0.1905)
		(layer "In7.Cu")
		(net "M_B_BS1")
	)
	(segment
		(start 161.98215 -11.323828)
		(end 161.98215 -12.065)
		(width 0.1905)
		(layer "In7.Cu")
		(net "M_B_BS1")
	)
	(segment
		(start 104.3432 -29.21)
		(end 104.606598 -28.946602)
		(width 0.1016)
		(layer "In7.Cu")
		(net "M_B_BS1")
	)
	(segment
		(start 104.3432 -29.614114)
		(end 104.3432 -29.21)
		(width 0.1016)
		(layer "In7.Cu")
		(net "M_B_BS1")
	)
	(segment
		(start 155.621482 -22.041104)
		(end 155.351734 -22.310852)
		(width 0.1905)
		(layer "In7.Cu")
		(net "M_B_BS1")
	)
	(segment
		(start 162.540696 -10.765282)
		(end 161.98215 -11.323828)
		(width 0.1905)
		(layer "In7.Cu")
		(net "M_B_BS1")
	)
	(segment
		(start 153.46553 -23.927816)
		(end 153.46553 -24.197056)
		(width 0.1905)
		(layer "In7.Cu")
		(net "M_B_BS1")
	)
	(segment
		(start 161.9885 -15.674086)
		(end 161.830766 -15.831566)
		(width 0.1905)
		(layer "In7.Cu")
		(net "M_B_BS1")
	)
	(segment
		(start 154.543506 -23.11908)
		(end 154.273758 -23.388828)
		(width 0.1905)
		(layer "In7.Cu")
		(net "M_B_BS1")
	)
	(segment
		(start 153.400506 -23.593552)
		(end 153.400506 -23.862792)
		(width 0.1905)
		(layer "In7.Cu")
		(net "M_B_BS1")
	)
	(segment
		(start 155.826206 -21.167852)
		(end 155.556458 -21.4376)
		(width 0.1905)
		(layer "In7.Cu")
		(net "M_B_BS1")
	)
	(segment
		(start 156.42971 -21.232876)
		(end 156.16047 -21.232876)
		(width 0.1905)
		(layer "In7.Cu")
		(net "M_B_BS1")
	)
	(segment
		(start 153.939494 -23.323804)
		(end 153.670254 -23.323804)
		(width 0.1905)
		(layer "In7.Cu")
		(net "M_B_BS1")
	)
	(segment
		(start 153.46553 -24.197056)
		(end 153.024586 -24.638)
		(width 0.1905)
		(layer "In7.Cu")
		(net "M_B_BS1")
	)
	(segment
		(start 110.2106 -26.8224)
		(end 111.0742 -26.8224)
		(width 0.1016)
		(layer "In7.Cu")
		(net "M_B_BS1")
	)
	(segment
		(start 114.818414 -26.8478)
		(end 113.4618 -26.8478)
		(width 0.1905)
		(layer "In7.Cu")
		(net "M_B_BS1")
	)
	(segment
		(start 153.400506 -23.862792)
		(end 153.46553 -23.927816)
		(width 0.1905)
		(layer "In7.Cu")
		(net "M_B_BS1")
	)
	(segment
		(start 155.556458 -21.70684)
		(end 155.621482 -21.771864)
		(width 0.1905)
		(layer "In7.Cu")
		(net "M_B_BS1")
	)
	(segment
		(start 153.670254 -23.323804)
		(end 153.400506 -23.593552)
		(width 0.1905)
		(layer "In7.Cu")
		(net "M_B_BS1")
	)
	(segment
		(start 109.3978 -27.6352)
		(end 110.2106 -26.8224)
		(width 0.1016)
		(layer "In7.Cu")
		(net "M_B_BS1")
	)
	(segment
		(start 153.024586 -24.638)
		(end 117.028214 -24.638)
		(width 0.1905)
		(layer "In7.Cu")
		(net "M_B_BS1")
	)
	(segment
		(start 105.622598 -28.946602)
		(end 106.934 -27.6352)
		(width 0.1016)
		(layer "In7.Cu")
		(net "M_B_BS1")
	)
	(segment
		(start 156.16047 -21.232876)
		(end 156.095446 -21.167852)
		(width 0.1905)
		(layer "In7.Cu")
		(net "M_B_BS1")
	)
	(segment
		(start 161.754566 -15.90802)
		(end 156.42971 -21.232876)
		(width 0.1905)
		(layer "In7.Cu")
		(net "M_B_BS1")
	)
	(segment
		(start 113.1697 -26.5557)
		(end 113.4618 -26.8478)
		(width 0.1016)
		(layer "In7.Cu")
		(net "M_B_BS1")
	)
	(segment
		(start 162.631628 -6.86435)
		(end 162.540696 -6.955282)
		(width 0.1905)
		(layer "In7.Cu")
		(net "M_B_BS1")
	)
	(segment
		(start 103.935784 -30.02153)
		(end 104.3432 -29.614114)
		(width 0.1016)
		(layer "In7.Cu")
		(net "M_B_BS1")
	)
	(segment
		(start 104.606598 -28.946602)
		(end 105.622598 -28.946602)
		(width 0.1016)
		(layer "In7.Cu")
		(net "M_B_BS1")
	)
	(segment
		(start 162.631628 -5.783834)
		(end 162.631628 -6.86435)
		(width 0.1905)
		(layer "In7.Cu")
		(net "M_B_BS1")
	)
	(segment
		(start 117.028214 -24.638)
		(end 114.818414 -26.8478)
		(width 0.1905)
		(layer "In7.Cu")
		(net "M_B_BS1")
	)
	(segment
		(start 111.0742 -26.8224)
		(end 111.3409 -26.5557)
		(width 0.1016)
		(layer "In7.Cu")
		(net "M_B_BS1")
	)
	(segment
		(start 155.621482 -21.771864)
		(end 155.621482 -22.041104)
		(width 0.1905)
		(layer "In7.Cu")
		(net "M_B_BS1")
	)
	(segment
		(start 163.155884 -5.259578)
		(end 162.631628 -5.783834)
		(width 0.1905)
		(layer "In7.Cu")
		(net "M_B_BS1")
	)
	(segment
		(start 155.556458 -21.4376)
		(end 155.556458 -21.70684)
		(width 0.1905)
		(layer "In7.Cu")
		(net "M_B_BS1")
	)
	(segment
		(start 154.74823 -22.245828)
		(end 154.478482 -22.515576)
		(width 0.1905)
		(layer "In7.Cu")
		(net "M_B_BS1")
	)
	(segment
		(start 161.830766 -15.831566)
		(end 161.754566 -15.907766)
		(width 0.1905)
		(layer "In7.Cu")
		(net "M_B_BS1")
	)
	(segment
		(start 188.4426 -29.972)
		(end 188.4934 -30.0228)
		(width 0.2032)
		(layer "F.Cu")
		(net "VR_PVDDR_A_VSEN")
	)
	(segment
		(start 187.901834 -29.972)
		(end 188.4426 -29.972)
		(width 0.2032)
		(layer "F.Cu")
		(net "VR_PVDDR_A_VSEN")
	)
	(segment
		(start 189.456314 -30.985714)
		(end 188.4934 -30.0228)
		(width 0.2032)
		(layer "F.Cu")
		(net "VR_PVDDR_A_VSEN")
	)
	(segment
		(start 186.9186 -28.2194)
		(end 186.9186 -27.5844)
		(width 0.2032)
		(layer "F.Cu")
		(net "VR_PVDDR_A_VSEN")
	)
	(segment
		(start 189.456314 -31.575502)
		(end 189.456314 -30.985714)
		(width 0.2032)
		(layer "F.Cu")
		(net "VR_PVDDR_A_VSEN")
	)
	(segment
		(start 186.9186 -27.5844)
		(end 187.071 -27.432)
		(width 0.2032)
		(layer "F.Cu")
		(net "VR_PVDDR_A_VSEN")
	)
	(segment
		(start 186.9186 -28.2194)
		(end 186.9186 -28.988766)
		(width 0.2032)
		(layer "F.Cu")
		(net "VR_PVDDR_A_VSEN")
	)
	(segment
		(start 186.9186 -28.988766)
		(end 187.901834 -29.972)
		(width 0.2032)
		(layer "F.Cu")
		(net "VR_PVDDR_A_VSEN")
	)
	(via
		(at 185.1406 -29.4894)
		(size 0.7112)
		(drill 0.3556)
		(layers "F.Cu" "B.Cu")
		(net "VR_PVDDR_A_VSEN")
	)
	(via
		(at 188.4934 -30.0228)
		(size 0.508)
		(drill 0.254)
		(layers "F.Cu" "B.Cu")
		(net "VR_PVDDR_A_VSEN")
	)
	(segment
		(start 188.4934 -30.0228)
		(end 188.0362 -30.48)
		(width 0.2032)
		(layer "B.Cu")
		(net "VR_PVDDR_A_VSEN")
	)
	(segment
		(start 185.1406 -29.4894)
		(end 184.3024 -29.4894)
		(width 0.2032)
		(layer "B.Cu")
		(net "VR_PVDDR_A_VSEN")
	)
	(segment
		(start 188.0362 -30.48)
		(end 186.5884 -30.48)
		(width 0.2032)
		(layer "B.Cu")
		(net "VR_PVDDR_A_VSEN")
	)
	(segment
		(start 186.5884 -30.48)
		(end 185.5978 -29.4894)
		(width 0.2032)
		(layer "B.Cu")
		(net "VR_PVDDR_A_VSEN")
	)
	(segment
		(start 183.4642 -29.591)
		(end 184.2008 -29.591)
		(width 0.2032)
		(layer "B.Cu")
		(net "VR_PVDDR_A_VSEN")
	)
	(segment
		(start 184.3024 -29.4894)
		(end 184.2008 -29.591)
		(width 0.2032)
		(layer "B.Cu")
		(net "VR_PVDDR_A_VSEN")
	)
	(segment
		(start 185.5978 -29.4894)
		(end 185.1406 -29.4894)
		(width 0.2032)
		(layer "B.Cu")
		(net "VR_PVDDR_A_VSEN")
	)
	(segment
		(start 132.43814 -3.580638)
		(end 132.2578 -3.760978)
		(width 0.1778)
		(layer "F.Cu")
		(net "M_B_DQ6")
	)
	(segment
		(start 92.6592 -23.1648)
		(end 93.1164 -23.622)
		(width 0.1016)
		(layer "F.Cu")
		(net "M_B_DQ6")
	)
	(segment
		(start 132.2705 -2.797302)
		(end 132.43814 -2.964942)
		(width 0.1778)
		(layer "F.Cu")
		(net "M_B_DQ6")
	)
	(segment
		(start 131.949952 -2.38379)
		(end 132.2705 -2.704338)
		(width 0.1778)
		(layer "F.Cu")
		(net "M_B_DQ6")
	)
	(segment
		(start 93.1164 -23.622)
		(end 93.1164 -24.85009)
		(width 0.1016)
		(layer "F.Cu")
		(net "M_B_DQ6")
	)
	(segment
		(start 132.2705 -2.704338)
		(end 132.2705 -2.797302)
		(width 0.1778)
		(layer "F.Cu")
		(net "M_B_DQ6")
	)
	(segment
		(start 131.949952 -1.68402)
		(end 131.949952 -2.38379)
		(width 0.1778)
		(layer "F.Cu")
		(net "M_B_DQ6")
	)
	(segment
		(start 93.1164 -24.85009)
		(end 94.217744 -25.951434)
		(width 0.1016)
		(layer "F.Cu")
		(net "M_B_DQ6")
	)
	(segment
		(start 94.217744 -25.951434)
		(end 94.513908 -25.951434)
		(width 0.1016)
		(layer "F.Cu")
		(net "M_B_DQ6")
	)
	(segment
		(start 132.43814 -2.964942)
		(end 132.43814 -3.580638)
		(width 0.1778)
		(layer "F.Cu")
		(net "M_B_DQ6")
	)
	(via
		(at 92.6592 -23.1648)
		(size 0.4318)
		(drill 0.2032)
		(layers "F.Cu" "B.Cu")
		(net "M_B_DQ6")
	)
	(via
		(at 132.2578 -3.760978)
		(size 0.4318)
		(drill 0.2032)
		(layers "F.Cu" "B.Cu")
		(net "M_B_DQ6")
	)
	(segment
		(start 132.43814 -3.580638)
		(end 132.2578 -3.760978)
		(width 0.1778)
		(layer "B.Cu")
		(net "M_B_DQ6")
	)
	(segment
		(start 132.567426 -2.917952)
		(end 132.567426 -2.928874)
		(width 0.1778)
		(layer "B.Cu")
		(net "M_B_DQ6")
	)
	(segment
		(start 132.43814 -3.05816)
		(end 132.43814 -3.580638)
		(width 0.1778)
		(layer "B.Cu")
		(net "M_B_DQ6")
	)
	(segment
		(start 132.849874 -2.635504)
		(end 132.567426 -2.917952)
		(width 0.1778)
		(layer "B.Cu")
		(net "M_B_DQ6")
	)
	(segment
		(start 132.567426 -2.928874)
		(end 132.43814 -3.05816)
		(width 0.1778)
		(layer "B.Cu")
		(net "M_B_DQ6")
	)
	(segment
		(start 132.849874 -1.690624)
		(end 132.849874 -2.635504)
		(width 0.1778)
		(layer "B.Cu")
		(net "M_B_DQ6")
	)
	(segment
		(start 132.0038 -4.141978)
		(end 132.2578 -3.887978)
		(width 0.1524)
		(layer "In7.Cu")
		(net "M_B_DQ6")
	)
	(segment
		(start 131.4958 -9.5504)
		(end 131.4958 -7.384542)
		(width 0.1524)
		(layer "In7.Cu")
		(net "M_B_DQ6")
	)
	(segment
		(start 132.200142 -4.776978)
		(end 129.8956 -4.776978)
		(width 0.1524)
		(layer "In7.Cu")
		(net "M_B_DQ6")
	)
	(segment
		(start 95.545402 -20.5232)
		(end 98.297746 -17.770856)
		(width 0.1524)
		(layer "In7.Cu")
		(net "M_B_DQ6")
	)
	(segment
		(start 127.762 -11.0236)
		(end 128.1176 -10.668)
		(width 0.1524)
		(layer "In7.Cu")
		(net "M_B_DQ6")
	)
	(segment
		(start 123.3678 -10.8712)
		(end 123.5202 -11.0236)
		(width 0.1524)
		(layer "In7.Cu")
		(net "M_B_DQ6")
	)
	(segment
		(start 114.051334 -10.6934)
		(end 114.542062 -10.6934)
		(width 0.1524)
		(layer "In7.Cu")
		(net "M_B_DQ6")
	)
	(segment
		(start 125.5014 -11.0236)
		(end 126.0094 -11.0236)
		(width 0.1524)
		(layer "In7.Cu")
		(net "M_B_DQ6")
	)
	(segment
		(start 129.7432 -4.624578)
		(end 129.7432 -3.811778)
		(width 0.1524)
		(layer "In7.Cu")
		(net "M_B_DQ6")
	)
	(segment
		(start 127.254 -11.0236)
		(end 127.762 -11.0236)
		(width 0.1524)
		(layer "In7.Cu")
		(net "M_B_DQ6")
	)
	(segment
		(start 128.1176 -10.668)
		(end 130.3782 -10.668)
		(width 0.1524)
		(layer "In7.Cu")
		(net "M_B_DQ6")
	)
	(segment
		(start 126.3396 -10.6934)
		(end 126.9238 -10.6934)
		(width 0.1524)
		(layer "In7.Cu")
		(net "M_B_DQ6")
	)
	(segment
		(start 131.4958 -7.384542)
		(end 132.403342 -6.477)
		(width 0.1524)
		(layer "In7.Cu")
		(net "M_B_DQ6")
	)
	(segment
		(start 95.545402 -20.5232)
		(end 93.8784 -20.5232)
		(width 0.1016)
		(layer "In7.Cu")
		(net "M_B_DQ6")
	)
	(segment
		(start 129.8956 -3.659378)
		(end 130.81 -3.659378)
		(width 0.1524)
		(layer "In7.Cu")
		(net "M_B_DQ6")
	)
	(segment
		(start 131.2926 -4.141978)
		(end 132.0038 -4.141978)
		(width 0.1524)
		(layer "In7.Cu")
		(net "M_B_DQ6")
	)
	(segment
		(start 132.403342 -4.980178)
		(end 132.200142 -4.776978)
		(width 0.1524)
		(layer "In7.Cu")
		(net "M_B_DQ6")
	)
	(segment
		(start 130.3782 -10.668)
		(end 131.4958 -9.5504)
		(width 0.1524)
		(layer "In7.Cu")
		(net "M_B_DQ6")
	)
	(segment
		(start 93.8784 -20.5232)
		(end 92.6592 -21.7424)
		(width 0.1016)
		(layer "In7.Cu")
		(net "M_B_DQ6")
	)
	(segment
		(start 132.403342 -6.477)
		(end 132.403342 -4.980178)
		(width 0.1524)
		(layer "In7.Cu")
		(net "M_B_DQ6")
	)
	(segment
		(start 123.2154 -9.6012)
		(end 123.3678 -9.7536)
		(width 0.1524)
		(layer "In7.Cu")
		(net "M_B_DQ6")
	)
	(segment
		(start 124.5362 -10.6934)
		(end 125.1712 -10.6934)
		(width 0.1524)
		(layer "In7.Cu")
		(net "M_B_DQ6")
	)
	(segment
		(start 124.206 -11.0236)
		(end 124.5362 -10.6934)
		(width 0.1524)
		(layer "In7.Cu")
		(net "M_B_DQ6")
	)
	(segment
		(start 129.8956 -4.776978)
		(end 129.7432 -4.624578)
		(width 0.1524)
		(layer "In7.Cu")
		(net "M_B_DQ6")
	)
	(segment
		(start 123.3678 -9.7536)
		(end 123.3678 -10.8712)
		(width 0.1524)
		(layer "In7.Cu")
		(net "M_B_DQ6")
	)
	(segment
		(start 126.0094 -11.0236)
		(end 126.3396 -10.6934)
		(width 0.1524)
		(layer "In7.Cu")
		(net "M_B_DQ6")
	)
	(segment
		(start 130.81 -3.659378)
		(end 131.2926 -4.141978)
		(width 0.1524)
		(layer "In7.Cu")
		(net "M_B_DQ6")
	)
	(segment
		(start 126.9238 -10.6934)
		(end 127.254 -11.0236)
		(width 0.1524)
		(layer "In7.Cu")
		(net "M_B_DQ6")
	)
	(segment
		(start 123.5202 -11.0236)
		(end 124.206 -11.0236)
		(width 0.1524)
		(layer "In7.Cu")
		(net "M_B_DQ6")
	)
	(segment
		(start 132.2578 -3.887978)
		(end 132.2578 -3.760978)
		(width 0.1524)
		(layer "In7.Cu")
		(net "M_B_DQ6")
	)
	(segment
		(start 125.1712 -10.6934)
		(end 125.5014 -11.0236)
		(width 0.1524)
		(layer "In7.Cu")
		(net "M_B_DQ6")
	)
	(segment
		(start 98.297746 -17.770856)
		(end 106.973878 -17.770856)
		(width 0.1524)
		(layer "In7.Cu")
		(net "M_B_DQ6")
	)
	(segment
		(start 115.634262 -9.6012)
		(end 123.2154 -9.6012)
		(width 0.1524)
		(layer "In7.Cu")
		(net "M_B_DQ6")
	)
	(segment
		(start 92.6592 -21.7424)
		(end 92.6592 -23.1648)
		(width 0.1016)
		(layer "In7.Cu")
		(net "M_B_DQ6")
	)
	(segment
		(start 129.7432 -3.811778)
		(end 129.8956 -3.659378)
		(width 0.1524)
		(layer "In7.Cu")
		(net "M_B_DQ6")
	)
	(segment
		(start 114.542062 -10.6934)
		(end 115.634262 -9.6012)
		(width 0.1524)
		(layer "In7.Cu")
		(net "M_B_DQ6")
	)
	(segment
		(start 106.973878 -17.770856)
		(end 114.051334 -10.6934)
		(width 0.1524)
		(layer "In7.Cu")
		(net "M_B_DQ6")
	)
	(segment
		(start 40.43045 -16.8656)
		(end 40.649398 -17.084548)
		(width 0.1397)
		(layer "B.Cu")
		(net "CLK_100M_CLKBUFF_SAS_R_DP")
	)
	(segment
		(start 40.64 -16.3322)
		(end 40.43045 -16.54175)
		(width 0.1397)
		(layer "B.Cu")
		(net "CLK_100M_CLKBUFF_SAS_R_DP")
	)
	(segment
		(start 40.649398 -17.084548)
		(end 41.443148 -17.084548)
		(width 0.1397)
		(layer "B.Cu")
		(net "CLK_100M_CLKBUFF_SAS_R_DP")
	)
	(segment
		(start 41.443148 -17.084548)
		(end 41.93921 -17.58061)
		(width 0.1397)
		(layer "B.Cu")
		(net "CLK_100M_CLKBUFF_SAS_R_DP")
	)
	(segment
		(start 41.93921 -17.93621)
		(end 42.01795 -18.01495)
		(width 0.1397)
		(layer "B.Cu")
		(net "CLK_100M_CLKBUFF_SAS_R_DP")
	)
	(segment
		(start 41.93921 -17.58061)
		(end 41.93921 -17.93621)
		(width 0.1397)
		(layer "B.Cu")
		(net "CLK_100M_CLKBUFF_SAS_R_DP")
	)
	(segment
		(start 42.01795 -18.01495)
		(end 42.01795 -18.6563)
		(width 0.1397)
		(layer "B.Cu")
		(net "CLK_100M_CLKBUFF_SAS_R_DP")
	)
	(segment
		(start 40.43045 -16.54175)
		(end 40.43045 -16.8656)
		(width 0.1397)
		(layer "B.Cu")
		(net "CLK_100M_CLKBUFF_SAS_R_DP")
	)
	(segment
		(start 189.5094 -27.4574)
		(end 189.5094 -26.481532)
		(width 0.2032)
		(layer "F.Cu")
		(net "VR_PVDDR_A_SUMN_C")
	)
	(segment
		(start 189.5094 -26.481532)
		(end 190.209932 -25.781)
		(width 0.2032)
		(layer "F.Cu")
		(net "VR_PVDDR_A_SUMN_C")
	)
	(segment
		(start 190.209932 -25.781)
		(end 190.373 -25.781)
		(width 0.2032)
		(layer "F.Cu")
		(net "VR_PVDDR_A_SUMN_C")
	)
	(via
		(at 189.1284 -25.2984)
		(size 0.7112)
		(drill 0.3556)
		(layers "F.Cu" "B.Cu")
		(net "VR_PVDDR_A_SUMN_C")
	)
	(via
		(at 190.373 -25.781)
		(size 0.508)
		(drill 0.254)
		(layers "F.Cu" "B.Cu")
		(net "VR_PVDDR_A_SUMN_C")
	)
	(segment
		(start 189.857888 -25.265888)
		(end 189.160912 -25.265888)
		(width 0.2032)
		(layer "B.Cu")
		(net "VR_PVDDR_A_SUMN_C")
	)
	(segment
		(start 188.341 -27.2542)
		(end 188.595 -27.5082)
		(width 0.2032)
		(layer "B.Cu")
		(net "VR_PVDDR_A_SUMN_C")
	)
	(segment
		(start 190.373 -25.781)
		(end 189.857888 -25.265888)
		(width 0.2032)
		(layer "B.Cu")
		(net "VR_PVDDR_A_SUMN_C")
	)
	(segment
		(start 189.1284 -25.2984)
		(end 189.1284 -25.47493)
		(width 0.2032)
		(layer "B.Cu")
		(net "VR_PVDDR_A_SUMN_C")
	)
	(segment
		(start 188.341 -26.26233)
		(end 188.341 -27.2542)
		(width 0.2032)
		(layer "B.Cu")
		(net "VR_PVDDR_A_SUMN_C")
	)
	(segment
		(start 189.160912 -25.265888)
		(end 189.1284 -25.2984)
		(width 0.2032)
		(layer "B.Cu")
		(net "VR_PVDDR_A_SUMN_C")
	)
	(segment
		(start 189.1284 -25.47493)
		(end 188.341 -26.26233)
		(width 0.2032)
		(layer "B.Cu")
		(net "VR_PVDDR_A_SUMN_C")
	)
	(segment
		(start 161.949892 -3.608578)
		(end 161.228278 -4.330192)
		(width 0.2413)
		(layer "F.Cu")
		(net "M_B_MA1")
	)
	(segment
		(start 104.02824 -28.81884)
		(end 103.759254 -28.549854)
		(width 0.1016)
		(layer "F.Cu")
		(net "M_B_MA1")
	)
	(segment
		(start 104.264968 -28.854654)
		(end 104.102408 -28.854654)
		(width 0.1016)
		(layer "F.Cu")
		(net "M_B_MA1")
	)
	(segment
		(start 104.066594 -28.81884)
		(end 104.02824 -28.81884)
		(width 0.1016)
		(layer "F.Cu")
		(net "M_B_MA1")
	)
	(segment
		(start 103.437436 -28.549854)
		(end 102.9208 -29.06649)
		(width 0.1016)
		(layer "F.Cu")
		(net "M_B_MA1")
	)
	(segment
		(start 161.228278 -4.330192)
		(end 161.228278 -5.132578)
		(width 0.2413)
		(layer "F.Cu")
		(net "M_B_MA1")
	)
	(segment
		(start 104.102408 -28.854654)
		(end 104.066594 -28.81884)
		(width 0.1016)
		(layer "F.Cu")
		(net "M_B_MA1")
	)
	(segment
		(start 161.949892 -1.68402)
		(end 161.949892 -3.608578)
		(width 0.2413)
		(layer "F.Cu")
		(net "M_B_MA1")
	)
	(segment
		(start 102.9208 -29.06649)
		(end 102.9208 -29.297122)
		(width 0.1016)
		(layer "F.Cu")
		(net "M_B_MA1")
	)
	(segment
		(start 103.759254 -28.549854)
		(end 103.437436 -28.549854)
		(width 0.1016)
		(layer "F.Cu")
		(net "M_B_MA1")
	)
	(via
		(at 161.228278 -5.132578)
		(size 0.4318)
		(drill 0.2032)
		(layers "F.Cu" "B.Cu")
		(net "M_B_MA1")
	)
	(via
		(at 102.9208 -29.297122)
		(size 0.4318)
		(drill 0.2032)
		(layers "F.Cu" "B.Cu")
		(net "M_B_MA1")
	)
	(segment
		(start 161.949892 -7.66953)
		(end 161.65322 -7.372858)
		(width 0.2413)
		(layer "B.Cu")
		(net "M_B_MA1")
	)
	(segment
		(start 161.279078 -5.183378)
		(end 161.228278 -5.132578)
		(width 0.2413)
		(layer "B.Cu")
		(net "M_B_MA1")
	)
	(segment
		(start 161.704528 -5.964936)
		(end 161.704528 -5.57022)
		(width 0.2413)
		(layer "B.Cu")
		(net "M_B_MA1")
	)
	(segment
		(start 161.65322 -7.372858)
		(end 161.65322 -6.016244)
		(width 0.2413)
		(layer "B.Cu")
		(net "M_B_MA1")
	)
	(segment
		(start 161.949892 -9.89076)
		(end 161.949892 -7.66953)
		(width 0.2413)
		(layer "B.Cu")
		(net "M_B_MA1")
	)
	(segment
		(start 161.317686 -5.183378)
		(end 161.279078 -5.183378)
		(width 0.2413)
		(layer "B.Cu")
		(net "M_B_MA1")
	)
	(segment
		(start 161.65322 -6.016244)
		(end 161.704528 -5.964936)
		(width 0.2413)
		(layer "B.Cu")
		(net "M_B_MA1")
	)
	(segment
		(start 161.704528 -5.57022)
		(end 161.317686 -5.183378)
		(width 0.2413)
		(layer "B.Cu")
		(net "M_B_MA1")
	)
	(segment
		(start 151.807164 -21.10105)
		(end 151.448262 -21.459952)
		(width 0.1905)
		(layer "In7.Cu")
		(net "M_B_MA1")
	)
	(segment
		(start 119.611394 -21.9202)
		(end 119.611394 -21.6789)
		(width 0.1905)
		(layer "In7.Cu")
		(net "M_B_MA1")
	)
	(segment
		(start 161.177478 -5.183378)
		(end 161.174684 -5.183378)
		(width 0.1905)
		(layer "In7.Cu")
		(net "M_B_MA1")
	)
	(segment
		(start 124.9045 -22.1107)
		(end 124.373894 -22.1107)
		(width 0.1905)
		(layer "In7.Cu")
		(net "M_B_MA1")
	)
	(segment
		(start 109.498892 -25.654)
		(end 107.747816 -25.654)
		(width 0.1016)
		(layer "In7.Cu")
		(net "M_B_MA1")
	)
	(segment
		(start 119.801894 -22.1107)
		(end 119.611394 -21.9202)
		(width 0.1905)
		(layer "In7.Cu")
		(net "M_B_MA1")
	)
	(segment
		(start 161.228278 -5.132578)
		(end 161.177478 -5.183378)
		(width 0.1905)
		(layer "In7.Cu")
		(net "M_B_MA1")
	)
	(segment
		(start 120.563894 -21.4884)
		(end 120.373394 -21.6789)
		(width 0.1905)
		(layer "In7.Cu")
		(net "M_B_MA1")
	)
	(segment
		(start 118.849394 -21.9202)
		(end 118.658894 -22.1107)
		(width 0.1905)
		(layer "In7.Cu")
		(net "M_B_MA1")
	)
	(segment
		(start 118.658894 -22.1107)
		(end 118.277894 -22.1107)
		(width 0.1905)
		(layer "In7.Cu")
		(net "M_B_MA1")
	)
	(segment
		(start 122.087894 -21.4884)
		(end 121.897394 -21.6789)
		(width 0.1905)
		(layer "In7.Cu")
		(net "M_B_MA1")
	)
	(segment
		(start 117.896894 -21.4884)
		(end 117.515894 -21.4884)
		(width 0.1905)
		(layer "In7.Cu")
		(net "M_B_MA1")
	)
	(segment
		(start 105.293414 -28.108402)
		(end 103.845868 -28.108402)
		(width 0.1016)
		(layer "In7.Cu")
		(net "M_B_MA1")
	)
	(segment
		(start 103.845868 -28.108402)
		(end 102.9208 -29.03347)
		(width 0.1016)
		(layer "In7.Cu")
		(net "M_B_MA1")
	)
	(segment
		(start 117.515894 -21.4884)
		(end 117.325394 -21.6789)
		(width 0.1905)
		(layer "In7.Cu")
		(net "M_B_MA1")
	)
	(segment
		(start 118.087394 -21.6789)
		(end 117.896894 -21.4884)
		(width 0.1905)
		(layer "In7.Cu")
		(net "M_B_MA1")
	)
	(segment
		(start 160.72612 -6.966458)
		(end 160.401 -7.291578)
		(width 0.1905)
		(layer "In7.Cu")
		(net "M_B_MA1")
	)
	(segment
		(start 121.897394 -21.9202)
		(end 121.706894 -22.1107)
		(width 0.1905)
		(layer "In7.Cu")
		(net "M_B_MA1")
	)
	(segment
		(start 122.468894 -21.4884)
		(end 122.087894 -21.4884)
		(width 0.1905)
		(layer "In7.Cu")
		(net "M_B_MA1")
	)
	(segment
		(start 123.992894 -21.4884)
		(end 123.611894 -21.4884)
		(width 0.1905)
		(layer "In7.Cu")
		(net "M_B_MA1")
	)
	(segment
		(start 120.373394 -21.9202)
		(end 120.182894 -22.1107)
		(width 0.1905)
		(layer "In7.Cu")
		(net "M_B_MA1")
	)
	(segment
		(start 158.7881 -11.698478)
		(end 158.7881 -14.684502)
		(width 0.1905)
		(layer "In7.Cu")
		(net "M_B_MA1")
	)
	(segment
		(start 123.611894 -21.4884)
		(end 123.421394 -21.6789)
		(width 0.1905)
		(layer "In7.Cu")
		(net "M_B_MA1")
	)
	(segment
		(start 160.401 -7.291578)
		(end 160.401 -10.085578)
		(width 0.1905)
		(layer "In7.Cu")
		(net "M_B_MA1")
	)
	(segment
		(start 122.659394 -21.9202)
		(end 122.659394 -21.6789)
		(width 0.1905)
		(layer "In7.Cu")
		(net "M_B_MA1")
	)
	(segment
		(start 124.183394 -21.9202)
		(end 124.183394 -21.6789)
		(width 0.1905)
		(layer "In7.Cu")
		(net "M_B_MA1")
	)
	(segment
		(start 119.420894 -21.4884)
		(end 119.039894 -21.4884)
		(width 0.1905)
		(layer "In7.Cu")
		(net "M_B_MA1")
	)
	(segment
		(start 119.039894 -21.4884)
		(end 118.849394 -21.6789)
		(width 0.1905)
		(layer "In7.Cu")
		(net "M_B_MA1")
	)
	(segment
		(start 161.174684 -5.183378)
		(end 160.726628 -5.631434)
		(width 0.1905)
		(layer "In7.Cu")
		(net "M_B_MA1")
	)
	(segment
		(start 118.087394 -21.9202)
		(end 118.087394 -21.6789)
		(width 0.1905)
		(layer "In7.Cu")
		(net "M_B_MA1")
	)
	(segment
		(start 120.373394 -21.6789)
		(end 120.373394 -21.9202)
		(width 0.1905)
		(layer "In7.Cu")
		(net "M_B_MA1")
	)
	(segment
		(start 107.747816 -25.654)
		(end 105.293414 -28.108402)
		(width 0.1016)
		(layer "In7.Cu")
		(net "M_B_MA1")
	)
	(segment
		(start 160.726628 -5.954522)
		(end 160.72612 -5.95503)
		(width 0.1905)
		(layer "In7.Cu")
		(net "M_B_MA1")
	)
	(segment
		(start 121.135394 -21.6789)
		(end 120.944894 -21.4884)
		(width 0.1905)
		(layer "In7.Cu")
		(net "M_B_MA1")
	)
	(segment
		(start 121.325894 -22.1107)
		(end 121.135394 -21.9202)
		(width 0.1905)
		(layer "In7.Cu")
		(net "M_B_MA1")
	)
	(segment
		(start 117.325394 -21.9202)
		(end 117.134894 -22.1107)
		(width 0.1905)
		(layer "In7.Cu")
		(net "M_B_MA1")
	)
	(segment
		(start 110.553754 -25.031446)
		(end 110.121446 -25.031446)
		(width 0.1016)
		(layer "In7.Cu")
		(net "M_B_MA1")
	)
	(segment
		(start 122.849894 -22.1107)
		(end 122.659394 -21.9202)
		(width 0.1905)
		(layer "In7.Cu")
		(net "M_B_MA1")
	)
	(segment
		(start 160.726628 -5.631434)
		(end 160.726628 -5.954522)
		(width 0.1905)
		(layer "In7.Cu")
		(net "M_B_MA1")
	)
	(segment
		(start 102.9208 -29.03347)
		(end 102.9208 -29.297122)
		(width 0.1016)
		(layer "In7.Cu")
		(net "M_B_MA1")
	)
	(segment
		(start 118.849394 -21.6789)
		(end 118.849394 -21.9202)
		(width 0.1905)
		(layer "In7.Cu")
		(net "M_B_MA1")
	)
	(segment
		(start 120.182894 -22.1107)
		(end 119.801894 -22.1107)
		(width 0.1905)
		(layer "In7.Cu")
		(net "M_B_MA1")
	)
	(segment
		(start 118.277894 -22.1107)
		(end 118.087394 -21.9202)
		(width 0.1905)
		(layer "In7.Cu")
		(net "M_B_MA1")
	)
	(segment
		(start 110.121446 -25.031446)
		(end 109.498892 -25.654)
		(width 0.1016)
		(layer "In7.Cu")
		(net "M_B_MA1")
	)
	(segment
		(start 123.230894 -22.1107)
		(end 122.849894 -22.1107)
		(width 0.1905)
		(layer "In7.Cu")
		(net "M_B_MA1")
	)
	(segment
		(start 151.448262 -21.459952)
		(end 125.555248 -21.459952)
		(width 0.1905)
		(layer "In7.Cu")
		(net "M_B_MA1")
	)
	(segment
		(start 160.401 -10.085578)
		(end 158.7881 -11.698478)
		(width 0.1905)
		(layer "In7.Cu")
		(net "M_B_MA1")
	)
	(segment
		(start 160.72612 -5.95503)
		(end 160.72612 -6.966458)
		(width 0.1905)
		(layer "In7.Cu")
		(net "M_B_MA1")
	)
	(segment
		(start 121.706894 -22.1107)
		(end 121.325894 -22.1107)
		(width 0.1905)
		(layer "In7.Cu")
		(net "M_B_MA1")
	)
	(segment
		(start 110.5916 -24.9936)
		(end 110.553754 -25.031446)
		(width 0.1016)
		(layer "In7.Cu")
		(net "M_B_MA1")
	)
	(segment
		(start 122.659394 -21.6789)
		(end 122.468894 -21.4884)
		(width 0.1905)
		(layer "In7.Cu")
		(net "M_B_MA1")
	)
	(segment
		(start 124.373894 -22.1107)
		(end 124.183394 -21.9202)
		(width 0.1905)
		(layer "In7.Cu")
		(net "M_B_MA1")
	)
	(segment
		(start 116.035074 -22.1107)
		(end 113.152174 -24.9936)
		(width 0.1905)
		(layer "In7.Cu")
		(net "M_B_MA1")
	)
	(segment
		(start 117.134894 -22.1107)
		(end 116.035074 -22.1107)
		(width 0.1905)
		(layer "In7.Cu")
		(net "M_B_MA1")
	)
	(segment
		(start 117.325394 -21.6789)
		(end 117.325394 -21.9202)
		(width 0.1905)
		(layer "In7.Cu")
		(net "M_B_MA1")
	)
	(segment
		(start 123.421394 -21.9202)
		(end 123.230894 -22.1107)
		(width 0.1905)
		(layer "In7.Cu")
		(net "M_B_MA1")
	)
	(segment
		(start 124.183394 -21.6789)
		(end 123.992894 -21.4884)
		(width 0.1905)
		(layer "In7.Cu")
		(net "M_B_MA1")
	)
	(segment
		(start 121.135394 -21.9202)
		(end 121.135394 -21.6789)
		(width 0.1905)
		(layer "In7.Cu")
		(net "M_B_MA1")
	)
	(segment
		(start 120.944894 -21.4884)
		(end 120.563894 -21.4884)
		(width 0.1905)
		(layer "In7.Cu")
		(net "M_B_MA1")
	)
	(segment
		(start 121.897394 -21.6789)
		(end 121.897394 -21.9202)
		(width 0.1905)
		(layer "In7.Cu")
		(net "M_B_MA1")
	)
	(segment
		(start 123.421394 -21.6789)
		(end 123.421394 -21.9202)
		(width 0.1905)
		(layer "In7.Cu")
		(net "M_B_MA1")
	)
	(segment
		(start 113.152174 -24.9936)
		(end 110.5916 -24.9936)
		(width 0.1905)
		(layer "In7.Cu")
		(net "M_B_MA1")
	)
	(segment
		(start 152.371552 -21.10105)
		(end 151.807164 -21.10105)
		(width 0.1905)
		(layer "In7.Cu")
		(net "M_B_MA1")
	)
	(segment
		(start 158.7881 -14.684502)
		(end 152.371552 -21.10105)
		(width 0.1905)
		(layer "In7.Cu")
		(net "M_B_MA1")
	)
	(segment
		(start 119.611394 -21.6789)
		(end 119.420894 -21.4884)
		(width 0.1905)
		(layer "In7.Cu")
		(net "M_B_MA1")
	)
	(segment
		(start 125.555248 -21.459952)
		(end 124.9045 -22.1107)
		(width 0.1905)
		(layer "In7.Cu")
		(net "M_B_MA1")
	)
	(segment
		(start 59.3852 -18.0594)
		(end 59.3852 -17.78)
		(width 0.1143)
		(layer "F.Cu")
		(net "SPI_CLK_GBE_R")
	)
	(segment
		(start 56.7309 -19.0246)
		(end 58.42 -19.0246)
		(width 0.1143)
		(layer "F.Cu")
		(net "SPI_CLK_GBE_R")
	)
	(segment
		(start 58.42 -19.0246)
		(end 59.3852 -18.0594)
		(width 0.1143)
		(layer "F.Cu")
		(net "SPI_CLK_GBE_R")
	)
	(via
		(at 58.42 -19.0246)
		(size 0.7112)
		(drill 0.3556)
		(layers "F.Cu" "B.Cu")
		(net "SPI_CLK_GBE_R")
	)
	(segment
		(start 102.174548 -25.707848)
		(end 102.174548 -26.487374)
		(width 0.1016)
		(layer "F.Cu")
		(net "M_B_DQ22")
	)
	(segment
		(start 142.750032 -1.68402)
		(end 142.750032 -2.971546)
		(width 0.1778)
		(layer "F.Cu")
		(net "M_B_DQ22")
	)
	(segment
		(start 101.7016 -25.019)
		(end 101.727 -25.0444)
		(width 0.1016)
		(layer "F.Cu")
		(net "M_B_DQ22")
	)
	(segment
		(start 142.750032 -2.971546)
		(end 142.5448 -3.176778)
		(width 0.1778)
		(layer "F.Cu")
		(net "M_B_DQ22")
	)
	(segment
		(start 101.727 -25.0444)
		(end 101.727 -25.2603)
		(width 0.1016)
		(layer "F.Cu")
		(net "M_B_DQ22")
	)
	(segment
		(start 102.174548 -26.487374)
		(end 102.245668 -26.558494)
		(width 0.1016)
		(layer "F.Cu")
		(net "M_B_DQ22")
	)
	(segment
		(start 101.727 -25.2603)
		(end 102.174548 -25.707848)
		(width 0.1016)
		(layer "F.Cu")
		(net "M_B_DQ22")
	)
	(via
		(at 142.5448 -3.176778)
		(size 0.4318)
		(drill 0.2032)
		(layers "F.Cu" "B.Cu")
		(net "M_B_DQ22")
	)
	(via
		(at 101.7016 -25.019)
		(size 0.4318)
		(drill 0.2032)
		(layers "F.Cu" "B.Cu")
		(net "M_B_DQ22")
	)
	(segment
		(start 142.450058 -1.690624)
		(end 142.450058 -3.082036)
		(width 0.1778)
		(layer "B.Cu")
		(net "M_B_DQ22")
	)
	(segment
		(start 142.450058 -3.082036)
		(end 142.5448 -3.176778)
		(width 0.1778)
		(layer "B.Cu")
		(net "M_B_DQ22")
	)
	(segment
		(start 142.3924 -3.837178)
		(end 142.0622 -3.837178)
		(width 0.1524)
		(layer "In4.Cu")
		(net "M_B_DQ22")
	)
	(segment
		(start 141.9098 -3.989578)
		(end 141.9098 -4.421378)
		(width 0.1524)
		(layer "In4.Cu")
		(net "M_B_DQ22")
	)
	(segment
		(start 101.3079 -20.8661)
		(end 101.3079 -24.6253)
		(width 0.1016)
		(layer "In4.Cu")
		(net "M_B_DQ22")
	)
	(segment
		(start 104.7496 -18.0848)
		(end 104.3432 -18.0848)
		(width 0.1016)
		(layer "In4.Cu")
		(net "M_B_DQ22")
	)
	(segment
		(start 136.002014 -14.3256)
		(end 113.981738 -14.3256)
		(width 0.1524)
		(layer "In4.Cu")
		(net "M_B_DQ22")
	)
	(segment
		(start 141.6304 -7.316978)
		(end 141.6304 -9.8044)
		(width 0.1524)
		(layer "In4.Cu")
		(net "M_B_DQ22")
	)
	(segment
		(start 142.4432 -4.573778)
		(end 142.5956 -4.726178)
		(width 0.1524)
		(layer "In4.Cu")
		(net "M_B_DQ22")
	)
	(segment
		(start 110.222538 -18.0848)
		(end 104.7496 -18.0848)
		(width 0.1524)
		(layer "In4.Cu")
		(net "M_B_DQ22")
	)
	(segment
		(start 103.6066 -18.8214)
		(end 103.3526 -18.8214)
		(width 0.1016)
		(layer "In4.Cu")
		(net "M_B_DQ22")
	)
	(segment
		(start 138.338814 -11.9888)
		(end 136.002014 -14.3256)
		(width 0.1524)
		(layer "In4.Cu")
		(net "M_B_DQ22")
	)
	(segment
		(start 141.9098 -4.421378)
		(end 142.0622 -4.573778)
		(width 0.1524)
		(layer "In4.Cu")
		(net "M_B_DQ22")
	)
	(segment
		(start 142.5448 -3.684778)
		(end 142.3924 -3.837178)
		(width 0.1524)
		(layer "In4.Cu")
		(net "M_B_DQ22")
	)
	(segment
		(start 104.3432 -18.0848)
		(end 103.6066 -18.8214)
		(width 0.1016)
		(layer "In4.Cu")
		(net "M_B_DQ22")
	)
	(segment
		(start 103.3526 -18.8214)
		(end 101.3079 -20.8661)
		(width 0.1016)
		(layer "In4.Cu")
		(net "M_B_DQ22")
	)
	(segment
		(start 101.3079 -24.6253)
		(end 101.7016 -25.019)
		(width 0.1016)
		(layer "In4.Cu")
		(net "M_B_DQ22")
	)
	(segment
		(start 113.981738 -14.3256)
		(end 110.222538 -18.0848)
		(width 0.1524)
		(layer "In4.Cu")
		(net "M_B_DQ22")
	)
	(segment
		(start 139.446 -11.9888)
		(end 138.338814 -11.9888)
		(width 0.1524)
		(layer "In4.Cu")
		(net "M_B_DQ22")
	)
	(segment
		(start 142.0622 -4.573778)
		(end 142.4432 -4.573778)
		(width 0.1524)
		(layer "In4.Cu")
		(net "M_B_DQ22")
	)
	(segment
		(start 142.5956 -4.726178)
		(end 142.5956 -6.351778)
		(width 0.1524)
		(layer "In4.Cu")
		(net "M_B_DQ22")
	)
	(segment
		(start 141.6304 -9.8044)
		(end 139.446 -11.9888)
		(width 0.1524)
		(layer "In4.Cu")
		(net "M_B_DQ22")
	)
	(segment
		(start 142.0622 -3.837178)
		(end 141.9098 -3.989578)
		(width 0.1524)
		(layer "In4.Cu")
		(net "M_B_DQ22")
	)
	(segment
		(start 142.5956 -6.351778)
		(end 141.6304 -7.316978)
		(width 0.1524)
		(layer "In4.Cu")
		(net "M_B_DQ22")
	)
	(segment
		(start 142.5448 -3.176778)
		(end 142.5448 -3.684778)
		(width 0.1524)
		(layer "In4.Cu")
		(net "M_B_DQ22")
	)
	(via
		(at 61.40831 -10.250678)
		(size 0.508)
		(drill 0.254)
		(layers "F.Cu" "B.Cu")
		(net "CLK_100M_CLKBUFF_ENET_DN")
	)
	(via
		(at 43.25366 -12.5984)
		(size 0.508)
		(drill 0.254)
		(layers "F.Cu" "B.Cu")
		(net "CLK_100M_CLKBUFF_ENET_DN")
	)
	(segment
		(start 61.691266 -8.7884)
		(end 61.691266 -9.967722)
		(width 0.1397)
		(layer "B.Cu")
		(net "CLK_100M_CLKBUFF_ENET_DN")
	)
	(segment
		(start 61.691266 -9.967722)
		(end 61.40831 -10.250678)
		(width 0.1397)
		(layer "B.Cu")
		(net "CLK_100M_CLKBUFF_ENET_DN")
	)
	(segment
		(start 43.3832 -15.5956)
		(end 43.3578 -15.5702)
		(width 0.1397)
		(layer "B.Cu")
		(net "CLK_100M_CLKBUFF_ENET_DN")
	)
	(segment
		(start 61.34989 -8.447024)
		(end 61.691266 -8.7884)
		(width 0.1397)
		(layer "B.Cu")
		(net "CLK_100M_CLKBUFF_ENET_DN")
	)
	(segment
		(start 43.561 -12.90574)
		(end 43.25366 -12.5984)
		(width 0.1397)
		(layer "B.Cu")
		(net "CLK_100M_CLKBUFF_ENET_DN")
	)
	(segment
		(start 43.3832 -16.3576)
		(end 43.3832 -15.5956)
		(width 0.1397)
		(layer "B.Cu")
		(net "CLK_100M_CLKBUFF_ENET_DN")
	)
	(segment
		(start 43.3578 -15.5702)
		(end 43.561 -15.367)
		(width 0.1397)
		(layer "B.Cu")
		(net "CLK_100M_CLKBUFF_ENET_DN")
	)
	(segment
		(start 61.34989 -5.814568)
		(end 61.34989 -8.447024)
		(width 0.1397)
		(layer "B.Cu")
		(net "CLK_100M_CLKBUFF_ENET_DN")
	)
	(segment
		(start 43.561 -15.367)
		(end 43.561 -12.90574)
		(width 0.1397)
		(layer "B.Cu")
		(net "CLK_100M_CLKBUFF_ENET_DN")
	)
	(segment
		(start 43.56735 -11.982196)
		(end 44.805346 -10.7442)
		(width 0.1143)
		(layer "In2.Cu")
		(net "CLK_100M_CLKBUFF_ENET_DN")
	)
	(segment
		(start 43.56735 -12.28471)
		(end 43.56735 -11.982196)
		(width 0.1143)
		(layer "In2.Cu")
		(net "CLK_100M_CLKBUFF_ENET_DN")
	)
	(segment
		(start 43.25366 -12.5984)
		(end 43.56735 -12.28471)
		(width 0.1143)
		(layer "In2.Cu")
		(net "CLK_100M_CLKBUFF_ENET_DN")
	)
	(segment
		(start 44.805346 -10.7442)
		(end 56.8452 -10.7442)
		(width 0.1143)
		(layer "In2.Cu")
		(net "CLK_100M_CLKBUFF_ENET_DN")
	)
	(segment
		(start 61.173106 -10.8712)
		(end 61.55055 -10.8712)
		(width 0.1143)
		(layer "In2.Cu")
		(net "CLK_100M_CLKBUFF_ENET_DN")
	)
	(segment
		(start 57.5564 -10.033)
		(end 60.334906 -10.033)
		(width 0.1143)
		(layer "In2.Cu")
		(net "CLK_100M_CLKBUFF_ENET_DN")
	)
	(segment
		(start 61.70295 -10.7188)
		(end 61.70295 -10.545318)
		(width 0.1143)
		(layer "In2.Cu")
		(net "CLK_100M_CLKBUFF_ENET_DN")
	)
	(segment
		(start 60.334906 -10.033)
		(end 61.173106 -10.8712)
		(width 0.1143)
		(layer "In2.Cu")
		(net "CLK_100M_CLKBUFF_ENET_DN")
	)
	(segment
		(start 61.55055 -10.8712)
		(end 61.70295 -10.7188)
		(width 0.1143)
		(layer "In2.Cu")
		(net "CLK_100M_CLKBUFF_ENET_DN")
	)
	(segment
		(start 56.8452 -10.7442)
		(end 57.5564 -10.033)
		(width 0.1143)
		(layer "In2.Cu")
		(net "CLK_100M_CLKBUFF_ENET_DN")
	)
	(segment
		(start 61.70295 -10.545318)
		(end 61.40831 -10.250678)
		(width 0.1143)
		(layer "In2.Cu")
		(net "CLK_100M_CLKBUFF_ENET_DN")
	)
	(via
		(at 20.7264 -61.242448)
		(size 0.7112)
		(drill 0.3556)
		(layers "F.Cu" "B.Cu")
		(net "VR_PVNN_FB_RC2")
	)
	(segment
		(start 19.812 -61.5188)
		(end 20.450048 -61.5188)
		(width 0.2032)
		(layer "B.Cu")
		(net "VR_PVNN_FB_RC2")
	)
	(segment
		(start 20.7264 -61.242448)
		(end 20.7264 -60.4266)
		(width 0.2032)
		(layer "B.Cu")
		(net "VR_PVNN_FB_RC2")
	)
	(segment
		(start 20.450048 -61.5188)
		(end 20.7264 -61.242448)
		(width 0.2032)
		(layer "B.Cu")
		(net "VR_PVNN_FB_RC2")
	)
	(segment
		(start 20.7264 -60.4266)
		(end 20.701 -60.4012)
		(width 0.2032)
		(layer "B.Cu")
		(net "VR_PVNN_FB_RC2")
	)
	(segment
		(start 166.150036 -1.68402)
		(end 166.150036 -2.696464)
		(width 0.2413)
		(layer "F.Cu")
		(net "M_B_BS0")
	)
	(segment
		(start 166.253414 -4.93776)
		(end 166.452804 -5.13715)
		(width 0.2413)
		(layer "F.Cu")
		(net "M_B_BS0")
	)
	(segment
		(start 103.563928 -31.902654)
		(end 103.1748 -32.3596)
		(width 0.0889)
		(layer "F.Cu")
		(net "M_B_BS0")
	)
	(segment
		(start 166.452804 -5.13715)
		(end 166.5478 -5.13715)
		(width 0.2413)
		(layer "F.Cu")
		(net "M_B_BS0")
	)
	(segment
		(start 166.253414 -2.799842)
		(end 166.253414 -4.93776)
		(width 0.2413)
		(layer "F.Cu")
		(net "M_B_BS0")
	)
	(segment
		(start 166.150036 -2.696464)
		(end 166.253414 -2.799842)
		(width 0.2413)
		(layer "F.Cu")
		(net "M_B_BS0")
	)
	(via
		(at 103.1748 -32.3596)
		(size 0.4318)
		(drill 0.2032)
		(layers "F.Cu" "B.Cu")
		(net "M_B_BS0")
	)
	(via
		(at 166.5478 -5.13715)
		(size 0.4318)
		(drill 0.2032)
		(layers "F.Cu" "B.Cu")
		(net "M_B_BS0")
	)
	(segment
		(start 166.99865 -6.597904)
		(end 166.99865 -5.583428)
		(width 0.2413)
		(layer "B.Cu")
		(net "M_B_BS0")
	)
	(segment
		(start 166.150036 -7.446518)
		(end 166.99865 -6.597904)
		(width 0.2413)
		(layer "B.Cu")
		(net "M_B_BS0")
	)
	(segment
		(start 166.552372 -5.13715)
		(end 166.5478 -5.13715)
		(width 0.2413)
		(layer "B.Cu")
		(net "M_B_BS0")
	)
	(segment
		(start 166.99865 -5.583428)
		(end 166.552372 -5.13715)
		(width 0.2413)
		(layer "B.Cu")
		(net "M_B_BS0")
	)
	(segment
		(start 166.150036 -9.89076)
		(end 166.150036 -7.446518)
		(width 0.2413)
		(layer "B.Cu")
		(net "M_B_BS0")
	)
	(segment
		(start 170.03268 -5.366258)
		(end 170.03268 -14.90472)
		(width 0.1905)
		(layer "In7.Cu")
		(net "M_B_BS0")
	)
	(segment
		(start 167.092376 -4.592574)
		(end 169.258996 -4.592574)
		(width 0.1905)
		(layer "In7.Cu")
		(net "M_B_BS0")
	)
	(segment
		(start 169.258996 -4.592574)
		(end 170.03268 -5.366258)
		(width 0.1905)
		(layer "In7.Cu")
		(net "M_B_BS0")
	)
	(segment
		(start 110.15726 -31.914338)
		(end 111.91748 -31.914338)
		(width 0.1016)
		(layer "In7.Cu")
		(net "M_B_BS0")
	)
	(segment
		(start 114.113818 -29.718)
		(end 112.014 -31.817818)
		(width 0.1905)
		(layer "In7.Cu")
		(net "M_B_BS0")
	)
	(segment
		(start 105.737406 -31.651194)
		(end 109.894116 -31.651194)
		(width 0.1016)
		(layer "In7.Cu")
		(net "M_B_BS0")
	)
	(segment
		(start 104.9401 -32.4485)
		(end 105.737406 -31.651194)
		(width 0.1016)
		(layer "In7.Cu")
		(net "M_B_BS0")
	)
	(segment
		(start 103.1748 -32.3596)
		(end 103.2637 -32.4485)
		(width 0.1016)
		(layer "In7.Cu")
		(net "M_B_BS0")
	)
	(segment
		(start 103.2637 -32.4485)
		(end 104.9401 -32.4485)
		(width 0.1016)
		(layer "In7.Cu")
		(net "M_B_BS0")
	)
	(segment
		(start 170.03268 -14.90472)
		(end 155.7274 -29.21)
		(width 0.1905)
		(layer "In7.Cu")
		(net "M_B_BS0")
	)
	(segment
		(start 109.894116 -31.651194)
		(end 110.15726 -31.914338)
		(width 0.1016)
		(layer "In7.Cu")
		(net "M_B_BS0")
	)
	(segment
		(start 118.1608 -29.718)
		(end 114.113818 -29.718)
		(width 0.1905)
		(layer "In7.Cu")
		(net "M_B_BS0")
	)
	(segment
		(start 111.91748 -31.914338)
		(end 112.014 -31.817818)
		(width 0.1016)
		(layer "In7.Cu")
		(net "M_B_BS0")
	)
	(segment
		(start 118.6688 -29.21)
		(end 118.1608 -29.718)
		(width 0.1905)
		(layer "In7.Cu")
		(net "M_B_BS0")
	)
	(segment
		(start 166.5478 -5.13715)
		(end 167.092376 -4.592574)
		(width 0.1905)
		(layer "In7.Cu")
		(net "M_B_BS0")
	)
	(segment
		(start 155.7274 -29.21)
		(end 118.6688 -29.21)
		(width 0.1905)
		(layer "In7.Cu")
		(net "M_B_BS0")
	)
	(segment
		(start 103.9114 -29.18714)
		(end 103.91394 -29.18714)
		(width 0.1016)
		(layer "F.Cu")
		(net "M_B_MA2")
	)
	(segment
		(start 162.12947 -8.969248)
		(end 162.12947 -6.525006)
		(width 0.2413)
		(layer "F.Cu")
		(net "M_B_MA2")
	)
	(segment
		(start 103.578914 -28.854654)
		(end 103.9114 -29.18714)
		(width 0.1016)
		(layer "F.Cu")
		(net "M_B_MA2")
	)
	(segment
		(start 162.249866 -9.897364)
		(end 162.249866 -9.089644)
		(width 0.2413)
		(layer "F.Cu")
		(net "M_B_MA2")
	)
	(segment
		(start 162.249866 -9.089644)
		(end 162.12947 -8.969248)
		(width 0.2413)
		(layer "F.Cu")
		(net "M_B_MA2")
	)
	(segment
		(start 103.563928 -28.854654)
		(end 103.578914 -28.854654)
		(width 0.1016)
		(layer "F.Cu")
		(net "M_B_MA2")
	)
	(segment
		(start 162.12947 -6.525006)
		(end 162.12566 -6.521196)
		(width 0.2413)
		(layer "F.Cu")
		(net "M_B_MA2")
	)
	(via
		(at 103.91394 -29.18714)
		(size 0.4318)
		(drill 0.2032)
		(layers "F.Cu" "B.Cu")
		(net "M_B_MA2")
	)
	(via
		(at 162.12566 -6.521196)
		(size 0.4318)
		(drill 0.2032)
		(layers "F.Cu" "B.Cu")
		(net "M_B_MA2")
	)
	(segment
		(start 162.657028 -6.08584)
		(end 162.221672 -6.521196)
		(width 0.2413)
		(layer "B.Cu")
		(net "M_B_MA2")
	)
	(segment
		(start 162.657028 -4.391406)
		(end 162.657028 -6.08584)
		(width 0.2413)
		(layer "B.Cu")
		(net "M_B_MA2")
	)
	(segment
		(start 162.18408 -3.918458)
		(end 162.657028 -4.391406)
		(width 0.2413)
		(layer "B.Cu")
		(net "M_B_MA2")
	)
	(segment
		(start 162.221672 -6.521196)
		(end 162.12566 -6.521196)
		(width 0.2413)
		(layer "B.Cu")
		(net "M_B_MA2")
	)
	(segment
		(start 162.249866 -2.735834)
		(end 162.18408 -2.80162)
		(width 0.2413)
		(layer "B.Cu")
		(net "M_B_MA2")
	)
	(segment
		(start 162.18408 -2.80162)
		(end 162.18408 -3.918458)
		(width 0.2413)
		(layer "B.Cu")
		(net "M_B_MA2")
	)
	(segment
		(start 162.249866 -1.690624)
		(end 162.249866 -2.735834)
		(width 0.2413)
		(layer "B.Cu")
		(net "M_B_MA2")
	)
	(segment
		(start 156.311854 -20.070572)
		(end 156.042614 -20.070572)
		(width 0.1905)
		(layer "In7.Cu")
		(net "M_B_MA2")
	)
	(segment
		(start 156.850842 -19.531584)
		(end 156.915866 -19.596608)
		(width 0.1905)
		(layer "In7.Cu")
		(net "M_B_MA2")
	)
	(segment
		(start 110.744 -26.4922)
		(end 110.998 -26.2382)
		(width 0.1016)
		(layer "In7.Cu")
		(net "M_B_MA2")
	)
	(segment
		(start 156.042614 -20.070572)
		(end 152.135332 -23.977854)
		(width 0.1905)
		(layer "In7.Cu")
		(net "M_B_MA2")
	)
	(segment
		(start 109.2708 -27.3812)
		(end 110.1598 -26.4922)
		(width 0.1016)
		(layer "In7.Cu")
		(net "M_B_MA2")
	)
	(segment
		(start 151.619966 -23.9776)
		(end 116.808504 -23.9776)
		(width 0.1905)
		(layer "In7.Cu")
		(net "M_B_MA2")
	)
	(segment
		(start 160.08477 -16.297656)
		(end 160.149794 -16.36268)
		(width 0.1905)
		(layer "In7.Cu")
		(net "M_B_MA2")
	)
	(segment
		(start 157.38983 -18.992596)
		(end 157.12059 -18.992596)
		(width 0.1905)
		(layer "In7.Cu")
		(net "M_B_MA2")
	)
	(segment
		(start 156.850842 -19.262344)
		(end 156.850842 -19.531584)
		(width 0.1905)
		(layer "In7.Cu")
		(net "M_B_MA2")
	)
	(segment
		(start 159.071818 -17.440656)
		(end 159.071818 -17.709896)
		(width 0.1905)
		(layer "In7.Cu")
		(net "M_B_MA2")
	)
	(segment
		(start 157.12059 -18.992596)
		(end 156.850842 -19.262344)
		(width 0.1905)
		(layer "In7.Cu")
		(net "M_B_MA2")
	)
	(segment
		(start 113.3856 -26.2382)
		(end 113.5126 -26.3652)
		(width 0.1016)
		(layer "In7.Cu")
		(net "M_B_MA2")
	)
	(segment
		(start 104.357678 -28.743402)
		(end 105.520998 -28.743402)
		(width 0.1016)
		(layer "In7.Cu")
		(net "M_B_MA2")
	)
	(segment
		(start 162.12947 -6.525006)
		(end 162.12947 -10.363708)
		(width 0.1905)
		(layer "In7.Cu")
		(net "M_B_MA2")
	)
	(segment
		(start 160.149794 -16.63192)
		(end 159.880046 -16.901668)
		(width 0.1905)
		(layer "In7.Cu")
		(net "M_B_MA2")
	)
	(segment
		(start 160.08477 -16.028416)
		(end 160.08477 -16.297656)
		(width 0.1905)
		(layer "In7.Cu")
		(net "M_B_MA2")
	)
	(segment
		(start 158.198566 -17.91462)
		(end 157.928818 -18.184368)
		(width 0.1905)
		(layer "In7.Cu")
		(net "M_B_MA2")
	)
	(segment
		(start 159.276542 -16.836644)
		(end 159.006794 -17.106392)
		(width 0.1905)
		(layer "In7.Cu")
		(net "M_B_MA2")
	)
	(segment
		(start 159.610806 -16.901668)
		(end 159.545782 -16.836644)
		(width 0.1905)
		(layer "In7.Cu")
		(net "M_B_MA2")
	)
	(segment
		(start 156.915866 -19.865848)
		(end 156.646118 -20.135596)
		(width 0.1905)
		(layer "In7.Cu")
		(net "M_B_MA2")
	)
	(segment
		(start 162.12566 -6.521196)
		(end 162.12947 -6.525006)
		(width 0.1905)
		(layer "In7.Cu")
		(net "M_B_MA2")
	)
	(segment
		(start 157.928818 -18.453608)
		(end 157.993842 -18.518632)
		(width 0.1905)
		(layer "In7.Cu")
		(net "M_B_MA2")
	)
	(segment
		(start 157.454854 -19.05762)
		(end 157.38983 -18.992596)
		(width 0.1905)
		(layer "In7.Cu")
		(net "M_B_MA2")
	)
	(segment
		(start 152.135332 -23.977854)
		(end 151.62022 -23.977854)
		(width 0.1905)
		(layer "In7.Cu")
		(net "M_B_MA2")
	)
	(segment
		(start 103.91394 -29.18714)
		(end 104.357678 -28.743402)
		(width 0.1016)
		(layer "In7.Cu")
		(net "M_B_MA2")
	)
	(segment
		(start 159.880046 -16.901668)
		(end 159.610806 -16.901668)
		(width 0.1905)
		(layer "In7.Cu")
		(net "M_B_MA2")
	)
	(segment
		(start 156.915866 -19.596608)
		(end 156.915866 -19.865848)
		(width 0.1905)
		(layer "In7.Cu")
		(net "M_B_MA2")
	)
	(segment
		(start 158.53283 -17.979644)
		(end 158.467806 -17.91462)
		(width 0.1905)
		(layer "In7.Cu")
		(net "M_B_MA2")
	)
	(segment
		(start 116.808504 -23.9776)
		(end 114.420904 -26.3652)
		(width 0.1905)
		(layer "In7.Cu")
		(net "M_B_MA2")
	)
	(segment
		(start 158.467806 -17.91462)
		(end 158.198566 -17.91462)
		(width 0.1905)
		(layer "In7.Cu")
		(net "M_B_MA2")
	)
	(segment
		(start 160.149794 -16.36268)
		(end 160.149794 -16.63192)
		(width 0.1905)
		(layer "In7.Cu")
		(net "M_B_MA2")
	)
	(segment
		(start 161.3662 -14.746986)
		(end 160.08477 -16.028416)
		(width 0.1905)
		(layer "In7.Cu")
		(net "M_B_MA2")
	)
	(segment
		(start 110.1598 -26.4922)
		(end 110.744 -26.4922)
		(width 0.1016)
		(layer "In7.Cu")
		(net "M_B_MA2")
	)
	(segment
		(start 106.8832 -27.3812)
		(end 109.2708 -27.3812)
		(width 0.1016)
		(layer "In7.Cu")
		(net "M_B_MA2")
	)
	(segment
		(start 151.62022 -23.977854)
		(end 151.619966 -23.9776)
		(width 0.1905)
		(layer "In7.Cu")
		(net "M_B_MA2")
	)
	(segment
		(start 161.3662 -11.126978)
		(end 161.3662 -14.746986)
		(width 0.1905)
		(layer "In7.Cu")
		(net "M_B_MA2")
	)
	(segment
		(start 159.545782 -16.836644)
		(end 159.276542 -16.836644)
		(width 0.1905)
		(layer "In7.Cu")
		(net "M_B_MA2")
	)
	(segment
		(start 157.724094 -19.05762)
		(end 157.454854 -19.05762)
		(width 0.1905)
		(layer "In7.Cu")
		(net "M_B_MA2")
	)
	(segment
		(start 110.998 -26.2382)
		(end 113.3856 -26.2382)
		(width 0.1016)
		(layer "In7.Cu")
		(net "M_B_MA2")
	)
	(segment
		(start 114.420904 -26.3652)
		(end 113.5126 -26.3652)
		(width 0.1905)
		(layer "In7.Cu")
		(net "M_B_MA2")
	)
	(segment
		(start 162.12947 -10.363708)
		(end 161.3662 -11.126978)
		(width 0.1905)
		(layer "In7.Cu")
		(net "M_B_MA2")
	)
	(segment
		(start 157.993842 -18.518632)
		(end 157.993842 -18.787872)
		(width 0.1905)
		(layer "In7.Cu")
		(net "M_B_MA2")
	)
	(segment
		(start 105.520998 -28.743402)
		(end 106.8832 -27.3812)
		(width 0.1016)
		(layer "In7.Cu")
		(net "M_B_MA2")
	)
	(segment
		(start 158.80207 -17.979644)
		(end 158.53283 -17.979644)
		(width 0.1905)
		(layer "In7.Cu")
		(net "M_B_MA2")
	)
	(segment
		(start 156.646118 -20.135596)
		(end 156.376878 -20.135596)
		(width 0.1905)
		(layer "In7.Cu")
		(net "M_B_MA2")
	)
	(segment
		(start 159.006794 -17.106392)
		(end 159.006794 -17.375632)
		(width 0.1905)
		(layer "In7.Cu")
		(net "M_B_MA2")
	)
	(segment
		(start 157.993842 -18.787872)
		(end 157.724094 -19.05762)
		(width 0.1905)
		(layer "In7.Cu")
		(net "M_B_MA2")
	)
	(segment
		(start 159.071818 -17.709896)
		(end 158.80207 -17.979644)
		(width 0.1905)
		(layer "In7.Cu")
		(net "M_B_MA2")
	)
	(segment
		(start 157.928818 -18.184368)
		(end 157.928818 -18.453608)
		(width 0.1905)
		(layer "In7.Cu")
		(net "M_B_MA2")
	)
	(segment
		(start 159.006794 -17.375632)
		(end 159.071818 -17.440656)
		(width 0.1905)
		(layer "In7.Cu")
		(net "M_B_MA2")
	)
	(segment
		(start 156.376878 -20.135596)
		(end 156.311854 -20.070572)
		(width 0.1905)
		(layer "In7.Cu")
		(net "M_B_MA2")
	)
	(segment
		(start 43.51909 -18.03654)
		(end 43.51909 -18.6563)
		(width 0.1397)
		(layer "B.Cu")
		(net "CLK_100M_CLKBUFF_ENET_R_DN")
	)
	(segment
		(start 43.59783 -17.9578)
		(end 43.51909 -18.03654)
		(width 0.1397)
		(layer "B.Cu")
		(net "CLK_100M_CLKBUFF_ENET_R_DN")
	)
	(segment
		(start 43.59783 -17.43583)
		(end 43.59783 -17.9578)
		(width 0.1397)
		(layer "B.Cu")
		(net "CLK_100M_CLKBUFF_ENET_R_DN")
	)
	(segment
		(start 43.3832 -17.2212)
		(end 43.59783 -17.43583)
		(width 0.1397)
		(layer "B.Cu")
		(net "CLK_100M_CLKBUFF_ENET_R_DN")
	)
	(segment
		(start 11.176 -59.9948)
		(end 12.4968 -61.3156)
		(width 0.127)
		(layer "F.Cu")
		(net "TP_PVCCP_ALERT")
	)
	(segment
		(start 11.176 -59.436)
		(end 11.176 -59.9948)
		(width 0.127)
		(layer "F.Cu")
		(net "TP_PVCCP_ALERT")
	)
	(segment
		(start 173.231302 -3.757676)
		(end 173.231302 -3.771392)
		(width 0.1778)
		(layer "F.Cu")
		(net "M_B_DQ38")
	)
	(segment
		(start 173.49724 -3.491738)
		(end 173.231302 -3.757676)
		(width 0.1778)
		(layer "F.Cu")
		(net "M_B_DQ38")
	)
	(segment
		(start 173.949868 -1.68402)
		(end 173.949868 -2.43459)
		(width 0.1778)
		(layer "F.Cu")
		(net "M_B_DQ38")
	)
	(segment
		(start 173.49724 -2.887218)
		(end 173.49724 -3.491738)
		(width 0.1778)
		(layer "F.Cu")
		(net "M_B_DQ38")
	)
	(segment
		(start 109.236002 -32.5882)
		(end 108.814108 -33.010094)
		(width 0.1778)
		(layer "F.Cu")
		(net "M_B_DQ38")
	)
	(segment
		(start 109.6518 -32.5882)
		(end 109.236002 -32.5882)
		(width 0.1778)
		(layer "F.Cu")
		(net "M_B_DQ38")
	)
	(segment
		(start 173.949868 -2.43459)
		(end 173.49724 -2.887218)
		(width 0.1778)
		(layer "F.Cu")
		(net "M_B_DQ38")
	)
	(via
		(at 173.231302 -3.771392)
		(size 0.4318)
		(drill 0.2032)
		(layers "F.Cu" "B.Cu")
		(net "M_B_DQ38")
	)
	(via
		(at 109.6518 -32.5882)
		(size 0.4318)
		(drill 0.2032)
		(layers "F.Cu" "B.Cu")
		(net "M_B_DQ38")
	)
	(segment
		(start 173.049946 -2.558034)
		(end 173.49724 -3.005328)
		(width 0.1778)
		(layer "B.Cu")
		(net "M_B_DQ38")
	)
	(segment
		(start 173.049946 -1.690624)
		(end 173.049946 -2.558034)
		(width 0.1778)
		(layer "B.Cu")
		(net "M_B_DQ38")
	)
	(segment
		(start 173.49724 -3.005328)
		(end 173.49724 -3.491738)
		(width 0.1778)
		(layer "B.Cu")
		(net "M_B_DQ38")
	)
	(segment
		(start 173.49724 -3.491738)
		(end 173.231302 -3.757676)
		(width 0.1778)
		(layer "B.Cu")
		(net "M_B_DQ38")
	)
	(segment
		(start 173.231302 -3.757676)
		(end 173.231302 -3.771392)
		(width 0.1778)
		(layer "B.Cu")
		(net "M_B_DQ38")
	)
	(segment
		(start 157.872938 -29.718)
		(end 175.26 -12.330938)
		(width 0.1524)
		(layer "In4.Cu")
		(net "M_B_DQ38")
	)
	(segment
		(start 136.9822 -29.8704)
		(end 136.9822 -30.23743)
		(width 0.1524)
		(layer "In4.Cu")
		(net "M_B_DQ38")
	)
	(segment
		(start 151.24557 -30.38983)
		(end 151.9174 -29.718)
		(width 0.1524)
		(layer "In4.Cu")
		(net "M_B_DQ38")
	)
	(segment
		(start 175.26 -8.405622)
		(end 174.5742 -7.719822)
		(width 0.1524)
		(layer "In4.Cu")
		(net "M_B_DQ38")
	)
	(segment
		(start 112.8776 -30.9118)
		(end 113.6142 -30.9118)
		(width 0.1524)
		(layer "In4.Cu")
		(net "M_B_DQ38")
	)
	(segment
		(start 117.5766 -30.099)
		(end 124.2314 -30.099)
		(width 0.1524)
		(layer "In4.Cu")
		(net "M_B_DQ38")
	)
	(segment
		(start 110.1598 -32.0802)
		(end 111.7092 -32.0802)
		(width 0.1524)
		(layer "In4.Cu")
		(net "M_B_DQ38")
	)
	(segment
		(start 173.231302 -4.39928)
		(end 173.231302 -3.771392)
		(width 0.1524)
		(layer "In4.Cu")
		(net "M_B_DQ38")
	)
	(segment
		(start 174.5742 -7.719822)
		(end 174.5742 -5.742178)
		(width 0.1524)
		(layer "In4.Cu")
		(net "M_B_DQ38")
	)
	(segment
		(start 136.9822 -30.23743)
		(end 137.1346 -30.38983)
		(width 0.1524)
		(layer "In4.Cu")
		(net "M_B_DQ38")
	)
	(segment
		(start 114.8588 -29.6672)
		(end 117.1448 -29.6672)
		(width 0.1524)
		(layer "In4.Cu")
		(net "M_B_DQ38")
	)
	(segment
		(start 125.6284 -29.9974)
		(end 126.238 -29.9974)
		(width 0.1524)
		(layer "In4.Cu")
		(net "M_B_DQ38")
	)
	(segment
		(start 124.2314 -30.099)
		(end 124.6124 -29.718)
		(width 0.1524)
		(layer "In4.Cu")
		(net "M_B_DQ38")
	)
	(segment
		(start 126.5174 -29.718)
		(end 136.8298 -29.718)
		(width 0.1524)
		(layer "In4.Cu")
		(net "M_B_DQ38")
	)
	(segment
		(start 111.7092 -32.0802)
		(end 112.8776 -30.9118)
		(width 0.1524)
		(layer "In4.Cu")
		(net "M_B_DQ38")
	)
	(segment
		(start 125.349 -29.718)
		(end 125.6284 -29.9974)
		(width 0.1524)
		(layer "In4.Cu")
		(net "M_B_DQ38")
	)
	(segment
		(start 113.6142 -30.9118)
		(end 114.8588 -29.6672)
		(width 0.1524)
		(layer "In4.Cu")
		(net "M_B_DQ38")
	)
	(segment
		(start 117.1448 -29.6672)
		(end 117.5766 -30.099)
		(width 0.1524)
		(layer "In4.Cu")
		(net "M_B_DQ38")
	)
	(segment
		(start 124.6124 -29.718)
		(end 125.349 -29.718)
		(width 0.1524)
		(layer "In4.Cu")
		(net "M_B_DQ38")
	)
	(segment
		(start 174.5742 -5.742178)
		(end 173.231302 -4.39928)
		(width 0.1524)
		(layer "In4.Cu")
		(net "M_B_DQ38")
	)
	(segment
		(start 109.6518 -32.5882)
		(end 110.1598 -32.0802)
		(width 0.1524)
		(layer "In4.Cu")
		(net "M_B_DQ38")
	)
	(segment
		(start 126.238 -29.9974)
		(end 126.5174 -29.718)
		(width 0.1524)
		(layer "In4.Cu")
		(net "M_B_DQ38")
	)
	(segment
		(start 137.1346 -30.38983)
		(end 151.24557 -30.38983)
		(width 0.1524)
		(layer "In4.Cu")
		(net "M_B_DQ38")
	)
	(segment
		(start 175.26 -12.330938)
		(end 175.26 -8.405622)
		(width 0.1524)
		(layer "In4.Cu")
		(net "M_B_DQ38")
	)
	(segment
		(start 151.9174 -29.718)
		(end 157.872938 -29.718)
		(width 0.1524)
		(layer "In4.Cu")
		(net "M_B_DQ38")
	)
	(segment
		(start 136.8298 -29.718)
		(end 136.9822 -29.8704)
		(width 0.1524)
		(layer "In4.Cu")
		(net "M_B_DQ38")
	)
	(segment
		(start 44.01947 -18.03654)
		(end 44.01947 -18.6563)
		(width 0.1397)
		(layer "B.Cu")
		(net "CLK_100M_CLKBUFF_ENET_R_DP")
	)
	(segment
		(start 43.94073 -17.42567)
		(end 43.94073 -17.9578)
		(width 0.1397)
		(layer "B.Cu")
		(net "CLK_100M_CLKBUFF_ENET_R_DP")
	)
	(segment
		(start 44.1452 -17.2212)
		(end 43.94073 -17.42567)
		(width 0.1397)
		(layer "B.Cu")
		(net "CLK_100M_CLKBUFF_ENET_R_DP")
	)
	(segment
		(start 43.94073 -17.9578)
		(end 44.01947 -18.03654)
		(width 0.1397)
		(layer "B.Cu")
		(net "CLK_100M_CLKBUFF_ENET_R_DP")
	)
	(segment
		(start 100.6475 -29.971746)
		(end 100.647754 -29.971746)
		(width 0.1016)
		(layer "F.Cu")
		(net "M_B_BS2")
	)
	(segment
		(start 100.292408 -29.616654)
		(end 100.6475 -29.971746)
		(width 0.1016)
		(layer "F.Cu")
		(net "M_B_BS2")
	)
	(segment
		(start 157.482286 -6.315456)
		(end 157.41142 -6.315456)
		(width 0.2413)
		(layer "F.Cu")
		(net "M_B_BS2")
	)
	(segment
		(start 157.750002 -1.68402)
		(end 157.750002 -3.186176)
		(width 0.2413)
		(layer "F.Cu")
		(net "M_B_BS2")
	)
	(segment
		(start 157.750002 -3.186176)
		(end 157.869128 -3.305302)
		(width 0.2413)
		(layer "F.Cu")
		(net "M_B_BS2")
	)
	(segment
		(start 157.869128 -5.928614)
		(end 157.482286 -6.315456)
		(width 0.2413)
		(layer "F.Cu")
		(net "M_B_BS2")
	)
	(segment
		(start 157.869128 -3.305302)
		(end 157.869128 -5.928614)
		(width 0.2413)
		(layer "F.Cu")
		(net "M_B_BS2")
	)
	(via
		(at 157.41142 -6.315456)
		(size 0.4318)
		(drill 0.2032)
		(layers "F.Cu" "B.Cu")
		(net "M_B_BS2")
	)
	(via
		(at 100.647754 -29.971746)
		(size 0.4318)
		(drill 0.2032)
		(layers "F.Cu" "B.Cu")
		(net "M_B_BS2")
	)
	(segment
		(start 157.41142 -7.381494)
		(end 157.41142 -6.315456)
		(width 0.2413)
		(layer "B.Cu")
		(net "M_B_BS2")
	)
	(segment
		(start 157.750002 -9.89076)
		(end 157.750002 -7.720076)
		(width 0.2413)
		(layer "B.Cu")
		(net "M_B_BS2")
	)
	(segment
		(start 157.750002 -7.720076)
		(end 157.41142 -7.381494)
		(width 0.2413)
		(layer "B.Cu")
		(net "M_B_BS2")
	)
	(segment
		(start 100.3681 -28.718256)
		(end 100.3681 -27.4701)
		(width 0.1016)
		(layer "In7.Cu")
		(net "M_B_BS2")
	)
	(segment
		(start 139.498578 -14.2748)
		(end 139.308078 -14.4653)
		(width 0.1905)
		(layer "In7.Cu")
		(net "M_B_BS2")
	)
	(segment
		(start 141.594078 -14.4653)
		(end 141.594078 -15.1003)
		(width 0.1905)
		(layer "In7.Cu")
		(net "M_B_BS2")
	)
	(segment
		(start 144.9451 -16.573246)
		(end 144.7546 -16.382746)
		(width 0.1905)
		(layer "In7.Cu")
		(net "M_B_BS2")
	)
	(segment
		(start 157.41142 -6.315456)
		(end 157.41142 -6.496558)
		(width 0.1905)
		(layer "In7.Cu")
		(net "M_B_BS2")
	)
	(segment
		(start 137.2489 -16.573246)
		(end 136.283446 -16.573246)
		(width 0.1905)
		(layer "In7.Cu")
		(net "M_B_BS2")
	)
	(segment
		(start 142.737078 -15.113)
		(end 142.737078 -14.4653)
		(width 0.1905)
		(layer "In7.Cu")
		(net "M_B_BS2")
	)
	(segment
		(start 137.4394 -16.382746)
		(end 137.2489 -16.573246)
		(width 0.1905)
		(layer "In7.Cu")
		(net "M_B_BS2")
	)
	(segment
		(start 137.6426 -15.2908)
		(end 137.4394 -15.494)
		(width 0.1905)
		(layer "In7.Cu")
		(net "M_B_BS2")
	)
	(segment
		(start 156.0576 -7.266178)
		(end 155.6258 -7.697978)
		(width 0.1905)
		(layer "In7.Cu")
		(net "M_B_BS2")
	)
	(segment
		(start 144.7546 -15.5194)
		(end 144.5514 -15.3162)
		(width 0.1905)
		(layer "In7.Cu")
		(net "M_B_BS2")
	)
	(segment
		(start 155.630626 -9.570974)
		(end 148.628354 -16.573246)
		(width 0.1905)
		(layer "In7.Cu")
		(net "M_B_BS2")
	)
	(segment
		(start 141.594078 -15.1003)
		(end 141.403578 -15.2908)
		(width 0.1905)
		(layer "In7.Cu")
		(net "M_B_BS2")
	)
	(segment
		(start 137.4394 -15.494)
		(end 137.4394 -16.382746)
		(width 0.1905)
		(layer "In7.Cu")
		(net "M_B_BS2")
	)
	(segment
		(start 139.308078 -15.0876)
		(end 139.104878 -15.2908)
		(width 0.1905)
		(layer "In7.Cu")
		(net "M_B_BS2")
	)
	(segment
		(start 140.451078 -15.1003)
		(end 140.451078 -14.4653)
		(width 0.1905)
		(layer "In7.Cu")
		(net "M_B_BS2")
	)
	(segment
		(start 144.7546 -16.382746)
		(end 144.7546 -15.5194)
		(width 0.1905)
		(layer "In7.Cu")
		(net "M_B_BS2")
	)
	(segment
		(start 155.6258 -7.697978)
		(end 155.6258 -8.242808)
		(width 0.1905)
		(layer "In7.Cu")
		(net "M_B_BS2")
	)
	(segment
		(start 142.737078 -14.4653)
		(end 142.546578 -14.2748)
		(width 0.1905)
		(layer "In7.Cu")
		(net "M_B_BS2")
	)
	(segment
		(start 103.9114 -25.7048)
		(end 103.9114 -21.6408)
		(width 0.1016)
		(layer "In7.Cu")
		(net "M_B_BS2")
	)
	(segment
		(start 141.784578 -14.2748)
		(end 141.594078 -14.4653)
		(width 0.1905)
		(layer "In7.Cu")
		(net "M_B_BS2")
	)
	(segment
		(start 136.27735 -16.56715)
		(end 115.30838 -16.56715)
		(width 0.1905)
		(layer "In7.Cu")
		(net "M_B_BS2")
	)
	(segment
		(start 139.308078 -14.4653)
		(end 139.308078 -15.0876)
		(width 0.1905)
		(layer "In7.Cu")
		(net "M_B_BS2")
	)
	(segment
		(start 103.6574 -25.9588)
		(end 103.9114 -25.7048)
		(width 0.1016)
		(layer "In7.Cu")
		(net "M_B_BS2")
	)
	(segment
		(start 101.8794 -25.9588)
		(end 103.6574 -25.9588)
		(width 0.1016)
		(layer "In7.Cu")
		(net "M_B_BS2")
	)
	(segment
		(start 140.451078 -14.4653)
		(end 140.260578 -14.2748)
		(width 0.1905)
		(layer "In7.Cu")
		(net "M_B_BS2")
	)
	(segment
		(start 115.30838 -16.56715)
		(end 110.56493 -21.3106)
		(width 0.1905)
		(layer "In7.Cu")
		(net "M_B_BS2")
	)
	(segment
		(start 100.482654 -28.83281)
		(end 100.3681 -28.718256)
		(width 0.1016)
		(layer "In7.Cu")
		(net "M_B_BS2")
	)
	(segment
		(start 142.546578 -14.2748)
		(end 141.784578 -14.2748)
		(width 0.1905)
		(layer "In7.Cu")
		(net "M_B_BS2")
	)
	(segment
		(start 100.3681 -27.4701)
		(end 101.8794 -25.9588)
		(width 0.1016)
		(layer "In7.Cu")
		(net "M_B_BS2")
	)
	(segment
		(start 103.9114 -21.6408)
		(end 104.2416 -21.3106)
		(width 0.1016)
		(layer "In7.Cu")
		(net "M_B_BS2")
	)
	(segment
		(start 157.41142 -6.496558)
		(end 156.6418 -7.266178)
		(width 0.1905)
		(layer "In7.Cu")
		(net "M_B_BS2")
	)
	(segment
		(start 100.647754 -29.971746)
		(end 100.482654 -29.806646)
		(width 0.1016)
		(layer "In7.Cu")
		(net "M_B_BS2")
	)
	(segment
		(start 140.260578 -14.2748)
		(end 139.498578 -14.2748)
		(width 0.1905)
		(layer "In7.Cu")
		(net "M_B_BS2")
	)
	(segment
		(start 110.56493 -21.3106)
		(end 104.2416 -21.3106)
		(width 0.1905)
		(layer "In7.Cu")
		(net "M_B_BS2")
	)
	(segment
		(start 142.940278 -15.3162)
		(end 142.737078 -15.113)
		(width 0.1905)
		(layer "In7.Cu")
		(net "M_B_BS2")
	)
	(segment
		(start 136.283446 -16.573246)
		(end 136.27735 -16.56715)
		(width 0.1905)
		(layer "In7.Cu")
		(net "M_B_BS2")
	)
	(segment
		(start 100.482654 -29.806646)
		(end 100.482654 -28.83281)
		(width 0.1016)
		(layer "In7.Cu")
		(net "M_B_BS2")
	)
	(segment
		(start 155.6258 -8.242808)
		(end 155.630626 -8.247634)
		(width 0.1905)
		(layer "In7.Cu")
		(net "M_B_BS2")
	)
	(segment
		(start 139.104878 -15.2908)
		(end 137.6426 -15.2908)
		(width 0.1905)
		(layer "In7.Cu")
		(net "M_B_BS2")
	)
	(segment
		(start 155.630626 -8.247634)
		(end 155.630626 -9.570974)
		(width 0.1905)
		(layer "In7.Cu")
		(net "M_B_BS2")
	)
	(segment
		(start 148.628354 -16.573246)
		(end 144.9451 -16.573246)
		(width 0.1905)
		(layer "In7.Cu")
		(net "M_B_BS2")
	)
	(segment
		(start 144.5514 -15.3162)
		(end 142.940278 -15.3162)
		(width 0.1905)
		(layer "In7.Cu")
		(net "M_B_BS2")
	)
	(segment
		(start 141.403578 -15.2908)
		(end 140.641578 -15.2908)
		(width 0.1905)
		(layer "In7.Cu")
		(net "M_B_BS2")
	)
	(segment
		(start 156.6418 -7.266178)
		(end 156.0576 -7.266178)
		(width 0.1905)
		(layer "In7.Cu")
		(net "M_B_BS2")
	)
	(segment
		(start 140.641578 -15.2908)
		(end 140.451078 -15.1003)
		(width 0.1905)
		(layer "In7.Cu")
		(net "M_B_BS2")
	)
	(via
		(at 18.194782 -59.69)
		(size 0.7112)
		(drill 0.3556)
		(layers "F.Cu" "B.Cu")
		(net "VR_PVNN_COMP_RC")
	)
	(segment
		(start 18.118582 -59.6138)
		(end 18.194782 -59.69)
		(width 0.2032)
		(layer "B.Cu")
		(net "VR_PVNN_COMP_RC")
	)
	(segment
		(start 18.161 -60.6298)
		(end 18.2118 -60.579)
		(width 0.2032)
		(layer "B.Cu")
		(net "VR_PVNN_COMP_RC")
	)
	(segment
		(start 17.272 -59.6138)
		(end 18.118582 -59.6138)
		(width 0.2032)
		(layer "B.Cu")
		(net "VR_PVNN_COMP_RC")
	)
	(segment
		(start 18.2118 -60.579)
		(end 18.2118 -59.707018)
		(width 0.2032)
		(layer "B.Cu")
		(net "VR_PVNN_COMP_RC")
	)
	(segment
		(start 18.2118 -59.707018)
		(end 18.194782 -59.69)
		(width 0.2032)
		(layer "B.Cu")
		(net "VR_PVNN_COMP_RC")
	)
	(segment
		(start 161.349944 -2.658872)
		(end 161.41065 -2.719578)
		(width 0.2413)
		(layer "F.Cu")
		(net "M_B_MA3")
	)
	(segment
		(start 161.41065 -2.719578)
		(end 161.41065 -3.35915)
		(width 0.2413)
		(layer "F.Cu")
		(net "M_B_MA3")
	)
	(segment
		(start 160.752028 -6.003036)
		(end 161.17697 -6.427978)
		(width 0.2413)
		(layer "F.Cu")
		(net "M_B_MA3")
	)
	(segment
		(start 101.981 -31.9024)
		(end 101.981 -31.985966)
		(width 0.1016)
		(layer "F.Cu")
		(net "M_B_MA3")
	)
	(segment
		(start 161.41065 -3.35915)
		(end 160.752028 -4.017772)
		(width 0.2413)
		(layer "F.Cu")
		(net "M_B_MA3")
	)
	(segment
		(start 161.349944 -1.68402)
		(end 161.349944 -2.658872)
		(width 0.2413)
		(layer "F.Cu")
		(net "M_B_MA3")
	)
	(segment
		(start 160.752028 -4.017772)
		(end 160.752028 -6.003036)
		(width 0.2413)
		(layer "F.Cu")
		(net "M_B_MA3")
	)
	(segment
		(start 101.981 -31.985966)
		(end 102.278688 -32.283654)
		(width 0.1016)
		(layer "F.Cu")
		(net "M_B_MA3")
	)
	(via
		(at 161.17697 -6.427978)
		(size 0.4318)
		(drill 0.2032)
		(layers "F.Cu" "B.Cu")
		(net "M_B_MA3")
	)
	(via
		(at 101.981 -31.9024)
		(size 0.4318)
		(drill 0.2032)
		(layers "F.Cu" "B.Cu")
		(net "M_B_MA3")
	)
	(segment
		(start 161.349944 -8.686038)
		(end 161.397696 -8.638286)
		(width 0.2413)
		(layer "B.Cu")
		(net "M_B_MA3")
	)
	(segment
		(start 161.397696 -7.602474)
		(end 161.17697 -7.381748)
		(width 0.2413)
		(layer "B.Cu")
		(net "M_B_MA3")
	)
	(segment
		(start 161.349944 -9.89076)
		(end 161.349944 -8.686038)
		(width 0.2413)
		(layer "B.Cu")
		(net "M_B_MA3")
	)
	(segment
		(start 161.397696 -8.638286)
		(end 161.397696 -7.602474)
		(width 0.2413)
		(layer "B.Cu")
		(net "M_B_MA3")
	)
	(segment
		(start 161.17697 -7.381748)
		(end 161.17697 -6.427978)
		(width 0.2413)
		(layer "B.Cu")
		(net "M_B_MA3")
	)
	(segment
		(start 125.813058 -22.082252)
		(end 125.16231 -22.733)
		(width 0.1905)
		(layer "In7.Cu")
		(net "M_B_MA3")
	)
	(segment
		(start 150.6982 -22.479)
		(end 150.301452 -22.082252)
		(width 0.1905)
		(layer "In7.Cu")
		(net "M_B_MA3")
	)
	(segment
		(start 130.37439 -22.4917)
		(end 130.18389 -22.6822)
		(width 0.1905)
		(layer "In7.Cu")
		(net "M_B_MA3")
	)
	(segment
		(start 139.803378 -22.528022)
		(end 139.274296 -22.528022)
		(width 0.1905)
		(layer "In7.Cu")
		(net "M_B_MA3")
	)
	(segment
		(start 151.390604 -22.262846)
		(end 151.17445 -22.479)
		(width 0.1905)
		(layer "In7.Cu")
		(net "M_B_MA3")
	)
	(segment
		(start 138.828526 -22.082252)
		(end 136.820148 -22.082252)
		(width 0.1905)
		(layer "In7.Cu")
		(net "M_B_MA3")
	)
	(segment
		(start 101.981 -31.877)
		(end 102.489 -31.369)
		(width 0.1016)
		(layer "In7.Cu")
		(net "M_B_MA3")
	)
	(segment
		(start 148.8694 -22.082252)
		(end 148.6662 -22.285452)
		(width 0.1905)
		(layer "In7.Cu")
		(net "M_B_MA3")
	)
	(segment
		(start 130.18389 -22.6822)
		(end 129.80289 -22.6822)
		(width 0.1905)
		(layer "In7.Cu")
		(net "M_B_MA3")
	)
	(segment
		(start 161.417 -9.711436)
		(end 159.4104 -11.718036)
		(width 0.1905)
		(layer "In7.Cu")
		(net "M_B_MA3")
	)
	(segment
		(start 152.629362 -21.72335)
		(end 152.064974 -21.72335)
		(width 0.1905)
		(layer "In7.Cu")
		(net "M_B_MA3")
	)
	(segment
		(start 110.45063 -25.926288)
		(end 110.517432 -25.859486)
		(width 0.1016)
		(layer "In7.Cu")
		(net "M_B_MA3")
	)
	(segment
		(start 102.489 -31.369)
		(end 102.489 -30.8864)
		(width 0.1016)
		(layer "In7.Cu")
		(net "M_B_MA3")
	)
	(segment
		(start 103.3272 -30.0482)
		(end 103.3272 -28.914598)
		(width 0.1016)
		(layer "In7.Cu")
		(net "M_B_MA3")
	)
	(segment
		(start 130.56489 -22.082252)
		(end 130.37439 -22.272752)
		(width 0.1905)
		(layer "In7.Cu")
		(net "M_B_MA3")
	)
	(segment
		(start 150.301452 -22.082252)
		(end 148.8694 -22.082252)
		(width 0.1905)
		(layer "In7.Cu")
		(net "M_B_MA3")
	)
	(segment
		(start 148.6662 -22.5044)
		(end 148.463 -22.7076)
		(width 0.1905)
		(layer "In7.Cu")
		(net "M_B_MA3")
	)
	(segment
		(start 136.820148 -22.082252)
		(end 136.4488 -22.4536)
		(width 0.1905)
		(layer "In7.Cu")
		(net "M_B_MA3")
	)
	(segment
		(start 110.951518 -25.4254)
		(end 110.517432 -25.859486)
		(width 0.1905)
		(layer "In7.Cu")
		(net "M_B_MA3")
	)
	(segment
		(start 147.6248 -22.285452)
		(end 147.4216 -22.082252)
		(width 0.1905)
		(layer "In7.Cu")
		(net "M_B_MA3")
	)
	(segment
		(start 129.61239 -22.272752)
		(end 129.42189 -22.082252)
		(width 0.1905)
		(layer "In7.Cu")
		(net "M_B_MA3")
	)
	(segment
		(start 148.463 -22.7076)
		(end 147.828 -22.7076)
		(width 0.1905)
		(layer "In7.Cu")
		(net "M_B_MA3")
	)
	(segment
		(start 136.4488 -22.4536)
		(end 135.9154 -22.4536)
		(width 0.1905)
		(layer "In7.Cu")
		(net "M_B_MA3")
	)
	(segment
		(start 113.600484 -25.4254)
		(end 110.951518 -25.4254)
		(width 0.1905)
		(layer "In7.Cu")
		(net "M_B_MA3")
	)
	(segment
		(start 107.763056 -25.926288)
		(end 110.45063 -25.926288)
		(width 0.1016)
		(layer "In7.Cu")
		(net "M_B_MA3")
	)
	(segment
		(start 151.17445 -22.479)
		(end 150.6982 -22.479)
		(width 0.1905)
		(layer "In7.Cu")
		(net "M_B_MA3")
	)
	(segment
		(start 159.4104 -14.942566)
		(end 152.629362 -21.72335)
		(width 0.1905)
		(layer "In7.Cu")
		(net "M_B_MA3")
	)
	(segment
		(start 116.292884 -22.733)
		(end 113.600484 -25.4254)
		(width 0.1905)
		(layer "In7.Cu")
		(net "M_B_MA3")
	)
	(segment
		(start 139.274296 -22.528022)
		(end 138.828526 -22.082252)
		(width 0.1905)
		(layer "In7.Cu")
		(net "M_B_MA3")
	)
	(segment
		(start 129.80289 -22.6822)
		(end 129.61239 -22.4917)
		(width 0.1905)
		(layer "In7.Cu")
		(net "M_B_MA3")
	)
	(segment
		(start 105.377742 -28.311602)
		(end 107.763056 -25.926288)
		(width 0.1016)
		(layer "In7.Cu")
		(net "M_B_MA3")
	)
	(segment
		(start 129.42189 -22.082252)
		(end 125.813058 -22.082252)
		(width 0.1905)
		(layer "In7.Cu")
		(net "M_B_MA3")
	)
	(segment
		(start 130.37439 -22.272752)
		(end 130.37439 -22.4917)
		(width 0.1905)
		(layer "In7.Cu")
		(net "M_B_MA3")
	)
	(segment
		(start 159.4104 -11.718036)
		(end 159.4104 -14.942566)
		(width 0.1905)
		(layer "In7.Cu")
		(net "M_B_MA3")
	)
	(segment
		(start 134.432802 -22.344126)
		(end 134.170928 -22.082252)
		(width 0.1905)
		(layer "In7.Cu")
		(net "M_B_MA3")
	)
	(segment
		(start 134.881874 -22.344126)
		(end 134.432802 -22.344126)
		(width 0.1905)
		(layer "In7.Cu")
		(net "M_B_MA3")
	)
	(segment
		(start 103.930196 -28.311602)
		(end 105.377742 -28.311602)
		(width 0.1016)
		(layer "In7.Cu")
		(net "M_B_MA3")
	)
	(segment
		(start 103.3272 -28.914598)
		(end 103.930196 -28.311602)
		(width 0.1016)
		(layer "In7.Cu")
		(net "M_B_MA3")
	)
	(segment
		(start 161.17697 -7.229348)
		(end 161.417 -7.469378)
		(width 0.1905)
		(layer "In7.Cu")
		(net "M_B_MA3")
	)
	(segment
		(start 152.064974 -21.72335)
		(end 151.525478 -22.262846)
		(width 0.1905)
		(layer "In7.Cu")
		(net "M_B_MA3")
	)
	(segment
		(start 101.981 -31.9024)
		(end 101.981 -31.877)
		(width 0.1016)
		(layer "In7.Cu")
		(net "M_B_MA3")
	)
	(segment
		(start 134.170928 -22.082252)
		(end 130.56489 -22.082252)
		(width 0.1905)
		(layer "In7.Cu")
		(net "M_B_MA3")
	)
	(segment
		(start 147.828 -22.7076)
		(end 147.6248 -22.5044)
		(width 0.1905)
		(layer "In7.Cu")
		(net "M_B_MA3")
	)
	(segment
		(start 135.544052 -22.082252)
		(end 135.143748 -22.082252)
		(width 0.1905)
		(layer "In7.Cu")
		(net "M_B_MA3")
	)
	(segment
		(start 161.17697 -6.427978)
		(end 161.17697 -7.229348)
		(width 0.1905)
		(layer "In7.Cu")
		(net "M_B_MA3")
	)
	(segment
		(start 129.61239 -22.4917)
		(end 129.61239 -22.272752)
		(width 0.1905)
		(layer "In7.Cu")
		(net "M_B_MA3")
	)
	(segment
		(start 147.6248 -22.5044)
		(end 147.6248 -22.285452)
		(width 0.1905)
		(layer "In7.Cu")
		(net "M_B_MA3")
	)
	(segment
		(start 161.417 -7.469378)
		(end 161.417 -9.711436)
		(width 0.1905)
		(layer "In7.Cu")
		(net "M_B_MA3")
	)
	(segment
		(start 135.9154 -22.4536)
		(end 135.544052 -22.082252)
		(width 0.1905)
		(layer "In7.Cu")
		(net "M_B_MA3")
	)
	(segment
		(start 148.6662 -22.285452)
		(end 148.6662 -22.5044)
		(width 0.1905)
		(layer "In7.Cu")
		(net "M_B_MA3")
	)
	(segment
		(start 147.4216 -22.082252)
		(end 140.249148 -22.082252)
		(width 0.1905)
		(layer "In7.Cu")
		(net "M_B_MA3")
	)
	(segment
		(start 135.143748 -22.082252)
		(end 134.881874 -22.344126)
		(width 0.1905)
		(layer "In7.Cu")
		(net "M_B_MA3")
	)
	(segment
		(start 102.489 -30.8864)
		(end 103.3272 -30.0482)
		(width 0.1016)
		(layer "In7.Cu")
		(net "M_B_MA3")
	)
	(segment
		(start 140.249148 -22.082252)
		(end 139.803378 -22.528022)
		(width 0.1905)
		(layer "In7.Cu")
		(net "M_B_MA3")
	)
	(segment
		(start 151.525478 -22.262846)
		(end 151.390604 -22.262846)
		(width 0.1905)
		(layer "In7.Cu")
		(net "M_B_MA3")
	)
	(segment
		(start 125.16231 -22.733)
		(end 116.292884 -22.733)
		(width 0.1905)
		(layer "In7.Cu")
		(net "M_B_MA3")
	)
	(segment
		(start 83.9343 -25.3619)
		(end 85.7123 -25.3619)
		(width 0.1397)
		(layer "F.Cu")
		(net "CLK_100M_CPU_GBE_DN")
	)
	(segment
		(start 85.852 -25.5016)
		(end 86.964012 -25.5016)
		(width 0.1397)
		(layer "F.Cu")
		(net "CLK_100M_CPU_GBE_DN")
	)
	(segment
		(start 83.8454 -25.4508)
		(end 83.9343 -25.3619)
		(width 0.1397)
		(layer "F.Cu")
		(net "CLK_100M_CPU_GBE_DN")
	)
	(segment
		(start 87.363808 -26.535634)
		(end 87.627968 -26.799794)
		(width 0.1397)
		(layer "F.Cu")
		(net "CLK_100M_CPU_GBE_DN")
	)
	(segment
		(start 87.363808 -25.901396)
		(end 87.363808 -26.535634)
		(width 0.1397)
		(layer "F.Cu")
		(net "CLK_100M_CPU_GBE_DN")
	)
	(segment
		(start 87.627968 -26.799794)
		(end 87.627968 -27.447494)
		(width 0.1397)
		(layer "F.Cu")
		(net "CLK_100M_CPU_GBE_DN")
	)
	(segment
		(start 86.964012 -25.5016)
		(end 87.363808 -25.901396)
		(width 0.1397)
		(layer "F.Cu")
		(net "CLK_100M_CPU_GBE_DN")
	)
	(segment
		(start 85.7123 -25.3619)
		(end 85.852 -25.5016)
		(width 0.1397)
		(layer "F.Cu")
		(net "CLK_100M_CPU_GBE_DN")
	)
	(via
		(at 43.41114 -44.15536)
		(size 0.508)
		(drill 0.254)
		(layers "F.Cu" "B.Cu")
		(net "CLK_100M_CPU_GBE_DN")
	)
	(via
		(at 83.8454 -25.4508)
		(size 0.4318)
		(drill 0.2032)
		(layers "F.Cu" "B.Cu")
		(net "CLK_100M_CPU_GBE_DN")
	)
	(segment
		(start 43.1038 -44.6532)
		(end 43.1038 -44.4627)
		(width 0.1397)
		(layer "B.Cu")
		(net "CLK_100M_CPU_GBE_DN")
	)
	(segment
		(start 44.323 -44.8564)
		(end 43.307 -44.8564)
		(width 0.1397)
		(layer "B.Cu")
		(net "CLK_100M_CPU_GBE_DN")
	)
	(segment
		(start 44.830238 -45.72)
		(end 44.830238 -45.363638)
		(width 0.1397)
		(layer "B.Cu")
		(net "CLK_100M_CPU_GBE_DN")
	)
	(segment
		(start 43.1038 -44.4627)
		(end 43.41114 -44.15536)
		(width 0.1397)
		(layer "B.Cu")
		(net "CLK_100M_CPU_GBE_DN")
	)
	(segment
		(start 44.830238 -45.363638)
		(end 44.323 -44.8564)
		(width 0.1397)
		(layer "B.Cu")
		(net "CLK_100M_CPU_GBE_DN")
	)
	(segment
		(start 44.858686 -45.748448)
		(end 44.830238 -45.72)
		(width 0.1397)
		(layer "B.Cu")
		(net "CLK_100M_CPU_GBE_DN")
	)
	(segment
		(start 43.307 -44.8564)
		(end 43.1038 -44.6532)
		(width 0.1397)
		(layer "B.Cu")
		(net "CLK_100M_CPU_GBE_DN")
	)
	(segment
		(start 44.858686 -46.087792)
		(end 44.858686 -45.748448)
		(width 0.1397)
		(layer "B.Cu")
		(net "CLK_100M_CPU_GBE_DN")
	)
	(segment
		(start 43.1038 -43.84802)
		(end 43.41114 -44.15536)
		(width 0.1143)
		(layer "In4.Cu")
		(net "CLK_100M_CPU_GBE_DN")
	)
	(segment
		(start 47.991014 -37.595556)
		(end 47.991014 -38.236906)
		(width 0.1143)
		(layer "In4.Cu")
		(net "CLK_100M_CPU_GBE_DN")
	)
	(segment
		(start 83.8454 -25.4508)
		(end 83.7692 -25.3746)
		(width 0.1143)
		(layer "In4.Cu")
		(net "CLK_100M_CPU_GBE_DN")
	)
	(segment
		(start 48.95977 -36.6268)
		(end 47.991014 -37.595556)
		(width 0.1143)
		(layer "In4.Cu")
		(net "CLK_100M_CPU_GBE_DN")
	)
	(segment
		(start 69.34835 -25.63495)
		(end 67.759834 -25.63495)
		(width 0.1143)
		(layer "In4.Cu")
		(net "CLK_100M_CPU_GBE_DN")
	)
	(segment
		(start 75.479656 -26.32075)
		(end 74.774806 -27.0256)
		(width 0.1143)
		(layer "In4.Cu")
		(net "CLK_100M_CPU_GBE_DN")
	)
	(segment
		(start 67.759834 -25.63495)
		(end 65.946528 -27.448256)
		(width 0.1143)
		(layer "In4.Cu")
		(net "CLK_100M_CPU_GBE_DN")
	)
	(segment
		(start 83.439 -25.3746)
		(end 83.29295 -25.52065)
		(width 0.1143)
		(layer "In4.Cu")
		(net "CLK_100M_CPU_GBE_DN")
	)
	(segment
		(start 43.1038 -43.12412)
		(end 43.1038 -43.84802)
		(width 0.1143)
		(layer "In4.Cu")
		(net "CLK_100M_CPU_GBE_DN")
	)
	(segment
		(start 82.807302 -26.32075)
		(end 75.479656 -26.32075)
		(width 0.1143)
		(layer "In4.Cu")
		(net "CLK_100M_CPU_GBE_DN")
	)
	(segment
		(start 83.7692 -25.3746)
		(end 83.439 -25.3746)
		(width 0.1143)
		(layer "In4.Cu")
		(net "CLK_100M_CPU_GBE_DN")
	)
	(segment
		(start 70.739 -27.0256)
		(end 69.34835 -25.63495)
		(width 0.1143)
		(layer "In4.Cu")
		(net "CLK_100M_CPU_GBE_DN")
	)
	(segment
		(start 63.84925 -27.448256)
		(end 60.233306 -31.0642)
		(width 0.1143)
		(layer "In4.Cu")
		(net "CLK_100M_CPU_GBE_DN")
	)
	(segment
		(start 60.233306 -31.0642)
		(end 56.624982 -31.0642)
		(width 0.1143)
		(layer "In4.Cu")
		(net "CLK_100M_CPU_GBE_DN")
	)
	(segment
		(start 65.946528 -27.448256)
		(end 63.84925 -27.448256)
		(width 0.1143)
		(layer "In4.Cu")
		(net "CLK_100M_CPU_GBE_DN")
	)
	(segment
		(start 54.3052 -35.696906)
		(end 53.375306 -36.6268)
		(width 0.1143)
		(layer "In4.Cu")
		(net "CLK_100M_CPU_GBE_DN")
	)
	(segment
		(start 54.3052 -33.383982)
		(end 54.3052 -35.696906)
		(width 0.1143)
		(layer "In4.Cu")
		(net "CLK_100M_CPU_GBE_DN")
	)
	(segment
		(start 56.624982 -31.0642)
		(end 54.3052 -33.383982)
		(width 0.1143)
		(layer "In4.Cu")
		(net "CLK_100M_CPU_GBE_DN")
	)
	(segment
		(start 47.991014 -38.236906)
		(end 43.1038 -43.12412)
		(width 0.1143)
		(layer "In4.Cu")
		(net "CLK_100M_CPU_GBE_DN")
	)
	(segment
		(start 83.29295 -25.52065)
		(end 83.29295 -25.835102)
		(width 0.1143)
		(layer "In4.Cu")
		(net "CLK_100M_CPU_GBE_DN")
	)
	(segment
		(start 53.375306 -36.6268)
		(end 48.95977 -36.6268)
		(width 0.1143)
		(layer "In4.Cu")
		(net "CLK_100M_CPU_GBE_DN")
	)
	(segment
		(start 74.774806 -27.0256)
		(end 70.739 -27.0256)
		(width 0.1143)
		(layer "In4.Cu")
		(net "CLK_100M_CPU_GBE_DN")
	)
	(segment
		(start 83.29295 -25.835102)
		(end 82.807302 -26.32075)
		(width 0.1143)
		(layer "In4.Cu")
		(net "CLK_100M_CPU_GBE_DN")
	)
	(via
		(at 18.951194 -56.2737)
		(size 0.7112)
		(drill 0.3556)
		(layers "F.Cu" "B.Cu")
		(net "VR_PVNN_FB_RC1")
	)
	(segment
		(start 18.951194 -56.2737)
		(end 18.951194 -57.172606)
		(width 0.2032)
		(layer "B.Cu")
		(net "VR_PVNN_FB_RC1")
	)
	(segment
		(start 18.3134 -56.1848)
		(end 18.1102 -56.388)
		(width 0.2032)
		(layer "B.Cu")
		(net "VR_PVNN_FB_RC1")
	)
	(segment
		(start 18.951194 -56.2737)
		(end 18.862294 -56.1848)
		(width 0.2032)
		(layer "B.Cu")
		(net "VR_PVNN_FB_RC1")
	)
	(segment
		(start 18.862294 -56.1848)
		(end 18.3134 -56.1848)
		(width 0.2032)
		(layer "B.Cu")
		(net "VR_PVNN_FB_RC1")
	)
	(segment
		(start 18.951194 -57.172606)
		(end 18.796 -57.3278)
		(width 0.2032)
		(layer "B.Cu")
		(net "VR_PVNN_FB_RC1")
	)
	(segment
		(start 186.85002 -9.897364)
		(end 186.85002 -8.990584)
		(width 0.1778)
		(layer "F.Cu")
		(net "M_B_DQS_DP7")
	)
	(segment
		(start 187.038996 -8.801608)
		(end 187.038996 -8.263382)
		(width 0.1778)
		(layer "F.Cu")
		(net "M_B_DQS_DP7")
	)
	(segment
		(start 186.625992 -6.79577)
		(end 186.625992 -6.212586)
		(width 0.1778)
		(layer "F.Cu")
		(net "M_B_DQS_DP7")
	)
	(segment
		(start 187.038996 -8.263382)
		(end 187.198 -8.104378)
		(width 0.1778)
		(layer "F.Cu")
		(net "M_B_DQS_DP7")
	)
	(segment
		(start 186.8424 -5.996178)
		(end 186.967114 -5.996178)
		(width 0.1778)
		(layer "F.Cu")
		(net "M_B_DQS_DP7")
	)
	(segment
		(start 186.625992 -6.212586)
		(end 186.8424 -5.996178)
		(width 0.1778)
		(layer "F.Cu")
		(net "M_B_DQS_DP7")
	)
	(segment
		(start 106.864912 -38.020498)
		(end 106.898694 -38.020498)
		(width 0.1016)
		(layer "F.Cu")
		(net "M_B_DQS_DP7")
	)
	(segment
		(start 106.528108 -37.683694)
		(end 106.864912 -38.020498)
		(width 0.1016)
		(layer "F.Cu")
		(net "M_B_DQS_DP7")
	)
	(segment
		(start 187.198 -7.367778)
		(end 186.625992 -6.79577)
		(width 0.1778)
		(layer "F.Cu")
		(net "M_B_DQS_DP7")
	)
	(segment
		(start 186.85002 -8.990584)
		(end 187.038996 -8.801608)
		(width 0.1778)
		(layer "F.Cu")
		(net "M_B_DQS_DP7")
	)
	(segment
		(start 187.198 -8.104378)
		(end 187.198 -7.367778)
		(width 0.1778)
		(layer "F.Cu")
		(net "M_B_DQS_DP7")
	)
	(via
		(at 106.898694 -38.020498)
		(size 0.4318)
		(drill 0.2032)
		(layers "F.Cu" "B.Cu")
		(net "M_B_DQS_DP7")
	)
	(via
		(at 186.967114 -5.996178)
		(size 0.4318)
		(drill 0.2032)
		(layers "F.Cu" "B.Cu")
		(net "M_B_DQS_DP7")
	)
	(segment
		(start 186.85002 -1.690624)
		(end 186.85002 -2.432558)
		(width 0.1778)
		(layer "B.Cu")
		(net "M_B_DQS_DP7")
	)
	(segment
		(start 186.702192 -2.580386)
		(end 186.702192 -5.731256)
		(width 0.1778)
		(layer "B.Cu")
		(net "M_B_DQS_DP7")
	)
	(segment
		(start 186.702192 -5.731256)
		(end 186.967114 -5.996178)
		(width 0.1778)
		(layer "B.Cu")
		(net "M_B_DQS_DP7")
	)
	(segment
		(start 186.85002 -2.432558)
		(end 186.702192 -2.580386)
		(width 0.1778)
		(layer "B.Cu")
		(net "M_B_DQS_DP7")
	)
	(segment
		(start 107.672886 -37.746686)
		(end 108.0135 -38.0873)
		(width 0.1016)
		(layer "In2.Cu")
		(net "M_B_DQS_DP7")
	)
	(segment
		(start 186.967114 -5.996178)
		(end 186.69 -6.273292)
		(width 0.1524)
		(layer "In2.Cu")
		(net "M_B_DQS_DP7")
	)
	(segment
		(start 143.799814 -36.738814)
		(end 143.3322 -36.2712)
		(width 0.1524)
		(layer "In2.Cu")
		(net "M_B_DQS_DP7")
	)
	(segment
		(start 146.306286 -36.738814)
		(end 143.799814 -36.738814)
		(width 0.1524)
		(layer "In2.Cu")
		(net "M_B_DQS_DP7")
	)
	(segment
		(start 186.69 -6.273292)
		(end 186.69 -7.483602)
		(width 0.1524)
		(layer "In2.Cu")
		(net "M_B_DQS_DP7")
	)
	(segment
		(start 148.808186 -36.738814)
		(end 147.547838 -36.738814)
		(width 0.1524)
		(layer "In2.Cu")
		(net "M_B_DQS_DP7")
	)
	(segment
		(start 184.584086 -9.589516)
		(end 184.323736 -9.589516)
		(width 0.1524)
		(layer "In2.Cu")
		(net "M_B_DQS_DP7")
	)
	(segment
		(start 146.622262 -35.6616)
		(end 146.622262 -36.422838)
		(width 0.1524)
		(layer "In2.Cu")
		(net "M_B_DQS_DP7")
	)
	(segment
		(start 135.3312 -36.2712)
		(end 132.6134 -36.2712)
		(width 0.1524)
		(layer "In2.Cu")
		(net "M_B_DQS_DP7")
	)
	(segment
		(start 107.172506 -37.746686)
		(end 107.672886 -37.746686)
		(width 0.1016)
		(layer "In2.Cu")
		(net "M_B_DQS_DP7")
	)
	(segment
		(start 112.787176 -36.399978)
		(end 113.054638 -36.66744)
		(width 0.1016)
		(layer "In2.Cu")
		(net "M_B_DQS_DP7")
	)
	(segment
		(start 132.145786 -36.738814)
		(end 117.6147 -36.738814)
		(width 0.1524)
		(layer "In2.Cu")
		(net "M_B_DQS_DP7")
	)
	(segment
		(start 117.512084 -36.66744)
		(end 117.583458 -36.738814)
		(width 0.1016)
		(layer "In2.Cu")
		(net "M_B_DQS_DP7")
	)
	(segment
		(start 186.69 -7.483602)
		(end 184.584086 -9.589516)
		(width 0.1524)
		(layer "In2.Cu")
		(net "M_B_DQS_DP7")
	)
	(segment
		(start 140.807186 -36.738814)
		(end 135.798814 -36.738814)
		(width 0.1524)
		(layer "In2.Cu")
		(net "M_B_DQS_DP7")
	)
	(segment
		(start 147.079462 -35.5092)
		(end 146.774662 -35.5092)
		(width 0.1524)
		(layer "In2.Cu")
		(net "M_B_DQS_DP7")
	)
	(segment
		(start 147.547838 -36.738814)
		(end 147.231862 -36.422838)
		(width 0.1524)
		(layer "In2.Cu")
		(net "M_B_DQS_DP7")
	)
	(segment
		(start 112.190022 -36.399978)
		(end 112.787176 -36.399978)
		(width 0.1016)
		(layer "In2.Cu")
		(net "M_B_DQS_DP7")
	)
	(segment
		(start 147.231862 -36.422838)
		(end 147.231862 -35.6616)
		(width 0.1524)
		(layer "In2.Cu")
		(net "M_B_DQS_DP7")
	)
	(segment
		(start 146.774662 -35.5092)
		(end 146.622262 -35.6616)
		(width 0.1524)
		(layer "In2.Cu")
		(net "M_B_DQS_DP7")
	)
	(segment
		(start 117.583458 -36.738814)
		(end 117.6147 -36.738814)
		(width 0.1016)
		(layer "In2.Cu")
		(net "M_B_DQS_DP7")
	)
	(segment
		(start 147.231862 -35.6616)
		(end 147.079462 -35.5092)
		(width 0.1524)
		(layer "In2.Cu")
		(net "M_B_DQS_DP7")
	)
	(segment
		(start 135.798814 -36.738814)
		(end 135.3312 -36.2712)
		(width 0.1524)
		(layer "In2.Cu")
		(net "M_B_DQS_DP7")
	)
	(segment
		(start 157.642052 -36.2712)
		(end 149.2758 -36.2712)
		(width 0.1524)
		(layer "In2.Cu")
		(net "M_B_DQS_DP7")
	)
	(segment
		(start 143.3322 -36.2712)
		(end 141.2748 -36.2712)
		(width 0.1524)
		(layer "In2.Cu")
		(net "M_B_DQS_DP7")
	)
	(segment
		(start 109.63021 -38.0873)
		(end 111.049308 -36.668202)
		(width 0.1016)
		(layer "In2.Cu")
		(net "M_B_DQS_DP7")
	)
	(segment
		(start 141.2748 -36.2712)
		(end 140.807186 -36.738814)
		(width 0.1524)
		(layer "In2.Cu")
		(net "M_B_DQS_DP7")
	)
	(segment
		(start 149.2758 -36.2712)
		(end 148.808186 -36.738814)
		(width 0.1524)
		(layer "In2.Cu")
		(net "M_B_DQS_DP7")
	)
	(segment
		(start 113.054638 -36.66744)
		(end 117.512084 -36.66744)
		(width 0.1016)
		(layer "In2.Cu")
		(net "M_B_DQS_DP7")
	)
	(segment
		(start 132.6134 -36.2712)
		(end 132.145786 -36.738814)
		(width 0.1524)
		(layer "In2.Cu")
		(net "M_B_DQS_DP7")
	)
	(segment
		(start 111.049308 -36.668202)
		(end 111.921798 -36.668202)
		(width 0.1016)
		(layer "In2.Cu")
		(net "M_B_DQS_DP7")
	)
	(segment
		(start 184.323736 -9.589516)
		(end 157.642052 -36.2712)
		(width 0.1524)
		(layer "In2.Cu")
		(net "M_B_DQS_DP7")
	)
	(segment
		(start 108.0135 -38.0873)
		(end 109.63021 -38.0873)
		(width 0.1016)
		(layer "In2.Cu")
		(net "M_B_DQS_DP7")
	)
	(segment
		(start 146.622262 -36.422838)
		(end 146.306286 -36.738814)
		(width 0.1524)
		(layer "In2.Cu")
		(net "M_B_DQS_DP7")
	)
	(segment
		(start 111.921798 -36.668202)
		(end 112.190022 -36.399978)
		(width 0.1016)
		(layer "In2.Cu")
		(net "M_B_DQS_DP7")
	)
	(segment
		(start 106.898694 -38.020498)
		(end 107.172506 -37.746686)
		(width 0.1016)
		(layer "In2.Cu")
		(net "M_B_DQS_DP7")
	)
	(segment
		(start 16.2814 -56.0832)
		(end 16.837406 -56.0832)
		(width 0.2032)
		(layer "F.Cu")
		(net "PWRGD_R_PVCCP")
	)
	(segment
		(start 16.837406 -56.0832)
		(end 17.272 -56.517794)
		(width 0.2032)
		(layer "F.Cu")
		(net "PWRGD_R_PVCCP")
	)
	(segment
		(start 17.272 -56.517794)
		(end 17.272 -57.093612)
		(width 0.2032)
		(layer "F.Cu")
		(net "PWRGD_R_PVCCP")
	)
	(segment
		(start 17.99844 -57.820052)
		(end 18.590006 -57.820052)
		(width 0.2032)
		(layer "F.Cu")
		(net "PWRGD_R_PVCCP")
	)
	(segment
		(start 17.272 -57.093612)
		(end 17.99844 -57.820052)
		(width 0.2032)
		(layer "F.Cu")
		(net "PWRGD_R_PVCCP")
	)
	(segment
		(start 109.339888 -31.168594)
		(end 110.268766 -31.168594)
		(width 0.1778)
		(layer "F.Cu")
		(net "M_B_CS_N2")
	)
	(segment
		(start 110.268766 -31.168594)
		(end 110.602268 -31.502096)
		(width 0.1778)
		(layer "F.Cu")
		(net "M_B_CS_N2")
	)
	(segment
		(start 168.694354 -3.310128)
		(end 169.145204 -3.760978)
		(width 0.1778)
		(layer "F.Cu")
		(net "M_B_CS_N2")
	)
	(segment
		(start 169.145204 -3.760978)
		(end 169.20845 -3.760978)
		(width 0.1778)
		(layer "F.Cu")
		(net "M_B_CS_N2")
	)
	(segment
		(start 109.195108 -31.023814)
		(end 109.339888 -31.168594)
		(width 0.1778)
		(layer "F.Cu")
		(net "M_B_CS_N2")
	)
	(segment
		(start 168.549828 -2.822702)
		(end 168.694354 -2.967228)
		(width 0.1778)
		(layer "F.Cu")
		(net "M_B_CS_N2")
	)
	(segment
		(start 168.694354 -2.967228)
		(end 168.694354 -3.310128)
		(width 0.1778)
		(layer "F.Cu")
		(net "M_B_CS_N2")
	)
	(segment
		(start 168.549828 -1.68402)
		(end 168.549828 -2.822702)
		(width 0.1778)
		(layer "F.Cu")
		(net "M_B_CS_N2")
	)
	(via
		(at 169.20845 -3.760978)
		(size 0.4318)
		(drill 0.2032)
		(layers "F.Cu" "B.Cu")
		(net "M_B_CS_N2")
	)
	(via
		(at 110.602268 -31.502096)
		(size 0.4318)
		(drill 0.2032)
		(layers "F.Cu" "B.Cu")
		(net "M_B_CS_N2")
	)
	(segment
		(start 112.935766 -32.03702)
		(end 111.5314 -32.03702)
		(width 0.1524)
		(layer "In9.Cu")
		(net "M_B_CS_N2")
	)
	(segment
		(start 172.339254 -15.05458)
		(end 158.260034 -29.1338)
		(width 0.1524)
		(layer "In9.Cu")
		(net "M_B_CS_N2")
	)
	(segment
		(start 169.5958 -4.776978)
		(end 169.5958 -7.00405)
		(width 0.1524)
		(layer "In9.Cu")
		(net "M_B_CS_N2")
	)
	(segment
		(start 113.304066 -31.66872)
		(end 112.935766 -32.03702)
		(width 0.1524)
		(layer "In9.Cu")
		(net "M_B_CS_N2")
	)
	(segment
		(start 170.445684 -11.177778)
		(end 171.475654 -11.177778)
		(width 0.1524)
		(layer "In9.Cu")
		(net "M_B_CS_N2")
	)
	(segment
		(start 169.20845 -3.760978)
		(end 169.5958 -4.776978)
		(width 0.1524)
		(layer "In9.Cu")
		(net "M_B_CS_N2")
	)
	(segment
		(start 169.755312 -10.487406)
		(end 170.445684 -11.177778)
		(width 0.1524)
		(layer "In9.Cu")
		(net "M_B_CS_N2")
	)
	(segment
		(start 172.339254 -12.041378)
		(end 172.339254 -15.05458)
		(width 0.1524)
		(layer "In9.Cu")
		(net "M_B_CS_N2")
	)
	(segment
		(start 114.7445 -29.8323)
		(end 113.304066 -31.66872)
		(width 0.1524)
		(layer "In9.Cu")
		(net "M_B_CS_N2")
	)
	(segment
		(start 171.475654 -11.177778)
		(end 172.339254 -12.041378)
		(width 0.1524)
		(layer "In9.Cu")
		(net "M_B_CS_N2")
	)
	(segment
		(start 115.443 -29.1338)
		(end 114.7445 -29.8323)
		(width 0.1524)
		(layer "In9.Cu")
		(net "M_B_CS_N2")
	)
	(segment
		(start 169.755312 -7.163562)
		(end 169.755312 -10.487406)
		(width 0.1524)
		(layer "In9.Cu")
		(net "M_B_CS_N2")
	)
	(segment
		(start 158.260034 -29.1338)
		(end 115.443 -29.1338)
		(width 0.1524)
		(layer "In9.Cu")
		(net "M_B_CS_N2")
	)
	(segment
		(start 169.5958 -7.00405)
		(end 169.755312 -7.163562)
		(width 0.1524)
		(layer "In9.Cu")
		(net "M_B_CS_N2")
	)
	(segment
		(start 111.5314 -32.03702)
		(end 110.602268 -31.502096)
		(width 0.1524)
		(layer "In9.Cu")
		(net "M_B_CS_N2")
	)
	(segment
		(start 83.9724 -25.019)
		(end 85.85454 -25.019)
		(width 0.1397)
		(layer "F.Cu")
		(net "CLK_100M_CPU_GBE_DP")
	)
	(segment
		(start 87.706708 -25.759156)
		(end 87.706708 -26.393394)
		(width 0.1397)
		(layer "F.Cu")
		(net "CLK_100M_CPU_GBE_DP")
	)
	(segment
		(start 85.99424 -25.1587)
		(end 87.106252 -25.1587)
		(width 0.1397)
		(layer "F.Cu")
		(net "CLK_100M_CPU_GBE_DP")
	)
	(segment
		(start 87.106252 -25.1587)
		(end 87.706708 -25.759156)
		(width 0.1397)
		(layer "F.Cu")
		(net "CLK_100M_CPU_GBE_DP")
	)
	(segment
		(start 83.8454 -24.892)
		(end 83.9724 -25.019)
		(width 0.1397)
		(layer "F.Cu")
		(net "CLK_100M_CPU_GBE_DP")
	)
	(segment
		(start 85.85454 -25.019)
		(end 85.99424 -25.1587)
		(width 0.1397)
		(layer "F.Cu")
		(net "CLK_100M_CPU_GBE_DP")
	)
	(via
		(at 42.45356 -44.15536)
		(size 0.508)
		(drill 0.254)
		(layers "F.Cu" "B.Cu")
		(net "CLK_100M_CPU_GBE_DP")
	)
	(via
		(at 83.8454 -24.892)
		(size 0.4318)
		(drill 0.2032)
		(layers "F.Cu" "B.Cu")
		(net "CLK_100M_CPU_GBE_DP")
	)
	(segment
		(start 44.487338 -45.505878)
		(end 44.18076 -45.1993)
		(width 0.1397)
		(layer "B.Cu")
		(net "CLK_100M_CPU_GBE_DP")
	)
	(segment
		(start 42.7609 -44.4627)
		(end 42.45356 -44.15536)
		(width 0.1397)
		(layer "B.Cu")
		(net "CLK_100M_CPU_GBE_DP")
	)
	(segment
		(start 44.458636 -46.087792)
		(end 44.458636 -45.711364)
		(width 0.1397)
		(layer "B.Cu")
		(net "CLK_100M_CPU_GBE_DP")
	)
	(segment
		(start 42.7609 -44.79544)
		(end 42.7609 -44.4627)
		(width 0.1397)
		(layer "B.Cu")
		(net "CLK_100M_CPU_GBE_DP")
	)
	(segment
		(start 44.487338 -45.682662)
		(end 44.487338 -45.505878)
		(width 0.1397)
		(layer "B.Cu")
		(net "CLK_100M_CPU_GBE_DP")
	)
	(segment
		(start 44.458636 -45.711364)
		(end 44.487338 -45.682662)
		(width 0.1397)
		(layer "B.Cu")
		(net "CLK_100M_CPU_GBE_DP")
	)
	(segment
		(start 44.18076 -45.1993)
		(end 43.16476 -45.1993)
		(width 0.1397)
		(layer "B.Cu")
		(net "CLK_100M_CPU_GBE_DP")
	)
	(segment
		(start 43.16476 -45.1993)
		(end 42.7609 -44.79544)
		(width 0.1397)
		(layer "B.Cu")
		(net "CLK_100M_CPU_GBE_DP")
	)
	(segment
		(start 82.96275 -25.698196)
		(end 82.670396 -25.99055)
		(width 0.1143)
		(layer "In4.Cu")
		(net "CLK_100M_CPU_GBE_DP")
	)
	(segment
		(start 63.712344 -27.118056)
		(end 60.0964 -30.734)
		(width 0.1143)
		(layer "In4.Cu")
		(net "CLK_100M_CPU_GBE_DP")
	)
	(segment
		(start 56.488076 -30.734)
		(end 53.975 -33.247076)
		(width 0.1143)
		(layer "In4.Cu")
		(net "CLK_100M_CPU_GBE_DP")
	)
	(segment
		(start 82.96275 -25.383744)
		(end 82.96275 -25.698196)
		(width 0.1143)
		(layer "In4.Cu")
		(net "CLK_100M_CPU_GBE_DP")
	)
	(segment
		(start 65.809622 -27.118056)
		(end 63.712344 -27.118056)
		(width 0.1143)
		(layer "In4.Cu")
		(net "CLK_100M_CPU_GBE_DP")
	)
	(segment
		(start 75.34275 -25.99055)
		(end 74.6379 -26.6954)
		(width 0.1143)
		(layer "In4.Cu")
		(net "CLK_100M_CPU_GBE_DP")
	)
	(segment
		(start 53.975 -33.247076)
		(end 53.975 -35.56)
		(width 0.1143)
		(layer "In4.Cu")
		(net "CLK_100M_CPU_GBE_DP")
	)
	(segment
		(start 83.302094 -25.0444)
		(end 82.96275 -25.383744)
		(width 0.1143)
		(layer "In4.Cu")
		(net "CLK_100M_CPU_GBE_DP")
	)
	(segment
		(start 53.2384 -36.2966)
		(end 48.822864 -36.2966)
		(width 0.1143)
		(layer "In4.Cu")
		(net "CLK_100M_CPU_GBE_DP")
	)
	(segment
		(start 74.6379 -26.6954)
		(end 70.875906 -26.6954)
		(width 0.1143)
		(layer "In4.Cu")
		(net "CLK_100M_CPU_GBE_DP")
	)
	(segment
		(start 48.822864 -36.2966)
		(end 47.660814 -37.45865)
		(width 0.1143)
		(layer "In4.Cu")
		(net "CLK_100M_CPU_GBE_DP")
	)
	(segment
		(start 82.670396 -25.99055)
		(end 75.34275 -25.99055)
		(width 0.1143)
		(layer "In4.Cu")
		(net "CLK_100M_CPU_GBE_DP")
	)
	(segment
		(start 53.975 -35.56)
		(end 53.2384 -36.2966)
		(width 0.1143)
		(layer "In4.Cu")
		(net "CLK_100M_CPU_GBE_DP")
	)
	(segment
		(start 69.485256 -25.30475)
		(end 67.622928 -25.30475)
		(width 0.1143)
		(layer "In4.Cu")
		(net "CLK_100M_CPU_GBE_DP")
	)
	(segment
		(start 42.7736 -42.987214)
		(end 42.7736 -43.83532)
		(width 0.1143)
		(layer "In4.Cu")
		(net "CLK_100M_CPU_GBE_DP")
	)
	(segment
		(start 83.693 -25.0444)
		(end 83.302094 -25.0444)
		(width 0.1143)
		(layer "In4.Cu")
		(net "CLK_100M_CPU_GBE_DP")
	)
	(segment
		(start 67.622928 -25.30475)
		(end 65.809622 -27.118056)
		(width 0.1143)
		(layer "In4.Cu")
		(net "CLK_100M_CPU_GBE_DP")
	)
	(segment
		(start 60.0964 -30.734)
		(end 56.488076 -30.734)
		(width 0.1143)
		(layer "In4.Cu")
		(net "CLK_100M_CPU_GBE_DP")
	)
	(segment
		(start 83.8454 -24.892)
		(end 83.693 -25.0444)
		(width 0.1143)
		(layer "In4.Cu")
		(net "CLK_100M_CPU_GBE_DP")
	)
	(segment
		(start 70.875906 -26.6954)
		(end 69.485256 -25.30475)
		(width 0.1143)
		(layer "In4.Cu")
		(net "CLK_100M_CPU_GBE_DP")
	)
	(segment
		(start 42.7736 -43.83532)
		(end 42.45356 -44.15536)
		(width 0.1143)
		(layer "In4.Cu")
		(net "CLK_100M_CPU_GBE_DP")
	)
	(segment
		(start 47.660814 -37.45865)
		(end 47.660814 -38.1)
		(width 0.1143)
		(layer "In4.Cu")
		(net "CLK_100M_CPU_GBE_DP")
	)
	(segment
		(start 47.660814 -38.1)
		(end 42.7736 -42.987214)
		(width 0.1143)
		(layer "In4.Cu")
		(net "CLK_100M_CPU_GBE_DP")
	)
	(segment
		(start 5.334 -53.3654)
		(end 4.9022 -53.3654)
		(width 0.1143)
		(layer "F.Cu")
		(net "PEDET_SEL")
	)
	(segment
		(start 4.9022 -53.3654)
		(end 4.3942 -52.8574)
		(width 0.1143)
		(layer "F.Cu")
		(net "PEDET_SEL")
	)
	(segment
		(start 4.278376 -52.741576)
		(end 4.3942 -52.8574)
		(width 0.1143)
		(layer "F.Cu")
		(net "PEDET_SEL")
	)
	(segment
		(start 4.278376 -51.5874)
		(end 4.278376 -52.741576)
		(width 0.1143)
		(layer "F.Cu")
		(net "PEDET_SEL")
	)
	(via
		(at 4.3942 -52.8574)
		(size 0.7112)
		(drill 0.3556)
		(layers "F.Cu" "B.Cu")
		(net "PEDET_SEL")
	)
	(via
		(at 4.278376 -51.5874)
		(size 0.508)
		(drill 0.254)
		(layers "F.Cu" "B.Cu")
		(net "PEDET_SEL")
	)
	(segment
		(start 4.278376 -51.296824)
		(end 4.62534 -50.94986)
		(width 0.1143)
		(layer "B.Cu")
		(net "PEDET_SEL")
	)
	(segment
		(start 4.278376 -51.5874)
		(end 4.278376 -51.296824)
		(width 0.1143)
		(layer "B.Cu")
		(net "PEDET_SEL")
	)
	(segment
		(start 4.62534 -50.94986)
		(end 5.575046 -50.94986)
		(width 0.1143)
		(layer "B.Cu")
		(net "PEDET_SEL")
	)
	(segment
		(start 17.392904 -60.30341)
		(end 17.876266 -59.820048)
		(width 0.2032)
		(layer "F.Cu")
		(net "PWRGD_R_PVNN")
	)
	(segment
		(start 17.157446 -60.9346)
		(end 17.164304 -60.9346)
		(width 0.2032)
		(layer "F.Cu")
		(net "PWRGD_R_PVNN")
	)
	(segment
		(start 17.392904 -60.706)
		(end 17.392904 -60.30341)
		(width 0.2032)
		(layer "F.Cu")
		(net "PWRGD_R_PVNN")
	)
	(segment
		(start 15.8496 -62.242446)
		(end 17.157446 -60.9346)
		(width 0.2032)
		(layer "F.Cu")
		(net "PWRGD_R_PVNN")
	)
	(segment
		(start 15.5702 -63.4746)
		(end 15.8496 -63.1952)
		(width 0.2032)
		(layer "F.Cu")
		(net "PWRGD_R_PVNN")
	)
	(segment
		(start 17.164304 -60.9346)
		(end 17.268952 -60.829952)
		(width 0.2032)
		(layer "F.Cu")
		(net "PWRGD_R_PVNN")
	)
	(segment
		(start 17.268952 -60.829952)
		(end 17.392904 -60.706)
		(width 0.2032)
		(layer "F.Cu")
		(net "PWRGD_R_PVNN")
	)
	(segment
		(start 17.876266 -59.820048)
		(end 18.590006 -59.820048)
		(width 0.2032)
		(layer "F.Cu")
		(net "PWRGD_R_PVNN")
	)
	(segment
		(start 15.8496 -63.1952)
		(end 15.8496 -62.242446)
		(width 0.2032)
		(layer "F.Cu")
		(net "PWRGD_R_PVNN")
	)
	(via
		(at 17.268952 -60.829952)
		(size 0.7112)
		(drill 0.3556)
		(layers "F.Cu" "B.Cu")
		(net "PWRGD_R_PVNN")
	)
	(segment
		(start 102.888542 -30.9118)
		(end 102.278688 -31.521654)
		(width 0.1016)
		(layer "F.Cu")
		(net "M_B_MA4")
	)
	(segment
		(start 161.649918 -6.628638)
		(end 161.65322 -6.625336)
		(width 0.2413)
		(layer "F.Cu")
		(net "M_B_MA4")
	)
	(segment
		(start 161.704528 -5.964936)
		(end 161.704528 -5.68325)
		(width 0.2413)
		(layer "F.Cu")
		(net "M_B_MA4")
	)
	(segment
		(start 161.65322 -6.016244)
		(end 161.704528 -5.964936)
		(width 0.2413)
		(layer "F.Cu")
		(net "M_B_MA4")
	)
	(segment
		(start 103.0986 -30.9118)
		(end 102.888542 -30.9118)
		(width 0.1016)
		(layer "F.Cu")
		(net "M_B_MA4")
	)
	(segment
		(start 161.649918 -9.897364)
		(end 161.649918 -6.628638)
		(width 0.2413)
		(layer "F.Cu")
		(net "M_B_MA4")
	)
	(segment
		(start 161.65322 -6.625336)
		(end 161.65322 -6.016244)
		(width 0.2413)
		(layer "F.Cu")
		(net "M_B_MA4")
	)
	(segment
		(start 161.704528 -5.68325)
		(end 162.1536 -5.234178)
		(width 0.2413)
		(layer "F.Cu")
		(net "M_B_MA4")
	)
	(via
		(at 103.0986 -30.9118)
		(size 0.4318)
		(drill 0.2032)
		(layers "F.Cu" "B.Cu")
		(net "M_B_MA4")
	)
	(via
		(at 162.1536 -5.234178)
		(size 0.4318)
		(drill 0.2032)
		(layers "F.Cu" "B.Cu")
		(net "M_B_MA4")
	)
	(segment
		(start 161.649918 -1.690624)
		(end 161.649918 -3.869436)
		(width 0.2413)
		(layer "B.Cu")
		(net "M_B_MA4")
	)
	(segment
		(start 162.1536 -4.373118)
		(end 162.1536 -5.234178)
		(width 0.2413)
		(layer "B.Cu")
		(net "M_B_MA4")
	)
	(segment
		(start 161.649918 -3.869436)
		(end 162.1536 -4.373118)
		(width 0.2413)
		(layer "B.Cu")
		(net "M_B_MA4")
	)
	(segment
		(start 161.679128 -5.954522)
		(end 161.67862 -5.95503)
		(width 0.1905)
		(layer "In7.Cu")
		(net "M_B_MA4")
	)
	(segment
		(start 161.67862 -5.95503)
		(end 161.67862 -7.31774)
		(width 0.1905)
		(layer "In7.Cu")
		(net "M_B_MA4")
	)
	(segment
		(start 160.7058 -14.527276)
		(end 151.877776 -23.3553)
		(width 0.1905)
		(layer "In7.Cu")
		(net "M_B_MA4")
	)
	(segment
		(start 161.67862 -7.31774)
		(end 161.798 -7.43712)
		(width 0.1905)
		(layer "In7.Cu")
		(net "M_B_MA4")
	)
	(segment
		(start 113.997994 -25.908)
		(end 110.882176 -25.908)
		(width 0.1905)
		(layer "In7.Cu")
		(net "M_B_MA4")
	)
	(segment
		(start 116.550694 -23.3553)
		(end 113.997994 -25.908)
		(width 0.1905)
		(layer "In7.Cu")
		(net "M_B_MA4")
	)
	(segment
		(start 103.5304 -28.998926)
		(end 104.005126 -28.5242)
		(width 0.1016)
		(layer "In7.Cu")
		(net "M_B_MA4")
	)
	(segment
		(start 107.847384 -26.129488)
		(end 110.660688 -26.129488)
		(width 0.1016)
		(layer "In7.Cu")
		(net "M_B_MA4")
	)
	(segment
		(start 104.005126 -28.5242)
		(end 105.452672 -28.5242)
		(width 0.1016)
		(layer "In7.Cu")
		(net "M_B_MA4")
	)
	(segment
		(start 103.5304 -30.366208)
		(end 103.5304 -28.998926)
		(width 0.1016)
		(layer "In7.Cu")
		(net "M_B_MA4")
	)
	(segment
		(start 161.798 -7.43712)
		(end 161.798 -10.069068)
		(width 0.1905)
		(layer "In7.Cu")
		(net "M_B_MA4")
	)
	(segment
		(start 151.877776 -23.3553)
		(end 116.550694 -23.3553)
		(width 0.1905)
		(layer "In7.Cu")
		(net "M_B_MA4")
	)
	(segment
		(start 105.452672 -28.5242)
		(end 107.847384 -26.129488)
		(width 0.1016)
		(layer "In7.Cu")
		(net "M_B_MA4")
	)
	(segment
		(start 160.7058 -11.161268)
		(end 160.7058 -14.527276)
		(width 0.1905)
		(layer "In7.Cu")
		(net "M_B_MA4")
	)
	(segment
		(start 103.0986 -30.798008)
		(end 103.5304 -30.366208)
		(width 0.1016)
		(layer "In7.Cu")
		(net "M_B_MA4")
	)
	(segment
		(start 161.679128 -5.70865)
		(end 161.679128 -5.954522)
		(width 0.1905)
		(layer "In7.Cu")
		(net "M_B_MA4")
	)
	(segment
		(start 103.0986 -30.9118)
		(end 103.0986 -30.798008)
		(width 0.1016)
		(layer "In7.Cu")
		(net "M_B_MA4")
	)
	(segment
		(start 110.882176 -25.908)
		(end 110.660688 -26.129488)
		(width 0.1905)
		(layer "In7.Cu")
		(net "M_B_MA4")
	)
	(segment
		(start 162.1536 -5.234178)
		(end 161.679128 -5.70865)
		(width 0.1905)
		(layer "In7.Cu")
		(net "M_B_MA4")
	)
	(segment
		(start 161.798 -10.069068)
		(end 160.7058 -11.161268)
		(width 0.1905)
		(layer "In7.Cu")
		(net "M_B_MA4")
	)
	(segment
		(start 111.262668 -38.265354)
		(end 111.887 -38.265354)
		(width 0.127)
		(layer "F.Cu")
		(net "AVV_VCCCPUVIDSIO_1P03_SENSE")
	)
	(segment
		(start 112.776 -38.354)
		(end 113.840006 -37.289994)
		(width 0.127)
		(layer "F.Cu")
		(net "AVV_VCCCPUVIDSIO_1P03_SENSE")
	)
	(segment
		(start 114.5032 -36.9316)
		(end 114.5032 -37.289994)
		(width 0.127)
		(layer "F.Cu")
		(net "AVV_VCCCPUVIDSIO_1P03_SENSE")
	)
	(segment
		(start 116.297202 -36.703)
		(end 115.772184 -36.703)
		(width 0.127)
		(layer "F.Cu")
		(net "AVV_VCCCPUVIDSIO_1P03_SENSE")
	)
	(segment
		(start 115.772184 -36.703)
		(end 115.18519 -37.289994)
		(width 0.127)
		(layer "F.Cu")
		(net "AVV_VCCCPUVIDSIO_1P03_SENSE")
	)
	(segment
		(start 113.840006 -37.289994)
		(end 114.5032 -37.289994)
		(width 0.127)
		(layer "F.Cu")
		(net "AVV_VCCCPUVIDSIO_1P03_SENSE")
	)
	(segment
		(start 111.975646 -38.354)
		(end 112.776 -38.354)
		(width 0.127)
		(layer "F.Cu")
		(net "AVV_VCCCPUVIDSIO_1P03_SENSE")
	)
	(segment
		(start 116.5352 -36.465002)
		(end 116.297202 -36.703)
		(width 0.127)
		(layer "F.Cu")
		(net "AVV_VCCCPUVIDSIO_1P03_SENSE")
	)
	(segment
		(start 111.092488 -38.095174)
		(end 111.262668 -38.265354)
		(width 0.127)
		(layer "F.Cu")
		(net "AVV_VCCCPUVIDSIO_1P03_SENSE")
	)
	(segment
		(start 111.887 -38.265354)
		(end 111.975646 -38.354)
		(width 0.127)
		(layer "F.Cu")
		(net "AVV_VCCCPUVIDSIO_1P03_SENSE")
	)
	(segment
		(start 115.18519 -37.289994)
		(end 114.5032 -37.289994)
		(width 0.127)
		(layer "F.Cu")
		(net "AVV_VCCCPUVIDSIO_1P03_SENSE")
	)
	(via
		(at 114.5032 -36.9316)
		(size 0.7112)
		(drill 0.3556)
		(layers "F.Cu" "B.Cu")
		(net "AVV_VCCCPUVIDSIO_1P03_SENSE")
	)
	(segment
		(start 107.671108 -34.996374)
		(end 107.2896 -35.306)
		(width 0.1016)
		(layer "F.Cu")
		(net "M_B_DQ50")
	)
	(segment
		(start 182.649876 -9.897364)
		(end 182.649876 -9.000744)
		(width 0.1778)
		(layer "F.Cu")
		(net "M_B_DQ50")
	)
	(segment
		(start 183.266842 -8.383778)
		(end 183.310276 -8.383778)
		(width 0.1778)
		(layer "F.Cu")
		(net "M_B_DQ50")
	)
	(segment
		(start 183.310276 -8.383778)
		(end 183.323738 -8.370316)
		(width 0.1778)
		(layer "F.Cu")
		(net "M_B_DQ50")
	)
	(segment
		(start 182.649876 -9.000744)
		(end 183.266842 -8.383778)
		(width 0.1778)
		(layer "F.Cu")
		(net "M_B_DQ50")
	)
	(via
		(at 183.323738 -8.370316)
		(size 0.4318)
		(drill 0.2032)
		(layers "F.Cu" "B.Cu")
		(net "M_B_DQ50")
	)
	(via
		(at 107.2896 -35.306)
		(size 0.4318)
		(drill 0.2032)
		(layers "F.Cu" "B.Cu")
		(net "M_B_DQ50")
	)
	(segment
		(start 183.550052 -8.59663)
		(end 183.323738 -8.370316)
		(width 0.1778)
		(layer "B.Cu")
		(net "M_B_DQ50")
	)
	(segment
		(start 183.550052 -9.89076)
		(end 183.550052 -8.59663)
		(width 0.1778)
		(layer "B.Cu")
		(net "M_B_DQ50")
	)
	(segment
		(start 117.733826 -38.608)
		(end 117.581426 -38.7604)
		(width 0.1524)
		(layer "In9.Cu")
		(net "M_B_DQ50")
	)
	(segment
		(start 106.68 -36.449)
		(end 106.644948 -36.199064)
		(width 0.1016)
		(layer "In9.Cu")
		(net "M_B_DQ50")
	)
	(segment
		(start 116.514626 -38.608)
		(end 116.362226 -38.7604)
		(width 0.1524)
		(layer "In9.Cu")
		(net "M_B_DQ50")
	)
	(segment
		(start 117.124226 -39.243)
		(end 116.971826 -39.0906)
		(width 0.1524)
		(layer "In9.Cu")
		(net "M_B_DQ50")
	)
	(segment
		(start 116.209826 -39.2938)
		(end 115.905026 -39.2938)
		(width 0.1524)
		(layer "In9.Cu")
		(net "M_B_DQ50")
	)
	(segment
		(start 183.35752 -8.404098)
		(end 183.35752 -10.31748)
		(width 0.1524)
		(layer "In9.Cu")
		(net "M_B_DQ50")
	)
	(segment
		(start 112.2934 -38.608)
		(end 111.7854 -38.1)
		(width 0.1524)
		(layer "In9.Cu")
		(net "M_B_DQ50")
	)
	(segment
		(start 180.624226 -16.199104)
		(end 167.07485 -30.969458)
		(width 0.1524)
		(layer "In9.Cu")
		(net "M_B_DQ50")
	)
	(segment
		(start 157.77718 -38.913054)
		(end 157.293564 -38.913054)
		(width 0.1524)
		(layer "In9.Cu")
		(net "M_B_DQ50")
	)
	(segment
		(start 116.362226 -39.1414)
		(end 116.209826 -39.2938)
		(width 0.1524)
		(layer "In9.Cu")
		(net "M_B_DQ50")
	)
	(segment
		(start 115.752626 -38.7604)
		(end 115.600226 -38.608)
		(width 0.1524)
		(layer "In9.Cu")
		(net "M_B_DQ50")
	)
	(segment
		(start 183.35752 -10.31748)
		(end 180.624226 -13.050774)
		(width 0.1524)
		(layer "In9.Cu")
		(net "M_B_DQ50")
	)
	(segment
		(start 114.685826 -39.2938)
		(end 114.533426 -39.1414)
		(width 0.1524)
		(layer "In9.Cu")
		(net "M_B_DQ50")
	)
	(segment
		(start 167.07485 -30.969458)
		(end 165.526466 -32.518096)
		(width 0.1524)
		(layer "In9.Cu")
		(net "M_B_DQ50")
	)
	(segment
		(start 115.295426 -38.608)
		(end 115.143026 -38.7604)
		(width 0.1524)
		(layer "In9.Cu")
		(net "M_B_DQ50")
	)
	(segment
		(start 117.581426 -38.7604)
		(end 117.581426 -39.0906)
		(width 0.1524)
		(layer "In9.Cu")
		(net "M_B_DQ50")
	)
	(segment
		(start 114.533426 -39.1414)
		(end 114.533426 -38.7604)
		(width 0.1524)
		(layer "In9.Cu")
		(net "M_B_DQ50")
	)
	(segment
		(start 115.905026 -39.2938)
		(end 115.752626 -39.1414)
		(width 0.1524)
		(layer "In9.Cu")
		(net "M_B_DQ50")
	)
	(segment
		(start 157.29331 -38.9128)
		(end 128.3462 -38.9128)
		(width 0.1524)
		(layer "In9.Cu")
		(net "M_B_DQ50")
	)
	(segment
		(start 114.990626 -39.2938)
		(end 114.685826 -39.2938)
		(width 0.1524)
		(layer "In9.Cu")
		(net "M_B_DQ50")
	)
	(segment
		(start 117.581426 -39.0906)
		(end 117.429026 -39.243)
		(width 0.1524)
		(layer "In9.Cu")
		(net "M_B_DQ50")
	)
	(segment
		(start 106.7054 -35.8394)
		(end 107.2896 -35.306)
		(width 0.1016)
		(layer "In9.Cu")
		(net "M_B_DQ50")
	)
	(segment
		(start 107.2642 -36.9824)
		(end 106.68 -36.449)
		(width 0.1016)
		(layer "In9.Cu")
		(net "M_B_DQ50")
	)
	(segment
		(start 116.819426 -38.608)
		(end 116.514626 -38.608)
		(width 0.1524)
		(layer "In9.Cu")
		(net "M_B_DQ50")
	)
	(segment
		(start 180.624226 -13.050774)
		(end 180.624226 -16.199104)
		(width 0.1524)
		(layer "In9.Cu")
		(net "M_B_DQ50")
	)
	(segment
		(start 115.143026 -38.7604)
		(end 115.143026 -39.1414)
		(width 0.1524)
		(layer "In9.Cu")
		(net "M_B_DQ50")
	)
	(segment
		(start 128.0414 -38.608)
		(end 117.733826 -38.608)
		(width 0.1524)
		(layer "In9.Cu")
		(net "M_B_DQ50")
	)
	(segment
		(start 165.526466 -32.518096)
		(end 162.966654 -35.077908)
		(width 0.1524)
		(layer "In9.Cu")
		(net "M_B_DQ50")
	)
	(segment
		(start 114.533426 -38.7604)
		(end 114.381026 -38.608)
		(width 0.1524)
		(layer "In9.Cu")
		(net "M_B_DQ50")
	)
	(segment
		(start 114.381026 -38.608)
		(end 112.2934 -38.608)
		(width 0.1524)
		(layer "In9.Cu")
		(net "M_B_DQ50")
	)
	(segment
		(start 108.3818 -38.1)
		(end 107.2642 -36.9824)
		(width 0.1016)
		(layer "In9.Cu")
		(net "M_B_DQ50")
	)
	(segment
		(start 115.752626 -39.1414)
		(end 115.752626 -38.7604)
		(width 0.1524)
		(layer "In9.Cu")
		(net "M_B_DQ50")
	)
	(segment
		(start 111.7854 -38.1)
		(end 109.3216 -38.1)
		(width 0.1524)
		(layer "In9.Cu")
		(net "M_B_DQ50")
	)
	(segment
		(start 162.966654 -35.077908)
		(end 157.77718 -38.913054)
		(width 0.1524)
		(layer "In9.Cu")
		(net "M_B_DQ50")
	)
	(segment
		(start 109.3216 -38.1)
		(end 108.3818 -38.1)
		(width 0.1016)
		(layer "In9.Cu")
		(net "M_B_DQ50")
	)
	(segment
		(start 183.323738 -8.370316)
		(end 183.35752 -8.404098)
		(width 0.1524)
		(layer "In9.Cu")
		(net "M_B_DQ50")
	)
	(segment
		(start 117.429026 -39.243)
		(end 117.124226 -39.243)
		(width 0.1524)
		(layer "In9.Cu")
		(net "M_B_DQ50")
	)
	(segment
		(start 157.293564 -38.913054)
		(end 157.29331 -38.9128)
		(width 0.1524)
		(layer "In9.Cu")
		(net "M_B_DQ50")
	)
	(segment
		(start 116.971826 -39.0906)
		(end 116.971826 -38.7604)
		(width 0.1524)
		(layer "In9.Cu")
		(net "M_B_DQ50")
	)
	(segment
		(start 106.644948 -36.199064)
		(end 106.64952 -35.93719)
		(width 0.1016)
		(layer "In9.Cu")
		(net "M_B_DQ50")
	)
	(segment
		(start 116.362226 -38.7604)
		(end 116.362226 -39.1414)
		(width 0.1524)
		(layer "In9.Cu")
		(net "M_B_DQ50")
	)
	(segment
		(start 116.971826 -38.7604)
		(end 116.819426 -38.608)
		(width 0.1524)
		(layer "In9.Cu")
		(net "M_B_DQ50")
	)
	(segment
		(start 128.3462 -38.9128)
		(end 128.0414 -38.608)
		(width 0.1524)
		(layer "In9.Cu")
		(net "M_B_DQ50")
	)
	(segment
		(start 106.64952 -35.93719)
		(end 106.7054 -35.8394)
		(width 0.1016)
		(layer "In9.Cu")
		(net "M_B_DQ50")
	)
	(segment
		(start 115.600226 -38.608)
		(end 115.295426 -38.608)
		(width 0.1524)
		(layer "In9.Cu")
		(net "M_B_DQ50")
	)
	(segment
		(start 115.143026 -39.1414)
		(end 114.990626 -39.2938)
		(width 0.1524)
		(layer "In9.Cu")
		(net "M_B_DQ50")
	)
	(segment
		(start 16.9672 -69.9008)
		(end 16.2306 -69.9008)
		(width 0.127)
		(layer "F.Cu")
		(net "LED_NGFF_DAS_R")
	)
	(segment
		(start 16.2306 -69.9008)
		(end 15.5448 -69.215)
		(width 0.127)
		(layer "F.Cu")
		(net "LED_NGFF_DAS_R")
	)
	(via
		(at 16.9672 -69.9008)
		(size 0.508)
		(drill 0.254)
		(layers "F.Cu" "B.Cu")
		(net "LED_NGFF_DAS_R")
	)
	(via
		(at 6.139942 -45.251116)
		(size 0.7112)
		(drill 0.3556)
		(layers "F.Cu" "B.Cu")
		(net "LED_NGFF_DAS_R")
	)
	(via
		(at 6.731 -46.1772)
		(size 0.508)
		(drill 0.254)
		(layers "F.Cu" "B.Cu")
		(net "LED_NGFF_DAS_R")
	)
	(segment
		(start 4.986274 -45.737526)
		(end 5.472684 -45.251116)
		(width 0.127)
		(layer "B.Cu")
		(net "LED_NGFF_DAS_R")
	)
	(segment
		(start 4.826 -45.737526)
		(end 4.986274 -45.737526)
		(width 0.127)
		(layer "B.Cu")
		(net "LED_NGFF_DAS_R")
	)
	(segment
		(start 5.472684 -45.251116)
		(end 6.139942 -45.251116)
		(width 0.127)
		(layer "B.Cu")
		(net "LED_NGFF_DAS_R")
	)
	(segment
		(start 6.731 -45.842174)
		(end 6.731 -46.1772)
		(width 0.127)
		(layer "B.Cu")
		(net "LED_NGFF_DAS_R")
	)
	(segment
		(start 6.139942 -45.251116)
		(end 6.731 -45.842174)
		(width 0.127)
		(layer "B.Cu")
		(net "LED_NGFF_DAS_R")
	)
	(segment
		(start 12.3698 -48.1076)
		(end 12.3698 -49.7332)
		(width 0.127)
		(layer "In2.Cu")
		(net "LED_NGFF_DAS_R")
	)
	(segment
		(start 6.731 -46.1772)
		(end 6.731 -46.3804)
		(width 0.127)
		(layer "In2.Cu")
		(net "LED_NGFF_DAS_R")
	)
	(segment
		(start 12.8778 -59.40679)
		(end 11.9634 -60.32119)
		(width 0.127)
		(layer "In2.Cu")
		(net "LED_NGFF_DAS_R")
	)
	(segment
		(start 16.891 -69.977)
		(end 16.9672 -69.9008)
		(width 0.127)
		(layer "In2.Cu")
		(net "LED_NGFF_DAS_R")
	)
	(segment
		(start 12.8778 -50.2412)
		(end 12.8778 -59.40679)
		(width 0.127)
		(layer "In2.Cu")
		(net "LED_NGFF_DAS_R")
	)
	(segment
		(start 6.731 -46.3804)
		(end 7.5438 -47.1932)
		(width 0.127)
		(layer "In2.Cu")
		(net "LED_NGFF_DAS_R")
	)
	(segment
		(start 11.4554 -47.1932)
		(end 12.3698 -48.1076)
		(width 0.127)
		(layer "In2.Cu")
		(net "LED_NGFF_DAS_R")
	)
	(segment
		(start 11.9634 -60.32119)
		(end 11.9634 -67.056)
		(width 0.127)
		(layer "In2.Cu")
		(net "LED_NGFF_DAS_R")
	)
	(segment
		(start 11.8872 -67.1322)
		(end 11.8872 -69.01561)
		(width 0.127)
		(layer "In2.Cu")
		(net "LED_NGFF_DAS_R")
	)
	(segment
		(start 7.5438 -47.1932)
		(end 11.4554 -47.1932)
		(width 0.127)
		(layer "In2.Cu")
		(net "LED_NGFF_DAS_R")
	)
	(segment
		(start 11.9634 -67.056)
		(end 11.8872 -67.1322)
		(width 0.127)
		(layer "In2.Cu")
		(net "LED_NGFF_DAS_R")
	)
	(segment
		(start 12.84859 -69.977)
		(end 16.891 -69.977)
		(width 0.127)
		(layer "In2.Cu")
		(net "LED_NGFF_DAS_R")
	)
	(segment
		(start 11.8872 -69.01561)
		(end 12.84859 -69.977)
		(width 0.127)
		(layer "In2.Cu")
		(net "LED_NGFF_DAS_R")
	)
	(segment
		(start 12.3698 -49.7332)
		(end 12.8778 -50.2412)
		(width 0.127)
		(layer "In2.Cu")
		(net "LED_NGFF_DAS_R")
	)
	(segment
		(start 24.999188 -58.8772)
		(end 24.741886 -58.619898)
		(width 0.2032)
		(layer "F.Cu")
		(net "VR_PVCCP_PVNN_VCCP")
	)
	(segment
		(start 26.336498 -59.7916)
		(end 25.5778 -59.032902)
		(width 0.508)
		(layer "F.Cu")
		(net "VR_PVCCP_PVNN_VCCP")
	)
	(segment
		(start 25.5778 -58.8772)
		(end 24.999188 -58.8772)
		(width 0.2032)
		(layer "F.Cu")
		(net "VR_PVCCP_PVNN_VCCP")
	)
	(segment
		(start 24.741886 -58.619898)
		(end 24.335994 -58.619898)
		(width 0.2032)
		(layer "F.Cu")
		(net "VR_PVCCP_PVNN_VCCP")
	)
	(segment
		(start 25.5778 -59.032902)
		(end 25.5778 -58.8772)
		(width 0.508)
		(layer "F.Cu")
		(net "VR_PVCCP_PVNN_VCCP")
	)
	(segment
		(start 26.416 -60.7314)
		(end 26.416 -59.7916)
		(width 0.508)
		(layer "F.Cu")
		(net "VR_PVCCP_PVNN_VCCP")
	)
	(segment
		(start 26.416 -59.7916)
		(end 26.336498 -59.7916)
		(width 0.508)
		(layer "F.Cu")
		(net "VR_PVCCP_PVNN_VCCP")
	)
	(segment
		(start 26.3144 -60.833)
		(end 26.416 -60.7314)
		(width 0.508)
		(layer "F.Cu")
		(net "VR_PVCCP_PVNN_VCCP")
	)
	(via
		(at 25.5778 -58.8772)
		(size 0.7112)
		(drill 0.3556)
		(layers "F.Cu" "B.Cu")
		(net "VR_PVCCP_PVNN_VCCP")
	)
	(segment
		(start 186.321192 -6.922262)
		(end 186.321192 -6.184646)
		(width 0.1778)
		(layer "F.Cu")
		(net "M_B_DQS_DN7")
	)
	(segment
		(start 186.249818 -9.155938)
		(end 186.734196 -8.67156)
		(width 0.1778)
		(layer "F.Cu")
		(net "M_B_DQS_DN7")
	)
	(segment
		(start 186.8932 -7.49427)
		(end 186.321192 -6.922262)
		(width 0.1778)
		(layer "F.Cu")
		(net "M_B_DQS_DN7")
	)
	(segment
		(start 186.249818 -9.897364)
		(end 186.249818 -9.155938)
		(width 0.1778)
		(layer "F.Cu")
		(net "M_B_DQS_DN7")
	)
	(segment
		(start 186.734196 -8.67156)
		(end 186.734196 -8.13689)
		(width 0.1778)
		(layer "F.Cu")
		(net "M_B_DQS_DN7")
	)
	(segment
		(start 186.8932 -7.977886)
		(end 186.8932 -7.49427)
		(width 0.1778)
		(layer "F.Cu")
		(net "M_B_DQS_DN7")
	)
	(segment
		(start 107.290108 -37.683694)
		(end 107.263946 -37.683694)
		(width 0.1016)
		(layer "F.Cu")
		(net "M_B_DQS_DN7")
	)
	(segment
		(start 186.321192 -6.184646)
		(end 186.132724 -5.996178)
		(width 0.1778)
		(layer "F.Cu")
		(net "M_B_DQS_DN7")
	)
	(segment
		(start 107.263946 -37.683694)
		(end 106.898694 -37.318442)
		(width 0.1016)
		(layer "F.Cu")
		(net "M_B_DQS_DN7")
	)
	(segment
		(start 186.734196 -8.13689)
		(end 186.8932 -7.977886)
		(width 0.1778)
		(layer "F.Cu")
		(net "M_B_DQS_DN7")
	)
	(via
		(at 106.898694 -37.318442)
		(size 0.4318)
		(drill 0.2032)
		(layers "F.Cu" "B.Cu")
		(net "M_B_DQS_DN7")
	)
	(via
		(at 186.132724 -5.996178)
		(size 0.4318)
		(drill 0.2032)
		(layers "F.Cu" "B.Cu")
		(net "M_B_DQS_DN7")
	)
	(segment
		(start 186.397392 -2.60477)
		(end 186.397392 -5.73151)
		(width 0.1778)
		(layer "B.Cu")
		(net "M_B_DQS_DN7")
	)
	(segment
		(start 186.249818 -1.690624)
		(end 186.249818 -2.457196)
		(width 0.1778)
		(layer "B.Cu")
		(net "M_B_DQS_DN7")
	)
	(segment
		(start 186.397392 -5.73151)
		(end 186.132724 -5.996178)
		(width 0.1778)
		(layer "B.Cu")
		(net "M_B_DQS_DN7")
	)
	(segment
		(start 186.249818 -2.457196)
		(end 186.397392 -2.60477)
		(width 0.1778)
		(layer "B.Cu")
		(net "M_B_DQS_DN7")
	)
	(segment
		(start 157.526228 -35.9918)
		(end 149.159976 -35.9918)
		(width 0.1524)
		(layer "In2.Cu")
		(net "M_B_DQS_DN7")
	)
	(segment
		(start 109.545882 -37.8841)
		(end 110.96498 -36.465002)
		(width 0.1016)
		(layer "In2.Cu")
		(net "M_B_DQS_DN7")
	)
	(segment
		(start 147.663662 -36.459414)
		(end 147.511262 -36.307014)
		(width 0.1524)
		(layer "In2.Cu")
		(net "M_B_DQS_DN7")
	)
	(segment
		(start 113.138966 -36.46424)
		(end 117.596412 -36.46424)
		(width 0.1016)
		(layer "In2.Cu")
		(net "M_B_DQS_DN7")
	)
	(segment
		(start 137.077958 -36.459414)
		(end 136.953498 -36.334954)
		(width 0.1524)
		(layer "In2.Cu")
		(net "M_B_DQS_DN7")
	)
	(segment
		(start 135.447024 -35.9918)
		(end 132.497576 -35.9918)
		(width 0.1524)
		(layer "In2.Cu")
		(net "M_B_DQS_DN7")
	)
	(segment
		(start 132.029962 -36.459414)
		(end 117.6274 -36.459414)
		(width 0.1524)
		(layer "In2.Cu")
		(net "M_B_DQS_DN7")
	)
	(segment
		(start 186.4106 -7.367778)
		(end 184.468262 -9.310116)
		(width 0.1524)
		(layer "In2.Cu")
		(net "M_B_DQS_DN7")
	)
	(segment
		(start 186.4106 -6.274054)
		(end 186.4106 -6.478778)
		(width 0.1524)
		(layer "In2.Cu")
		(net "M_B_DQS_DN7")
	)
	(segment
		(start 107.757214 -37.543486)
		(end 108.097828 -37.8841)
		(width 0.1016)
		(layer "In2.Cu")
		(net "M_B_DQS_DN7")
	)
	(segment
		(start 146.658838 -35.2298)
		(end 146.342862 -35.545776)
		(width 0.1524)
		(layer "In2.Cu")
		(net "M_B_DQS_DN7")
	)
	(segment
		(start 149.159976 -35.9918)
		(end 148.692362 -36.459414)
		(width 0.1524)
		(layer "In2.Cu")
		(net "M_B_DQS_DN7")
	)
	(segment
		(start 141.158976 -35.9918)
		(end 140.691362 -36.459414)
		(width 0.1524)
		(layer "In2.Cu")
		(net "M_B_DQS_DN7")
	)
	(segment
		(start 111.83747 -36.465002)
		(end 112.105694 -36.196778)
		(width 0.1016)
		(layer "In2.Cu")
		(net "M_B_DQS_DN7")
	)
	(segment
		(start 143.915638 -36.459414)
		(end 143.448024 -35.9918)
		(width 0.1524)
		(layer "In2.Cu")
		(net "M_B_DQS_DN7")
	)
	(segment
		(start 137.535158 -36.459414)
		(end 137.077958 -36.459414)
		(width 0.1524)
		(layer "In2.Cu")
		(net "M_B_DQS_DN7")
	)
	(segment
		(start 117.601238 -36.459414)
		(end 117.6274 -36.459414)
		(width 0.1016)
		(layer "In2.Cu")
		(net "M_B_DQS_DN7")
	)
	(segment
		(start 147.511262 -35.545776)
		(end 147.195286 -35.2298)
		(width 0.1524)
		(layer "In2.Cu")
		(net "M_B_DQS_DN7")
	)
	(segment
		(start 146.342862 -35.545776)
		(end 146.342862 -36.307014)
		(width 0.1524)
		(layer "In2.Cu")
		(net "M_B_DQS_DN7")
	)
	(segment
		(start 135.914638 -36.459414)
		(end 135.447024 -35.9918)
		(width 0.1524)
		(layer "In2.Cu")
		(net "M_B_DQS_DN7")
	)
	(segment
		(start 186.132724 -5.996178)
		(end 186.4106 -6.274054)
		(width 0.1524)
		(layer "In2.Cu")
		(net "M_B_DQS_DN7")
	)
	(segment
		(start 136.496298 -36.334954)
		(end 136.371838 -36.459414)
		(width 0.1524)
		(layer "In2.Cu")
		(net "M_B_DQS_DN7")
	)
	(segment
		(start 186.4106 -7.062978)
		(end 186.4106 -7.367778)
		(width 0.1524)
		(layer "In2.Cu")
		(net "M_B_DQS_DN7")
	)
	(segment
		(start 184.468262 -9.310116)
		(end 184.207912 -9.310116)
		(width 0.1524)
		(layer "In2.Cu")
		(net "M_B_DQS_DN7")
	)
	(segment
		(start 139.404598 -36.459414)
		(end 139.280138 -36.334954)
		(width 0.1524)
		(layer "In2.Cu")
		(net "M_B_DQS_DN7")
	)
	(segment
		(start 138.698478 -36.459414)
		(end 138.241278 -36.459414)
		(width 0.1524)
		(layer "In2.Cu")
		(net "M_B_DQS_DN7")
	)
	(segment
		(start 137.659618 -36.334954)
		(end 137.535158 -36.459414)
		(width 0.1524)
		(layer "In2.Cu")
		(net "M_B_DQS_DN7")
	)
	(segment
		(start 139.280138 -36.334954)
		(end 138.822938 -36.334954)
		(width 0.1524)
		(layer "In2.Cu")
		(net "M_B_DQS_DN7")
	)
	(segment
		(start 186.2328 -6.656578)
		(end 186.2328 -6.885178)
		(width 0.1524)
		(layer "In2.Cu")
		(net "M_B_DQS_DN7")
	)
	(segment
		(start 112.105694 -36.196778)
		(end 112.871504 -36.196778)
		(width 0.1016)
		(layer "In2.Cu")
		(net "M_B_DQS_DN7")
	)
	(segment
		(start 110.96498 -36.465002)
		(end 111.83747 -36.465002)
		(width 0.1016)
		(layer "In2.Cu")
		(net "M_B_DQS_DN7")
	)
	(segment
		(start 106.898694 -37.318442)
		(end 107.123738 -37.543486)
		(width 0.1016)
		(layer "In2.Cu")
		(net "M_B_DQS_DN7")
	)
	(segment
		(start 186.2328 -6.885178)
		(end 186.4106 -7.062978)
		(width 0.1524)
		(layer "In2.Cu")
		(net "M_B_DQS_DN7")
	)
	(segment
		(start 132.497576 -35.9918)
		(end 132.029962 -36.459414)
		(width 0.1524)
		(layer "In2.Cu")
		(net "M_B_DQS_DN7")
	)
	(segment
		(start 184.207912 -9.310116)
		(end 157.526228 -35.9918)
		(width 0.1524)
		(layer "In2.Cu")
		(net "M_B_DQS_DN7")
	)
	(segment
		(start 143.448024 -35.9918)
		(end 141.158976 -35.9918)
		(width 0.1524)
		(layer "In2.Cu")
		(net "M_B_DQS_DN7")
	)
	(segment
		(start 136.371838 -36.459414)
		(end 135.914638 -36.459414)
		(width 0.1524)
		(layer "In2.Cu")
		(net "M_B_DQS_DN7")
	)
	(segment
		(start 140.691362 -36.459414)
		(end 139.404598 -36.459414)
		(width 0.1524)
		(layer "In2.Cu")
		(net "M_B_DQS_DN7")
	)
	(segment
		(start 147.195286 -35.2298)
		(end 146.658838 -35.2298)
		(width 0.1524)
		(layer "In2.Cu")
		(net "M_B_DQS_DN7")
	)
	(segment
		(start 107.123738 -37.543486)
		(end 107.757214 -37.543486)
		(width 0.1016)
		(layer "In2.Cu")
		(net "M_B_DQS_DN7")
	)
	(segment
		(start 146.342862 -36.307014)
		(end 146.190462 -36.459414)
		(width 0.1524)
		(layer "In2.Cu")
		(net "M_B_DQS_DN7")
	)
	(segment
		(start 186.4106 -6.478778)
		(end 186.2328 -6.656578)
		(width 0.1524)
		(layer "In2.Cu")
		(net "M_B_DQS_DN7")
	)
	(segment
		(start 112.871504 -36.196778)
		(end 113.138966 -36.46424)
		(width 0.1016)
		(layer "In2.Cu")
		(net "M_B_DQS_DN7")
	)
	(segment
		(start 138.822938 -36.334954)
		(end 138.698478 -36.459414)
		(width 0.1524)
		(layer "In2.Cu")
		(net "M_B_DQS_DN7")
	)
	(segment
		(start 138.116818 -36.334954)
		(end 137.659618 -36.334954)
		(width 0.1524)
		(layer "In2.Cu")
		(net "M_B_DQS_DN7")
	)
	(segment
		(start 117.596412 -36.46424)
		(end 117.601238 -36.459414)
		(width 0.1016)
		(layer "In2.Cu")
		(net "M_B_DQS_DN7")
	)
	(segment
		(start 148.692362 -36.459414)
		(end 147.663662 -36.459414)
		(width 0.1524)
		(layer "In2.Cu")
		(net "M_B_DQS_DN7")
	)
	(segment
		(start 108.097828 -37.8841)
		(end 109.545882 -37.8841)
		(width 0.1016)
		(layer "In2.Cu")
		(net "M_B_DQS_DN7")
	)
	(segment
		(start 147.511262 -36.307014)
		(end 147.511262 -35.545776)
		(width 0.1524)
		(layer "In2.Cu")
		(net "M_B_DQS_DN7")
	)
	(segment
		(start 146.190462 -36.459414)
		(end 143.915638 -36.459414)
		(width 0.1524)
		(layer "In2.Cu")
		(net "M_B_DQS_DN7")
	)
	(segment
		(start 136.953498 -36.334954)
		(end 136.496298 -36.334954)
		(width 0.1524)
		(layer "In2.Cu")
		(net "M_B_DQS_DN7")
	)
	(segment
		(start 138.241278 -36.459414)
		(end 138.116818 -36.334954)
		(width 0.1524)
		(layer "In2.Cu")
		(net "M_B_DQS_DN7")
	)
	(segment
		(start 58.97626 -17.018)
		(end 58.190892 -17.803368)
		(width 0.1143)
		(layer "F.Cu")
		(net "SPI_MOSI_GBE_R")
	)
	(segment
		(start 58.190892 -17.803368)
		(end 58.142124 -17.7546)
		(width 0.1143)
		(layer "F.Cu")
		(net "SPI_MOSI_GBE_R")
	)
	(segment
		(start 58.142124 -17.7546)
		(end 56.7309 -17.7546)
		(width 0.1143)
		(layer "F.Cu")
		(net "SPI_MOSI_GBE_R")
	)
	(segment
		(start 59.3852 -17.018)
		(end 58.97626 -17.018)
		(width 0.1143)
		(layer "F.Cu")
		(net "SPI_MOSI_GBE_R")
	)
	(via
		(at 58.190892 -17.803368)
		(size 0.7112)
		(drill 0.3556)
		(layers "F.Cu" "B.Cu")
		(net "SPI_MOSI_GBE_R")
	)
	(segment
		(start 11.6586 -62.0776)
		(end 11.049 -61.468)
		(width 0.127)
		(layer "F.Cu")
		(net "TP_PVCCP_VDIO")
	)
	(segment
		(start 12.4968 -62.0776)
		(end 11.6586 -62.0776)
		(width 0.127)
		(layer "F.Cu")
		(net "TP_PVCCP_VDIO")
	)
	(segment
		(start 111.491268 -36.362132)
		(end 111.491268 -36.588954)
		(width 0.1016)
		(layer "F.Cu")
		(net "M_B_DQ42")
	)
	(segment
		(start 113.215166 -35.959034)
		(end 111.894366 -35.959034)
		(width 0.1016)
		(layer "F.Cu")
		(net "M_B_DQ42")
	)
	(segment
		(start 178.449986 -8.967216)
		(end 178.49342 -8.923782)
		(width 0.1778)
		(layer "F.Cu")
		(net "M_B_DQ42")
	)
	(segment
		(start 178.34102 -7.824978)
		(end 178.2572 -7.824978)
		(width 0.1778)
		(layer "F.Cu")
		(net "M_B_DQ42")
	)
	(segment
		(start 115.824 -33.909)
		(end 115.2652 -33.909)
		(width 0.1016)
		(layer "F.Cu")
		(net "M_B_DQ42")
	)
	(segment
		(start 115.2652 -33.909)
		(end 113.215166 -35.959034)
		(width 0.1016)
		(layer "F.Cu")
		(net "M_B_DQ42")
	)
	(segment
		(start 178.49342 -7.977378)
		(end 178.34102 -7.824978)
		(width 0.1778)
		(layer "F.Cu")
		(net "M_B_DQ42")
	)
	(segment
		(start 178.449986 -9.897364)
		(end 178.449986 -8.967216)
		(width 0.1778)
		(layer "F.Cu")
		(net "M_B_DQ42")
	)
	(segment
		(start 178.49342 -8.923782)
		(end 178.49342 -7.977378)
		(width 0.1778)
		(layer "F.Cu")
		(net "M_B_DQ42")
	)
	(segment
		(start 111.894366 -35.959034)
		(end 111.491268 -36.362132)
		(width 0.1016)
		(layer "F.Cu")
		(net "M_B_DQ42")
	)
	(via
		(at 178.2572 -7.824978)
		(size 0.4318)
		(drill 0.2032)
		(layers "F.Cu" "B.Cu")
		(net "M_B_DQ42")
	)
	(via
		(at 115.824 -33.909)
		(size 0.4318)
		(drill 0.2032)
		(layers "F.Cu" "B.Cu")
		(net "M_B_DQ42")
	)
	(segment
		(start 178.150012 -9.89076)
		(end 178.150012 -9.113266)
		(width 0.1778)
		(layer "B.Cu")
		(net "M_B_DQ42")
	)
	(segment
		(start 178.47056 -8.792718)
		(end 178.47056 -8.038338)
		(width 0.1778)
		(layer "B.Cu")
		(net "M_B_DQ42")
	)
	(segment
		(start 178.47056 -8.038338)
		(end 178.2572 -7.824978)
		(width 0.1778)
		(layer "B.Cu")
		(net "M_B_DQ42")
	)
	(segment
		(start 178.150012 -9.113266)
		(end 178.47056 -8.792718)
		(width 0.1778)
		(layer "B.Cu")
		(net "M_B_DQ42")
	)
	(segment
		(start 165.030658 -21.6154)
		(end 166.5859 -21.6154)
		(width 0.1524)
		(layer "In2.Cu")
		(net "M_B_DQ42")
	)
	(segment
		(start 178.2064 -9.9949)
		(end 178.2064 -9.017)
		(width 0.1524)
		(layer "In2.Cu")
		(net "M_B_DQ42")
	)
	(segment
		(start 118.1354 -33.4772)
		(end 118.912386 -32.700214)
		(width 0.1016)
		(layer "In2.Cu")
		(net "M_B_DQ42")
	)
	(segment
		(start 158.565596 -28.28925)
		(end 158.775146 -28.498292)
		(width 0.1524)
		(layer "In2.Cu")
		(net "M_B_DQ42")
	)
	(segment
		(start 158.13405 -28.720288)
		(end 158.13405 -28.50515)
		(width 0.1524)
		(layer "In2.Cu")
		(net "M_B_DQ42")
	)
	(segment
		(start 158.127954 -29.360876)
		(end 158.343854 -29.144976)
		(width 0.1524)
		(layer "In2.Cu")
		(net "M_B_DQ42")
	)
	(segment
		(start 158.990538 -28.498292)
		(end 159.206438 -28.282392)
		(width 0.1524)
		(layer "In2.Cu")
		(net "M_B_DQ42")
	)
	(segment
		(start 115.824 -33.909)
		(end 116.2558 -33.4772)
		(width 0.1016)
		(layer "In2.Cu")
		(net "M_B_DQ42")
	)
	(segment
		(start 137.8966 -31.285434)
		(end 138.2014 -31.285434)
		(width 0.1524)
		(layer "In2.Cu")
		(net "M_B_DQ42")
	)
	(segment
		(start 154.305 -30.4292)
		(end 156.3878 -30.4292)
		(width 0.1524)
		(layer "In2.Cu")
		(net "M_B_DQ42")
	)
	(segment
		(start 159.085788 -27.94635)
		(end 159.085788 -27.731212)
		(width 0.1524)
		(layer "In2.Cu")
		(net "M_B_DQ42")
	)
	(segment
		(start 138.3538 -30.7086)
		(end 138.5062 -30.5562)
		(width 0.1524)
		(layer "In2.Cu")
		(net "M_B_DQ42")
	)
	(segment
		(start 178.4604 -8.763)
		(end 178.4604 -8.028178)
		(width 0.1524)
		(layer "In2.Cu")
		(net "M_B_DQ42")
	)
	(segment
		(start 157.791912 -29.24048)
		(end 157.912562 -29.360876)
		(width 0.1524)
		(layer "In2.Cu")
		(net "M_B_DQ42")
	)
	(segment
		(start 131.345178 -31.285434)
		(end 131.820412 -30.8102)
		(width 0.1524)
		(layer "In2.Cu")
		(net "M_B_DQ42")
	)
	(segment
		(start 178.2064 -9.017)
		(end 178.4604 -8.763)
		(width 0.1524)
		(layer "In2.Cu")
		(net "M_B_DQ42")
	)
	(segment
		(start 158.34995 -28.28925)
		(end 158.565596 -28.28925)
		(width 0.1524)
		(layer "In2.Cu")
		(net "M_B_DQ42")
	)
	(segment
		(start 138.5062 -30.5562)
		(end 150.1902 -30.5562)
		(width 0.1524)
		(layer "In2.Cu")
		(net "M_B_DQ42")
	)
	(segment
		(start 136.557766 -31.285434)
		(end 137.287 -30.5562)
		(width 0.1524)
		(layer "In2.Cu")
		(net "M_B_DQ42")
	)
	(segment
		(start 138.2014 -31.285434)
		(end 138.3538 -31.133034)
		(width 0.1524)
		(layer "In2.Cu")
		(net "M_B_DQ42")
	)
	(segment
		(start 132.6642 -30.8102)
		(end 133.139434 -31.285434)
		(width 0.1524)
		(layer "In2.Cu")
		(net "M_B_DQ42")
	)
	(segment
		(start 138.3538 -31.133034)
		(end 138.3538 -30.7086)
		(width 0.1524)
		(layer "In2.Cu")
		(net "M_B_DQ42")
	)
	(segment
		(start 118.912386 -32.700214)
		(end 129.930652 -32.700214)
		(width 0.1524)
		(layer "In2.Cu")
		(net "M_B_DQ42")
	)
	(segment
		(start 178.4604 -8.028178)
		(end 178.2572 -7.824978)
		(width 0.1524)
		(layer "In2.Cu")
		(net "M_B_DQ42")
	)
	(segment
		(start 157.57652 -29.24048)
		(end 157.791912 -29.24048)
		(width 0.1524)
		(layer "In2.Cu")
		(net "M_B_DQ42")
	)
	(segment
		(start 156.3878 -30.4292)
		(end 157.57652 -29.24048)
		(width 0.1524)
		(layer "In2.Cu")
		(net "M_B_DQ42")
	)
	(segment
		(start 158.13405 -28.50515)
		(end 158.34995 -28.28925)
		(width 0.1524)
		(layer "In2.Cu")
		(net "M_B_DQ42")
	)
	(segment
		(start 159.206438 -28.067)
		(end 159.085788 -27.94635)
		(width 0.1524)
		(layer "In2.Cu")
		(net "M_B_DQ42")
	)
	(segment
		(start 157.912562 -29.360876)
		(end 158.127954 -29.360876)
		(width 0.1524)
		(layer "In2.Cu")
		(net "M_B_DQ42")
	)
	(segment
		(start 129.930652 -32.700214)
		(end 131.345178 -31.285434)
		(width 0.1524)
		(layer "In2.Cu")
		(net "M_B_DQ42")
	)
	(segment
		(start 137.287 -30.5562)
		(end 137.5918 -30.5562)
		(width 0.1524)
		(layer "In2.Cu")
		(net "M_B_DQ42")
	)
	(segment
		(start 158.775146 -28.498292)
		(end 158.990538 -28.498292)
		(width 0.1524)
		(layer "In2.Cu")
		(net "M_B_DQ42")
	)
	(segment
		(start 153.8986 -30.8356)
		(end 154.305 -30.4292)
		(width 0.1524)
		(layer "In2.Cu")
		(net "M_B_DQ42")
	)
	(segment
		(start 133.139434 -31.285434)
		(end 136.557766 -31.285434)
		(width 0.1524)
		(layer "In2.Cu")
		(net "M_B_DQ42")
	)
	(segment
		(start 158.343854 -29.144976)
		(end 158.343854 -28.929584)
		(width 0.1524)
		(layer "In2.Cu")
		(net "M_B_DQ42")
	)
	(segment
		(start 137.7442 -30.7086)
		(end 137.7442 -31.133034)
		(width 0.1524)
		(layer "In2.Cu")
		(net "M_B_DQ42")
	)
	(segment
		(start 159.206438 -28.282392)
		(end 159.206438 -28.067)
		(width 0.1524)
		(layer "In2.Cu")
		(net "M_B_DQ42")
	)
	(segment
		(start 137.7442 -31.133034)
		(end 137.8966 -31.285434)
		(width 0.1524)
		(layer "In2.Cu")
		(net "M_B_DQ42")
	)
	(segment
		(start 137.5918 -30.5562)
		(end 137.7442 -30.7086)
		(width 0.1524)
		(layer "In2.Cu")
		(net "M_B_DQ42")
	)
	(segment
		(start 158.343854 -28.929584)
		(end 158.13405 -28.720288)
		(width 0.1524)
		(layer "In2.Cu")
		(net "M_B_DQ42")
	)
	(segment
		(start 163.592002 -23.224998)
		(end 163.592002 -23.054056)
		(width 0.1524)
		(layer "In2.Cu")
		(net "M_B_DQ42")
	)
	(segment
		(start 116.2558 -33.4772)
		(end 118.1354 -33.4772)
		(width 0.1016)
		(layer "In2.Cu")
		(net "M_B_DQ42")
	)
	(segment
		(start 150.4696 -30.8356)
		(end 153.8986 -30.8356)
		(width 0.1524)
		(layer "In2.Cu")
		(net "M_B_DQ42")
	)
	(segment
		(start 163.592002 -23.054056)
		(end 165.030658 -21.6154)
		(width 0.1524)
		(layer "In2.Cu")
		(net "M_B_DQ42")
	)
	(segment
		(start 150.1902 -30.5562)
		(end 150.4696 -30.8356)
		(width 0.1524)
		(layer "In2.Cu")
		(net "M_B_DQ42")
	)
	(segment
		(start 131.820412 -30.8102)
		(end 132.6642 -30.8102)
		(width 0.1524)
		(layer "In2.Cu")
		(net "M_B_DQ42")
	)
	(segment
		(start 166.5859 -21.6154)
		(end 178.2064 -9.9949)
		(width 0.1524)
		(layer "In2.Cu")
		(net "M_B_DQ42")
	)
	(segment
		(start 159.085788 -27.731212)
		(end 163.592002 -23.224998)
		(width 0.1524)
		(layer "In2.Cu")
		(net "M_B_DQ42")
	)
	(segment
		(start 19.685 -49.276)
		(end 19.685 -48.7172)
		(width 0.2032)
		(layer "F.Cu")
		(net "VR_PVCCP_FB_RC1")
	)
	(segment
		(start 19.685 -48.7172)
		(end 20.0406 -48.3616)
		(width 0.2032)
		(layer "F.Cu")
		(net "VR_PVCCP_FB_RC1")
	)
	(segment
		(start 19.685 -50.2666)
		(end 19.6596 -50.292)
		(width 0.2032)
		(layer "F.Cu")
		(net "VR_PVCCP_FB_RC1")
	)
	(segment
		(start 19.685 -49.276)
		(end 19.685 -50.2666)
		(width 0.2032)
		(layer "F.Cu")
		(net "VR_PVCCP_FB_RC1")
	)
	(segment
		(start 20.0406 -48.3616)
		(end 20.066 -48.3616)
		(width 0.2032)
		(layer "F.Cu")
		(net "VR_PVCCP_FB_RC1")
	)
	(via
		(at 20.066 -48.3616)
		(size 0.7112)
		(drill 0.3556)
		(layers "F.Cu" "B.Cu")
		(net "VR_PVCCP_FB_RC1")
	)
	(segment
		(start 105.440988 -26.319988)
		(end 105.514394 -26.393394)
		(width 0.1016)
		(layer "F.Cu")
		(net "M_B_DQS_DP8")
	)
	(segment
		(start 105.5497 -26.002488)
		(end 105.440988 -26.1112)
		(width 0.1016)
		(layer "F.Cu")
		(net "M_B_DQS_DP8")
	)
	(segment
		(start 105.7402 -23.324312)
		(end 105.7402 -25.073864)
		(width 0.1016)
		(layer "F.Cu")
		(net "M_B_DQS_DP8")
	)
	(segment
		(start 105.7402 -25.073864)
		(end 105.5497 -25.264364)
		(width 0.1016)
		(layer "F.Cu")
		(net "M_B_DQS_DP8")
	)
	(segment
		(start 153.549858 -1.68402)
		(end 153.549858 -2.436876)
		(width 0.1778)
		(layer "F.Cu")
		(net "M_B_DQS_DP8")
	)
	(segment
		(start 153.402284 -5.553456)
		(end 153.667206 -5.818378)
		(width 0.1778)
		(layer "F.Cu")
		(net "M_B_DQS_DP8")
	)
	(segment
		(start 105.514394 -26.393394)
		(end 105.717848 -26.393394)
		(width 0.1016)
		(layer "F.Cu")
		(net "M_B_DQS_DP8")
	)
	(segment
		(start 105.5497 -25.264364)
		(end 105.5497 -26.002488)
		(width 0.1016)
		(layer "F.Cu")
		(net "M_B_DQS_DP8")
	)
	(segment
		(start 105.339388 -22.9235)
		(end 105.7402 -23.324312)
		(width 0.1016)
		(layer "F.Cu")
		(net "M_B_DQS_DP8")
	)
	(segment
		(start 105.440988 -26.1112)
		(end 105.440988 -26.319988)
		(width 0.1016)
		(layer "F.Cu")
		(net "M_B_DQS_DP8")
	)
	(segment
		(start 153.549858 -2.436876)
		(end 153.402284 -2.58445)
		(width 0.1778)
		(layer "F.Cu")
		(net "M_B_DQS_DP8")
	)
	(segment
		(start 153.402284 -2.58445)
		(end 153.402284 -5.553456)
		(width 0.1778)
		(layer "F.Cu")
		(net "M_B_DQS_DP8")
	)
	(via
		(at 105.339388 -22.9235)
		(size 0.4318)
		(drill 0.2032)
		(layers "F.Cu" "B.Cu")
		(net "M_B_DQS_DP8")
	)
	(via
		(at 153.667206 -5.818378)
		(size 0.4318)
		(drill 0.2032)
		(layers "F.Cu" "B.Cu")
		(net "M_B_DQS_DP8")
	)
	(segment
		(start 153.402284 -6.0833)
		(end 153.667206 -5.818378)
		(width 0.1778)
		(layer "B.Cu")
		(net "M_B_DQS_DP8")
	)
	(segment
		(start 153.402284 -8.654034)
		(end 153.402284 -6.0833)
		(width 0.1778)
		(layer "B.Cu")
		(net "M_B_DQS_DP8")
	)
	(segment
		(start 153.549858 -9.89076)
		(end 153.549858 -8.801608)
		(width 0.1778)
		(layer "B.Cu")
		(net "M_B_DQS_DP8")
	)
	(segment
		(start 153.549858 -8.801608)
		(end 153.402284 -8.654034)
		(width 0.1778)
		(layer "B.Cu")
		(net "M_B_DQS_DP8")
	)
	(segment
		(start 152.732486 -7.570978)
		(end 152.732486 -7.394956)
		(width 0.1524)
		(layer "In2.Cu")
		(net "M_B_DQS_DP8")
	)
	(segment
		(start 152.11806 -14.217904)
		(end 152.11806 -13.760704)
		(width 0.1524)
		(layer "In2.Cu")
		(net "M_B_DQS_DP8")
	)
	(segment
		(start 105.339388 -22.58314)
		(end 105.339388 -22.9235)
		(width 0.1016)
		(layer "In2.Cu")
		(net "M_B_DQS_DP8")
	)
	(segment
		(start 152.11806 -12.55014)
		(end 151.9936 -12.42568)
		(width 0.1524)
		(layer "In2.Cu")
		(net "M_B_DQS_DP8")
	)
	(segment
		(start 152.11806 -11.38682)
		(end 151.9936 -11.26236)
		(width 0.1524)
		(layer "In2.Cu")
		(net "M_B_DQS_DP8")
	)
	(segment
		(start 152.11806 -15.429992)
		(end 151.9936 -15.305532)
		(width 0.1524)
		(layer "In2.Cu")
		(net "M_B_DQS_DP8")
	)
	(segment
		(start 111.393224 -21.8694)
		(end 112.028224 -21.8694)
		(width 0.1524)
		(layer "In2.Cu")
		(net "M_B_DQS_DP8")
	)
	(segment
		(start 152.11806 -11.84402)
		(end 152.11806 -11.38682)
		(width 0.1524)
		(layer "In2.Cu")
		(net "M_B_DQS_DP8")
	)
	(segment
		(start 152.409144 -7.89432)
		(end 152.732486 -7.570978)
		(width 0.1524)
		(layer "In2.Cu")
		(net "M_B_DQS_DP8")
	)
	(segment
		(start 152.11806 -10.6807)
		(end 152.11806 -10.2235)
		(width 0.1524)
		(layer "In2.Cu")
		(net "M_B_DQS_DP8")
	)
	(segment
		(start 110.885224 -22.0472)
		(end 110.859824 -22.0218)
		(width 0.1016)
		(layer "In2.Cu")
		(net "M_B_DQS_DP8")
	)
	(segment
		(start 110.859824 -22.0218)
		(end 105.900728 -22.0218)
		(width 0.1016)
		(layer "In2.Cu")
		(net "M_B_DQS_DP8")
	)
	(segment
		(start 151.9936 -16.894556)
		(end 151.9936 -16.011652)
		(width 0.1524)
		(layer "In2.Cu")
		(net "M_B_DQS_DP8")
	)
	(segment
		(start 113.8936 -21.8694)
		(end 123.267978 -21.8694)
		(width 0.1524)
		(layer "In2.Cu")
		(net "M_B_DQS_DP8")
	)
	(segment
		(start 151.9936 -10.09904)
		(end 151.9936 -8.133842)
		(width 0.1524)
		(layer "In2.Cu")
		(net "M_B_DQS_DP8")
	)
	(segment
		(start 110.885224 -22.0472)
		(end 111.215424 -22.0472)
		(width 0.1524)
		(layer "In2.Cu")
		(net "M_B_DQS_DP8")
	)
	(segment
		(start 152.11806 -17.476216)
		(end 152.11806 -17.019016)
		(width 0.1524)
		(layer "In2.Cu")
		(net "M_B_DQS_DP8")
	)
	(segment
		(start 152.233122 -7.89432)
		(end 152.409144 -7.89432)
		(width 0.1524)
		(layer "In2.Cu")
		(net "M_B_DQS_DP8")
	)
	(segment
		(start 151.9936 -15.305532)
		(end 151.9936 -14.342364)
		(width 0.1524)
		(layer "In2.Cu")
		(net "M_B_DQS_DP8")
	)
	(segment
		(start 151.9936 -18.057876)
		(end 151.9936 -17.600676)
		(width 0.1524)
		(layer "In2.Cu")
		(net "M_B_DQS_DP8")
	)
	(segment
		(start 151.9936 -13.1318)
		(end 152.11806 -13.00734)
		(width 0.1524)
		(layer "In2.Cu")
		(net "M_B_DQS_DP8")
	)
	(segment
		(start 112.028224 -21.8694)
		(end 112.688624 -21.209)
		(width 0.1524)
		(layer "In2.Cu")
		(net "M_B_DQS_DP8")
	)
	(segment
		(start 151.9936 -8.133842)
		(end 152.233122 -7.89432)
		(width 0.1524)
		(layer "In2.Cu")
		(net "M_B_DQS_DP8")
	)
	(segment
		(start 125.426978 -19.7104)
		(end 150.341076 -19.7104)
		(width 0.1524)
		(layer "In2.Cu")
		(net "M_B_DQS_DP8")
	)
	(segment
		(start 151.9936 -12.42568)
		(end 151.9936 -11.96848)
		(width 0.1524)
		(layer "In2.Cu")
		(net "M_B_DQS_DP8")
	)
	(segment
		(start 152.11806 -13.760704)
		(end 151.9936 -13.636244)
		(width 0.1524)
		(layer "In2.Cu")
		(net "M_B_DQS_DP8")
	)
	(segment
		(start 151.9936 -11.96848)
		(end 152.11806 -11.84402)
		(width 0.1524)
		(layer "In2.Cu")
		(net "M_B_DQS_DP8")
	)
	(segment
		(start 152.11806 -17.019016)
		(end 151.9936 -16.894556)
		(width 0.1524)
		(layer "In2.Cu")
		(net "M_B_DQS_DP8")
	)
	(segment
		(start 153.389838 -6.737604)
		(end 153.389838 -6.095746)
		(width 0.1524)
		(layer "In2.Cu")
		(net "M_B_DQS_DP8")
	)
	(segment
		(start 111.215424 -22.0472)
		(end 111.393224 -21.8694)
		(width 0.1524)
		(layer "In2.Cu")
		(net "M_B_DQS_DP8")
	)
	(segment
		(start 152.11806 -13.00734)
		(end 152.11806 -12.55014)
		(width 0.1524)
		(layer "In2.Cu")
		(net "M_B_DQS_DP8")
	)
	(segment
		(start 112.688624 -21.209)
		(end 113.2332 -21.209)
		(width 0.1524)
		(layer "In2.Cu")
		(net "M_B_DQS_DP8")
	)
	(segment
		(start 151.9936 -16.011652)
		(end 152.11806 -15.887192)
		(width 0.1524)
		(layer "In2.Cu")
		(net "M_B_DQS_DP8")
	)
	(segment
		(start 150.341076 -19.7104)
		(end 151.9936 -18.057876)
		(width 0.1524)
		(layer "In2.Cu")
		(net "M_B_DQS_DP8")
	)
	(segment
		(start 105.900728 -22.0218)
		(end 105.339388 -22.58314)
		(width 0.1016)
		(layer "In2.Cu")
		(net "M_B_DQS_DP8")
	)
	(segment
		(start 151.9936 -11.26236)
		(end 151.9936 -10.80516)
		(width 0.1524)
		(layer "In2.Cu")
		(net "M_B_DQS_DP8")
	)
	(segment
		(start 152.11806 -15.887192)
		(end 152.11806 -15.429992)
		(width 0.1524)
		(layer "In2.Cu")
		(net "M_B_DQS_DP8")
	)
	(segment
		(start 151.9936 -10.80516)
		(end 152.11806 -10.6807)
		(width 0.1524)
		(layer "In2.Cu")
		(net "M_B_DQS_DP8")
	)
	(segment
		(start 151.9936 -13.636244)
		(end 151.9936 -13.1318)
		(width 0.1524)
		(layer "In2.Cu")
		(net "M_B_DQS_DP8")
	)
	(segment
		(start 151.9936 -17.600676)
		(end 152.11806 -17.476216)
		(width 0.1524)
		(layer "In2.Cu")
		(net "M_B_DQS_DP8")
	)
	(segment
		(start 113.2332 -21.209)
		(end 113.8936 -21.8694)
		(width 0.1524)
		(layer "In2.Cu")
		(net "M_B_DQS_DP8")
	)
	(segment
		(start 151.9936 -14.342364)
		(end 152.11806 -14.217904)
		(width 0.1524)
		(layer "In2.Cu")
		(net "M_B_DQS_DP8")
	)
	(segment
		(start 152.732486 -7.394956)
		(end 153.389838 -6.737604)
		(width 0.1524)
		(layer "In2.Cu")
		(net "M_B_DQS_DP8")
	)
	(segment
		(start 152.11806 -10.2235)
		(end 151.9936 -10.09904)
		(width 0.1524)
		(layer "In2.Cu")
		(net "M_B_DQS_DP8")
	)
	(segment
		(start 153.389838 -6.095746)
		(end 153.667206 -5.818378)
		(width 0.1524)
		(layer "In2.Cu")
		(net "M_B_DQS_DP8")
	)
	(segment
		(start 123.267978 -21.8694)
		(end 125.426978 -19.7104)
		(width 0.1524)
		(layer "In2.Cu")
		(net "M_B_DQS_DP8")
	)
	(segment
		(start 20.3708 -66.7512)
		(end 21.1328 -66.7512)
		(width 0.2032)
		(layer "F.Cu")
		(net "VR_PVNN_ISUMN")
	)
	(segment
		(start 17.8054 -66.6496)
		(end 17.8308 -66.675)
		(width 0.2032)
		(layer "F.Cu")
		(net "VR_PVNN_ISUMN")
	)
	(segment
		(start 19.5834 -66.7004)
		(end 18.717514 -66.7004)
		(width 0.2032)
		(layer "F.Cu")
		(net "VR_PVNN_ISUMN")
	)
	(segment
		(start 17.8308 -66.675)
		(end 18.692114 -66.675)
		(width 0.2032)
		(layer "F.Cu")
		(net "VR_PVNN_ISUMN")
	)
	(segment
		(start 21.8948 -66.421)
		(end 21.8948 -65.659)
		(width 0.2032)
		(layer "F.Cu")
		(net "VR_PVNN_ISUMN")
	)
	(segment
		(start 21.5646 -66.7512)
		(end 21.8948 -66.421)
		(width 0.2032)
		(layer "F.Cu")
		(net "VR_PVNN_ISUMN")
	)
	(segment
		(start 19.5834 -66.7004)
		(end 20.32 -66.7004)
		(width 0.2032)
		(layer "F.Cu")
		(net "VR_PVNN_ISUMN")
	)
	(segment
		(start 17.8054 -65.8622)
		(end 17.8054 -66.6496)
		(width 0.2032)
		(layer "F.Cu")
		(net "VR_PVNN_ISUMN")
	)
	(segment
		(start 18.692114 -66.675)
		(end 18.6944 -66.677286)
		(width 0.2032)
		(layer "F.Cu")
		(net "VR_PVNN_ISUMN")
	)
	(segment
		(start 21.1328 -66.7512)
		(end 21.5646 -66.7512)
		(width 0.2032)
		(layer "F.Cu")
		(net "VR_PVNN_ISUMN")
	)
	(segment
		(start 20.32 -66.7004)
		(end 20.3708 -66.7512)
		(width 0.2032)
		(layer "F.Cu")
		(net "VR_PVNN_ISUMN")
	)
	(segment
		(start 18.717514 -66.7004)
		(end 18.6944 -66.677286)
		(width 0.2032)
		(layer "F.Cu")
		(net "VR_PVNN_ISUMN")
	)
	(segment
		(start 21.8948 -65.659)
		(end 21.9456 -65.6082)
		(width 0.2032)
		(layer "F.Cu")
		(net "VR_PVNN_ISUMN")
	)
	(via
		(at 17.8054 -65.8622)
		(size 0.7112)
		(drill 0.3556)
		(layers "F.Cu" "B.Cu")
		(net "VR_PVNN_ISUMN")
	)
	(segment
		(start 105.664 -34.539682)
		(end 105.664 -34.717482)
		(width 0.1016)
		(layer "F.Cu")
		(net "M_B_DQ48")
	)
	(segment
		(start 180.24983 -9.897364)
		(end 180.24983 -7.912608)
		(width 0.1778)
		(layer "F.Cu")
		(net "M_B_DQ48")
	)
	(segment
		(start 180.24983 -7.912608)
		(end 180.0606 -7.723378)
		(width 0.1778)
		(layer "F.Cu")
		(net "M_B_DQ48")
	)
	(segment
		(start 105.664 -34.717482)
		(end 105.385108 -34.996374)
		(width 0.1016)
		(layer "F.Cu")
		(net "M_B_DQ48")
	)
	(via
		(at 180.0606 -7.723378)
		(size 0.4318)
		(drill 0.2032)
		(layers "F.Cu" "B.Cu")
		(net "M_B_DQ48")
	)
	(via
		(at 105.664 -34.539682)
		(size 0.4318)
		(drill 0.2032)
		(layers "F.Cu" "B.Cu")
		(net "M_B_DQ48")
	)
	(segment
		(start 179.949856 -9.099042)
		(end 180.14696 -8.901938)
		(width 0.1778)
		(layer "B.Cu")
		(net "M_B_DQ48")
	)
	(segment
		(start 180.14696 -7.809738)
		(end 180.0606 -7.723378)
		(width 0.1778)
		(layer "B.Cu")
		(net "M_B_DQ48")
	)
	(segment
		(start 179.949856 -9.89076)
		(end 179.949856 -9.099042)
		(width 0.1778)
		(layer "B.Cu")
		(net "M_B_DQ48")
	)
	(segment
		(start 180.14696 -8.901938)
		(end 180.14696 -7.809738)
		(width 0.1778)
		(layer "B.Cu")
		(net "M_B_DQ48")
	)
	(segment
		(start 148.8694 -34.671)
		(end 148.7424 -34.544)
		(width 0.1524)
		(layer "In9.Cu")
		(net "M_B_DQ48")
	)
	(segment
		(start 124.08027 -35.0012)
		(end 124.08027 -35.5854)
		(width 0.1524)
		(layer "In9.Cu")
		(net "M_B_DQ48")
	)
	(segment
		(start 124.08027 -35.5854)
		(end 123.92787 -35.7378)
		(width 0.1524)
		(layer "In9.Cu")
		(net "M_B_DQ48")
	)
	(segment
		(start 124.68987 -35.0012)
		(end 124.53747 -34.8488)
		(width 0.1524)
		(layer "In9.Cu")
		(net "M_B_DQ48")
	)
	(segment
		(start 149.2758 -34.671)
		(end 148.8694 -34.671)
		(width 0.1524)
		(layer "In9.Cu")
		(net "M_B_DQ48")
	)
	(segment
		(start 125.29947 -35.5854)
		(end 125.14707 -35.7378)
		(width 0.1524)
		(layer "In9.Cu")
		(net "M_B_DQ48")
	)
	(segment
		(start 110.8202 -35.0012)
		(end 110.617 -35.0012)
		(width 0.1016)
		(layer "In9.Cu")
		(net "M_B_DQ48")
	)
	(segment
		(start 123.47067 -35.5854)
		(end 123.47067 -35.0012)
		(width 0.1524)
		(layer "In9.Cu")
		(net "M_B_DQ48")
	)
	(segment
		(start 131.0894 -34.7218)
		(end 130.0734 -35.7378)
		(width 0.1524)
		(layer "In9.Cu")
		(net "M_B_DQ48")
	)
	(segment
		(start 122.40387 -35.7378)
		(end 122.25147 -35.5854)
		(width 0.1524)
		(layer "In9.Cu")
		(net "M_B_DQ48")
	)
	(segment
		(start 158.267908 -34.7218)
		(end 150.1394 -34.7218)
		(width 0.1524)
		(layer "In9.Cu")
		(net "M_B_DQ48")
	)
	(segment
		(start 149.5552 -34.2138)
		(end 149.4028 -34.3662)
		(width 0.1524)
		(layer "In9.Cu")
		(net "M_B_DQ48")
	)
	(segment
		(start 107.7468 -34.7472)
		(end 107.2134 -34.2138)
		(width 0.1016)
		(layer "In9.Cu")
		(net "M_B_DQ48")
	)
	(segment
		(start 150.1394 -34.7218)
		(end 150.0124 -34.5948)
		(width 0.1524)
		(layer "In9.Cu")
		(net "M_B_DQ48")
	)
	(segment
		(start 123.62307 -35.7378)
		(end 123.47067 -35.5854)
		(width 0.1524)
		(layer "In9.Cu")
		(net "M_B_DQ48")
	)
	(segment
		(start 148.7424 -34.544)
		(end 148.7424 -34.3662)
		(width 0.1524)
		(layer "In9.Cu")
		(net "M_B_DQ48")
	)
	(segment
		(start 109.6772 -34.3662)
		(end 109.2962 -34.7472)
		(width 0.1016)
		(layer "In9.Cu")
		(net "M_B_DQ48")
	)
	(segment
		(start 146.290538 -34.2138)
		(end 145.8722 -33.795462)
		(width 0.1524)
		(layer "In9.Cu")
		(net "M_B_DQ48")
	)
	(segment
		(start 126.06147 -35.7378)
		(end 125.90907 -35.5854)
		(width 0.1524)
		(layer "In9.Cu")
		(net "M_B_DQ48")
	)
	(segment
		(start 124.84227 -35.7378)
		(end 124.68987 -35.5854)
		(width 0.1524)
		(layer "In9.Cu")
		(net "M_B_DQ48")
	)
	(segment
		(start 125.90907 -35.5854)
		(end 125.90907 -35.1536)
		(width 0.1524)
		(layer "In9.Cu")
		(net "M_B_DQ48")
	)
	(segment
		(start 105.989882 -34.2138)
		(end 105.664 -34.539682)
		(width 0.1016)
		(layer "In9.Cu")
		(net "M_B_DQ48")
	)
	(segment
		(start 122.09907 -35.1028)
		(end 121.79427 -35.1028)
		(width 0.1524)
		(layer "In9.Cu")
		(net "M_B_DQ48")
	)
	(segment
		(start 125.14707 -35.7378)
		(end 124.84227 -35.7378)
		(width 0.1524)
		(layer "In9.Cu")
		(net "M_B_DQ48")
	)
	(segment
		(start 122.70867 -35.7378)
		(end 122.40387 -35.7378)
		(width 0.1524)
		(layer "In9.Cu")
		(net "M_B_DQ48")
	)
	(segment
		(start 109.2962 -34.7472)
		(end 107.7468 -34.7472)
		(width 0.1016)
		(layer "In9.Cu")
		(net "M_B_DQ48")
	)
	(segment
		(start 180.14696 -9.63422)
		(end 177.5206 -12.26058)
		(width 0.1524)
		(layer "In9.Cu")
		(net "M_B_DQ48")
	)
	(segment
		(start 124.68987 -35.5854)
		(end 124.68987 -35.0012)
		(width 0.1524)
		(layer "In9.Cu")
		(net "M_B_DQ48")
	)
	(segment
		(start 147.5232 -34.3662)
		(end 147.3708 -34.2138)
		(width 0.1524)
		(layer "In9.Cu")
		(net "M_B_DQ48")
	)
	(segment
		(start 124.53747 -34.8488)
		(end 124.23267 -34.8488)
		(width 0.1524)
		(layer "In9.Cu")
		(net "M_B_DQ48")
	)
	(segment
		(start 122.86107 -35.5854)
		(end 122.70867 -35.7378)
		(width 0.1524)
		(layer "In9.Cu")
		(net "M_B_DQ48")
	)
	(segment
		(start 121.64187 -35.5854)
		(end 121.48947 -35.7378)
		(width 0.1524)
		(layer "In9.Cu")
		(net "M_B_DQ48")
	)
	(segment
		(start 125.45187 -35.0012)
		(end 125.29947 -35.1536)
		(width 0.1524)
		(layer "In9.Cu")
		(net "M_B_DQ48")
	)
	(segment
		(start 114.3 -35.7378)
		(end 113.5634 -35.0012)
		(width 0.1524)
		(layer "In9.Cu")
		(net "M_B_DQ48")
	)
	(segment
		(start 124.23267 -34.8488)
		(end 124.08027 -35.0012)
		(width 0.1524)
		(layer "In9.Cu")
		(net "M_B_DQ48")
	)
	(segment
		(start 107.2134 -34.2138)
		(end 105.989882 -34.2138)
		(width 0.1016)
		(layer "In9.Cu")
		(net "M_B_DQ48")
	)
	(segment
		(start 180.0606 -7.723378)
		(end 180.14696 -7.809738)
		(width 0.1524)
		(layer "In9.Cu")
		(net "M_B_DQ48")
	)
	(segment
		(start 139.5222 -34.7218)
		(end 131.0894 -34.7218)
		(width 0.1524)
		(layer "In9.Cu")
		(net "M_B_DQ48")
	)
	(segment
		(start 113.5634 -35.0012)
		(end 110.8202 -35.0012)
		(width 0.1524)
		(layer "In9.Cu")
		(net "M_B_DQ48")
	)
	(segment
		(start 149.86 -34.2138)
		(end 149.5552 -34.2138)
		(width 0.1524)
		(layer "In9.Cu")
		(net "M_B_DQ48")
	)
	(segment
		(start 121.64187 -35.2552)
		(end 121.64187 -35.5854)
		(width 0.1524)
		(layer "In9.Cu")
		(net "M_B_DQ48")
	)
	(segment
		(start 123.92787 -35.7378)
		(end 123.62307 -35.7378)
		(width 0.1524)
		(layer "In9.Cu")
		(net "M_B_DQ48")
	)
	(segment
		(start 145.8722 -33.795462)
		(end 139.827 -33.795462)
		(width 0.1524)
		(layer "In9.Cu")
		(net "M_B_DQ48")
	)
	(segment
		(start 149.4028 -34.544)
		(end 149.2758 -34.671)
		(width 0.1524)
		(layer "In9.Cu")
		(net "M_B_DQ48")
	)
	(segment
		(start 148.59 -34.2138)
		(end 148.2852 -34.2138)
		(width 0.1524)
		(layer "In9.Cu")
		(net "M_B_DQ48")
	)
	(segment
		(start 139.827 -33.795462)
		(end 139.6746 -33.947862)
		(width 0.1524)
		(layer "In9.Cu")
		(net "M_B_DQ48")
	)
	(segment
		(start 177.5206 -15.469108)
		(end 158.267908 -34.7218)
		(width 0.1524)
		(layer "In9.Cu")
		(net "M_B_DQ48")
	)
	(segment
		(start 125.75667 -35.0012)
		(end 125.45187 -35.0012)
		(width 0.1524)
		(layer "In9.Cu")
		(net "M_B_DQ48")
	)
	(segment
		(start 177.5206 -12.26058)
		(end 177.5206 -15.469108)
		(width 0.1524)
		(layer "In9.Cu")
		(net "M_B_DQ48")
	)
	(segment
		(start 125.29947 -35.1536)
		(end 125.29947 -35.5854)
		(width 0.1524)
		(layer "In9.Cu")
		(net "M_B_DQ48")
	)
	(segment
		(start 150.0124 -34.3662)
		(end 149.86 -34.2138)
		(width 0.1524)
		(layer "In9.Cu")
		(net "M_B_DQ48")
	)
	(segment
		(start 139.6746 -33.947862)
		(end 139.6746 -34.5694)
		(width 0.1524)
		(layer "In9.Cu")
		(net "M_B_DQ48")
	)
	(segment
		(start 110.617 -35.0012)
		(end 109.982 -34.3662)
		(width 0.1016)
		(layer "In9.Cu")
		(net "M_B_DQ48")
	)
	(segment
		(start 123.31827 -34.8488)
		(end 123.01347 -34.8488)
		(width 0.1524)
		(layer "In9.Cu")
		(net "M_B_DQ48")
	)
	(segment
		(start 148.7424 -34.3662)
		(end 148.59 -34.2138)
		(width 0.1524)
		(layer "In9.Cu")
		(net "M_B_DQ48")
	)
	(segment
		(start 148.2852 -34.2138)
		(end 148.1328 -34.3662)
		(width 0.1524)
		(layer "In9.Cu")
		(net "M_B_DQ48")
	)
	(segment
		(start 148.1328 -34.3662)
		(end 147.5232 -34.3662)
		(width 0.1524)
		(layer "In9.Cu")
		(net "M_B_DQ48")
	)
	(segment
		(start 109.982 -34.3662)
		(end 109.6772 -34.3662)
		(width 0.1016)
		(layer "In9.Cu")
		(net "M_B_DQ48")
	)
	(segment
		(start 121.79427 -35.1028)
		(end 121.64187 -35.2552)
		(width 0.1524)
		(layer "In9.Cu")
		(net "M_B_DQ48")
	)
	(segment
		(start 123.47067 -35.0012)
		(end 123.31827 -34.8488)
		(width 0.1524)
		(layer "In9.Cu")
		(net "M_B_DQ48")
	)
	(segment
		(start 122.25147 -35.2552)
		(end 122.09907 -35.1028)
		(width 0.1524)
		(layer "In9.Cu")
		(net "M_B_DQ48")
	)
	(segment
		(start 122.86107 -35.0012)
		(end 122.86107 -35.5854)
		(width 0.1524)
		(layer "In9.Cu")
		(net "M_B_DQ48")
	)
	(segment
		(start 180.14696 -7.809738)
		(end 180.14696 -9.63422)
		(width 0.1524)
		(layer "In9.Cu")
		(net "M_B_DQ48")
	)
	(segment
		(start 123.01347 -34.8488)
		(end 122.86107 -35.0012)
		(width 0.1524)
		(layer "In9.Cu")
		(net "M_B_DQ48")
	)
	(segment
		(start 122.25147 -35.5854)
		(end 122.25147 -35.2552)
		(width 0.1524)
		(layer "In9.Cu")
		(net "M_B_DQ48")
	)
	(segment
		(start 149.4028 -34.3662)
		(end 149.4028 -34.544)
		(width 0.1524)
		(layer "In9.Cu")
		(net "M_B_DQ48")
	)
	(segment
		(start 121.48947 -35.7378)
		(end 114.3 -35.7378)
		(width 0.1524)
		(layer "In9.Cu")
		(net "M_B_DQ48")
	)
	(segment
		(start 125.90907 -35.1536)
		(end 125.75667 -35.0012)
		(width 0.1524)
		(layer "In9.Cu")
		(net "M_B_DQ48")
	)
	(segment
		(start 139.6746 -34.5694)
		(end 139.5222 -34.7218)
		(width 0.1524)
		(layer "In9.Cu")
		(net "M_B_DQ48")
	)
	(segment
		(start 130.0734 -35.7378)
		(end 126.06147 -35.7378)
		(width 0.1524)
		(layer "In9.Cu")
		(net "M_B_DQ48")
	)
	(segment
		(start 150.0124 -34.5948)
		(end 150.0124 -34.3662)
		(width 0.1524)
		(layer "In9.Cu")
		(net "M_B_DQ48")
	)
	(segment
		(start 147.3708 -34.2138)
		(end 146.290538 -34.2138)
		(width 0.1524)
		(layer "In9.Cu")
		(net "M_B_DQ48")
	)
	(segment
		(start 87.035386 -34.757614)
		(end 86.684104 -35.108896)
		(width 0.1143)
		(layer "F.Cu")
		(net "SPI_MOSI_GBE")
	)
	(segment
		(start 61.0362 -17.0688)
		(end 61.715396 -17.0688)
		(width 0.1143)
		(layer "F.Cu")
		(net "SPI_MOSI_GBE")
	)
	(segment
		(start 60.9854 -17.018)
		(end 61.0362 -17.0688)
		(width 0.1143)
		(layer "F.Cu")
		(net "SPI_MOSI_GBE")
	)
	(segment
		(start 87.076788 -34.757614)
		(end 87.035386 -34.757614)
		(width 0.1143)
		(layer "F.Cu")
		(net "SPI_MOSI_GBE")
	)
	(segment
		(start 61.715396 -17.0688)
		(end 61.908944 -16.875252)
		(width 0.1143)
		(layer "F.Cu")
		(net "SPI_MOSI_GBE")
	)
	(segment
		(start 60.2488 -17.018)
		(end 60.9854 -17.018)
		(width 0.1143)
		(layer "F.Cu")
		(net "SPI_MOSI_GBE")
	)
	(segment
		(start 86.684104 -35.108896)
		(end 86.700868 -35.108896)
		(width 0.1143)
		(layer "F.Cu")
		(net "SPI_MOSI_GBE")
	)
	(via
		(at 61.908944 -16.875252)
		(size 0.7112)
		(drill 0.3556)
		(layers "F.Cu" "B.Cu")
		(net "SPI_MOSI_GBE")
	)
	(via
		(at 86.700868 -35.108896)
		(size 0.4318)
		(drill 0.2032)
		(layers "F.Cu" "B.Cu")
		(net "SPI_MOSI_GBE")
	)
	(via
		(at 61.0362 -17.0688)
		(size 0.508)
		(drill 0.254)
		(layers "F.Cu" "B.Cu")
		(net "SPI_MOSI_GBE")
	)
	(segment
		(start 76.529946 -30.423358)
		(end 79.063088 -32.9565)
		(width 0.0889)
		(layer "In7.Cu")
		(net "SPI_MOSI_GBE")
	)
	(segment
		(start 60.7695 -18.5039)
		(end 64.6176 -22.352)
		(width 0.0889)
		(layer "In7.Cu")
		(net "SPI_MOSI_GBE")
	)
	(segment
		(start 82.58937 -33.598358)
		(end 82.889598 -33.598358)
		(width 0.0889)
		(layer "In7.Cu")
		(net "SPI_MOSI_GBE")
	)
	(segment
		(start 82.889598 -33.598358)
		(end 83.074002 -33.782762)
		(width 0.0889)
		(layer "In7.Cu")
		(net "SPI_MOSI_GBE")
	)
	(segment
		(start 83.074002 -33.782762)
		(end 85.771482 -33.782762)
		(width 0.0889)
		(layer "In7.Cu")
		(net "SPI_MOSI_GBE")
	)
	(segment
		(start 85.771482 -33.782762)
		(end 86.297516 -34.308796)
		(width 0.0889)
		(layer "In7.Cu")
		(net "SPI_MOSI_GBE")
	)
	(segment
		(start 79.5655 -32.9565)
		(end 80.315562 -33.706562)
		(width 0.0889)
		(layer "In7.Cu")
		(net "SPI_MOSI_GBE")
	)
	(segment
		(start 79.063088 -32.9565)
		(end 79.5655 -32.9565)
		(width 0.0889)
		(layer "In7.Cu")
		(net "SPI_MOSI_GBE")
	)
	(segment
		(start 61.0362 -17.0688)
		(end 60.7695 -17.3355)
		(width 0.0889)
		(layer "In7.Cu")
		(net "SPI_MOSI_GBE")
	)
	(segment
		(start 64.6176 -22.352)
		(end 66.586354 -22.352)
		(width 0.0889)
		(layer "In7.Cu")
		(net "SPI_MOSI_GBE")
	)
	(segment
		(start 86.297516 -34.705544)
		(end 86.700868 -35.108896)
		(width 0.0889)
		(layer "In7.Cu")
		(net "SPI_MOSI_GBE")
	)
	(segment
		(start 71.253604 -27.01925)
		(end 74.710036 -27.01925)
		(width 0.0889)
		(layer "In7.Cu")
		(net "SPI_MOSI_GBE")
	)
	(segment
		(start 66.586354 -22.352)
		(end 71.253604 -27.01925)
		(width 0.0889)
		(layer "In7.Cu")
		(net "SPI_MOSI_GBE")
	)
	(segment
		(start 76.529946 -28.83916)
		(end 76.529946 -30.423358)
		(width 0.0889)
		(layer "In7.Cu")
		(net "SPI_MOSI_GBE")
	)
	(segment
		(start 86.297516 -34.308796)
		(end 86.297516 -34.705544)
		(width 0.0889)
		(layer "In7.Cu")
		(net "SPI_MOSI_GBE")
	)
	(segment
		(start 74.710036 -27.01925)
		(end 76.529946 -28.83916)
		(width 0.0889)
		(layer "In7.Cu")
		(net "SPI_MOSI_GBE")
	)
	(segment
		(start 60.7695 -17.3355)
		(end 60.7695 -18.5039)
		(width 0.0889)
		(layer "In7.Cu")
		(net "SPI_MOSI_GBE")
	)
	(segment
		(start 82.481166 -33.706562)
		(end 82.58937 -33.598358)
		(width 0.0889)
		(layer "In7.Cu")
		(net "SPI_MOSI_GBE")
	)
	(segment
		(start 80.315562 -33.706562)
		(end 82.481166 -33.706562)
		(width 0.0889)
		(layer "In7.Cu")
		(net "SPI_MOSI_GBE")
	)
	(segment
		(start 21.252942 -49.276)
		(end 20.81784 -49.711102)
		(width 0.2032)
		(layer "F.Cu")
		(net "VR_PVCCP_ISEN1")
	)
	(segment
		(start 21.2598 -49.276)
		(end 21.252942 -49.276)
		(width 0.2032)
		(layer "F.Cu")
		(net "VR_PVCCP_ISEN1")
	)
	(segment
		(start 20.81784 -49.711102)
		(end 20.81784 -50.732436)
		(width 0.2032)
		(layer "F.Cu")
		(net "VR_PVCCP_ISEN1")
	)
	(segment
		(start 20.81784 -51.29784)
		(end 20.81784 -50.732436)
		(width 0.2032)
		(layer "F.Cu")
		(net "VR_PVCCP_ISEN1")
	)
	(segment
		(start 21.1836 -51.6636)
		(end 20.81784 -51.29784)
		(width 0.2032)
		(layer "F.Cu")
		(net "VR_PVCCP_ISEN1")
	)
	(via
		(at 20.81784 -50.732436)
		(size 0.7112)
		(drill 0.3556)
		(layers "F.Cu" "B.Cu")
		(net "VR_PVCCP_ISEN1")
	)
	(segment
		(start 105.3465 -24.924512)
		(end 105.313988 -24.892)
		(width 0.1016)
		(layer "F.Cu")
		(net "M_B_DQS_DN8")
	)
	(segment
		(start 153.097484 -2.549906)
		(end 153.097484 -5.55371)
		(width 0.1778)
		(layer "F.Cu")
		(net "M_B_DQS_DN8")
	)
	(segment
		(start 105.639108 -27.447494)
		(end 105.237788 -26.3652)
		(width 0.1016)
		(layer "F.Cu")
		(net "M_B_DQS_DN8")
	)
	(segment
		(start 105.3465 -25.91816)
		(end 105.3465 -24.924512)
		(width 0.1016)
		(layer "F.Cu")
		(net "M_B_DQS_DN8")
	)
	(segment
		(start 105.237788 -26.026872)
		(end 105.3465 -25.91816)
		(width 0.1016)
		(layer "F.Cu")
		(net "M_B_DQS_DN8")
	)
	(segment
		(start 152.94991 -2.402332)
		(end 153.097484 -2.549906)
		(width 0.1778)
		(layer "F.Cu")
		(net "M_B_DQS_DN8")
	)
	(segment
		(start 105.237788 -26.3652)
		(end 105.237788 -26.026872)
		(width 0.1016)
		(layer "F.Cu")
		(net "M_B_DQS_DN8")
	)
	(segment
		(start 152.94991 -1.68402)
		(end 152.94991 -2.402332)
		(width 0.1778)
		(layer "F.Cu")
		(net "M_B_DQS_DN8")
	)
	(segment
		(start 153.097484 -5.55371)
		(end 152.832816 -5.818378)
		(width 0.1778)
		(layer "F.Cu")
		(net "M_B_DQS_DN8")
	)
	(via
		(at 152.832816 -5.818378)
		(size 0.4318)
		(drill 0.2032)
		(layers "F.Cu" "B.Cu")
		(net "M_B_DQS_DN8")
	)
	(via
		(at 105.313988 -24.892)
		(size 0.4318)
		(drill 0.2032)
		(layers "F.Cu" "B.Cu")
		(net "M_B_DQS_DN8")
	)
	(segment
		(start 153.097484 -8.654034)
		(end 153.097484 -6.083046)
		(width 0.1778)
		(layer "B.Cu")
		(net "M_B_DQS_DN8")
	)
	(segment
		(start 153.097484 -6.083046)
		(end 152.832816 -5.818378)
		(width 0.1778)
		(layer "B.Cu")
		(net "M_B_DQS_DN8")
	)
	(segment
		(start 152.94991 -8.801608)
		(end 153.097484 -8.654034)
		(width 0.1778)
		(layer "B.Cu")
		(net "M_B_DQS_DN8")
	)
	(segment
		(start 152.94991 -9.89076)
		(end 152.94991 -8.801608)
		(width 0.1778)
		(layer "B.Cu")
		(net "M_B_DQS_DN8")
	)
	(segment
		(start 110.7694 -21.7678)
		(end 110.7186 -21.8186)
		(width 0.1016)
		(layer "In2.Cu")
		(net "M_B_DQS_DN8")
	)
	(segment
		(start 153.110438 -6.096)
		(end 152.832816 -5.818378)
		(width 0.1524)
		(layer "In2.Cu")
		(net "M_B_DQS_DN8")
	)
	(segment
		(start 153.110438 -6.62178)
		(end 153.110438 -6.096)
		(width 0.1524)
		(layer "In2.Cu")
		(net "M_B_DQS_DN8")
	)
	(segment
		(start 125.311154 -19.431)
		(end 150.225252 -19.431)
		(width 0.1524)
		(layer "In2.Cu")
		(net "M_B_DQS_DN8")
	)
	(segment
		(start 111.9124 -21.59)
		(end 112.5728 -20.9296)
		(width 0.1524)
		(layer "In2.Cu")
		(net "M_B_DQS_DN8")
	)
	(segment
		(start 151.7142 -17.942052)
		(end 151.7142 -8.018018)
		(width 0.1524)
		(layer "In2.Cu")
		(net "M_B_DQS_DN8")
	)
	(segment
		(start 111.2774 -21.59)
		(end 111.9124 -21.59)
		(width 0.1524)
		(layer "In2.Cu")
		(net "M_B_DQS_DN8")
	)
	(segment
		(start 113.349024 -20.9296)
		(end 114.009424 -21.59)
		(width 0.1524)
		(layer "In2.Cu")
		(net "M_B_DQS_DN8")
	)
	(segment
		(start 112.5728 -20.9296)
		(end 113.349024 -20.9296)
		(width 0.1524)
		(layer "In2.Cu")
		(net "M_B_DQS_DN8")
	)
	(segment
		(start 151.7142 -8.018018)
		(end 153.110438 -6.62178)
		(width 0.1524)
		(layer "In2.Cu")
		(net "M_B_DQS_DN8")
	)
	(segment
		(start 114.009424 -21.59)
		(end 123.152154 -21.59)
		(width 0.1524)
		(layer "In2.Cu")
		(net "M_B_DQS_DN8")
	)
	(segment
		(start 110.7186 -21.8186)
		(end 105.8164 -21.8186)
		(width 0.1016)
		(layer "In2.Cu")
		(net "M_B_DQS_DN8")
	)
	(segment
		(start 123.152154 -21.59)
		(end 125.311154 -19.431)
		(width 0.1524)
		(layer "In2.Cu")
		(net "M_B_DQS_DN8")
	)
	(segment
		(start 111.0996 -21.7678)
		(end 111.2774 -21.59)
		(width 0.1524)
		(layer "In2.Cu")
		(net "M_B_DQS_DN8")
	)
	(segment
		(start 104.9528 -24.530812)
		(end 105.313988 -24.892)
		(width 0.1016)
		(layer "In2.Cu")
		(net "M_B_DQS_DN8")
	)
	(segment
		(start 104.9528 -22.6822)
		(end 104.9528 -24.530812)
		(width 0.1016)
		(layer "In2.Cu")
		(net "M_B_DQS_DN8")
	)
	(segment
		(start 150.225252 -19.431)
		(end 151.7142 -17.942052)
		(width 0.1524)
		(layer "In2.Cu")
		(net "M_B_DQS_DN8")
	)
	(segment
		(start 105.8164 -21.8186)
		(end 104.9528 -22.6822)
		(width 0.1016)
		(layer "In2.Cu")
		(net "M_B_DQS_DN8")
	)
	(segment
		(start 110.7694 -21.7678)
		(end 111.0996 -21.7678)
		(width 0.1524)
		(layer "In2.Cu")
		(net "M_B_DQS_DN8")
	)
	(segment
		(start 86.6648 -28.607766)
		(end 86.6648 -28.592526)
		(width 0.1143)
		(layer "F.Cu")
		(net "GBE_OBSN")
	)
	(segment
		(start 87.673688 -29.616654)
		(end 86.6648 -28.607766)
		(width 0.1143)
		(layer "F.Cu")
		(net "GBE_OBSN")
	)
	(via
		(at 85.9536 -28.9052)
		(size 0.7112)
		(drill 0.3556)
		(layers "F.Cu" "B.Cu")
		(net "GBE_OBSN")
	)
	(via
		(at 86.6648 -28.592526)
		(size 0.4318)
		(drill 0.2032)
		(layers "F.Cu" "B.Cu")
		(net "GBE_OBSN")
	)
	(segment
		(start 85.9536 -28.9052)
		(end 86.352126 -28.9052)
		(width 0.1143)
		(layer "B.Cu")
		(net "GBE_OBSN")
	)
	(segment
		(start 85.344 -28.423362)
		(end 85.825838 -28.9052)
		(width 0.1143)
		(layer "B.Cu")
		(net "GBE_OBSN")
	)
	(segment
		(start 86.352126 -28.9052)
		(end 86.6648 -28.592526)
		(width 0.1143)
		(layer "B.Cu")
		(net "GBE_OBSN")
	)
	(segment
		(start 85.825838 -28.9052)
		(end 85.9536 -28.9052)
		(width 0.1143)
		(layer "B.Cu")
		(net "GBE_OBSN")
	)
	(segment
		(start 85.344 -28.1178)
		(end 85.344 -28.423362)
		(width 0.1143)
		(layer "B.Cu")
		(net "GBE_OBSN")
	)
	(segment
		(start 17.004792 -58.619898)
		(end 18.590006 -58.619898)
		(width 0.1143)
		(layer "F.Cu")
		(net "VR_95831_SCLK")
	)
	(segment
		(start 16.2814 -59.1312)
		(end 16.49349 -59.1312)
		(width 0.1143)
		(layer "F.Cu")
		(net "VR_95831_SCLK")
	)
	(segment
		(start 16.49349 -59.1312)
		(end 17.004792 -58.619898)
		(width 0.1143)
		(layer "F.Cu")
		(net "VR_95831_SCLK")
	)
	(segment
		(start 104.6226 -37.2872)
		(end 104.6226 -37.302186)
		(width 0.1016)
		(layer "F.Cu")
		(net "M_B_DQ58")
	)
	(segment
		(start 187.9092 -8.028178)
		(end 187.9092 -7.697978)
		(width 0.1778)
		(layer "F.Cu")
		(net "M_B_DQ58")
	)
	(segment
		(start 188.049916 -8.168894)
		(end 187.9092 -8.028178)
		(width 0.1778)
		(layer "F.Cu")
		(net "M_B_DQ58")
	)
	(segment
		(start 188.049916 -9.897364)
		(end 188.049916 -8.168894)
		(width 0.1778)
		(layer "F.Cu")
		(net "M_B_DQ58")
	)
	(segment
		(start 187.9092 -7.697978)
		(end 188.0108 -7.596378)
		(width 0.1778)
		(layer "F.Cu")
		(net "M_B_DQ58")
	)
	(segment
		(start 104.6226 -37.302186)
		(end 105.004108 -37.683694)
		(width 0.1016)
		(layer "F.Cu")
		(net "M_B_DQ58")
	)
	(via
		(at 104.6226 -37.2872)
		(size 0.4318)
		(drill 0.2032)
		(layers "F.Cu" "B.Cu")
		(net "M_B_DQ58")
	)
	(via
		(at 188.0108 -7.596378)
		(size 0.4318)
		(drill 0.2032)
		(layers "F.Cu" "B.Cu")
		(net "M_B_DQ58")
	)
	(segment
		(start 188.0108 -8.581898)
		(end 188.0108 -7.596378)
		(width 0.1778)
		(layer "B.Cu")
		(net "M_B_DQ58")
	)
	(segment
		(start 187.749942 -9.89076)
		(end 187.749942 -8.842756)
		(width 0.1778)
		(layer "B.Cu")
		(net "M_B_DQ58")
	)
	(segment
		(start 187.749942 -8.842756)
		(end 188.0108 -8.581898)
		(width 0.1778)
		(layer "B.Cu")
		(net "M_B_DQ58")
	)
	(segment
		(start 104.7242 -37.6682)
		(end 105.047796 -38.18255)
		(width 0.1016)
		(layer "In2.Cu")
		(net "M_B_DQ58")
	)
	(segment
		(start 106.0704 -38.5064)
		(end 106.426 -38.862)
		(width 0.1016)
		(layer "In2.Cu")
		(net "M_B_DQ58")
	)
	(segment
		(start 183.86679 -13.8684)
		(end 182.523638 -13.8684)
		(width 0.1524)
		(layer "In2.Cu")
		(net "M_B_DQ58")
	)
	(segment
		(start 112.1664 -39.497)
		(end 112.776 -38.8874)
		(width 0.1016)
		(layer "In2.Cu")
		(net "M_B_DQ58")
	)
	(segment
		(start 113.0173 -38.6461)
		(end 112.776 -38.8874)
		(width 0.1524)
		(layer "In2.Cu")
		(net "M_B_DQ58")
	)
	(segment
		(start 188.0108 -7.596378)
		(end 188.0108 -9.72439)
		(width 0.1524)
		(layer "In2.Cu")
		(net "M_B_DQ58")
	)
	(segment
		(start 106.426 -38.862)
		(end 109.8804 -38.862)
		(width 0.1016)
		(layer "In2.Cu")
		(net "M_B_DQ58")
	)
	(segment
		(start 111.125 -39.497)
		(end 112.1664 -39.497)
		(width 0.1016)
		(layer "In2.Cu")
		(net "M_B_DQ58")
	)
	(segment
		(start 105.047796 -38.18255)
		(end 105.289096 -38.42385)
		(width 0.1016)
		(layer "In2.Cu")
		(net "M_B_DQ58")
	)
	(segment
		(start 104.6226 -37.2872)
		(end 104.7242 -37.6682)
		(width 0.1016)
		(layer "In2.Cu")
		(net "M_B_DQ58")
	)
	(segment
		(start 157.745938 -38.6461)
		(end 113.0173 -38.6461)
		(width 0.1524)
		(layer "In2.Cu")
		(net "M_B_DQ58")
	)
	(segment
		(start 105.5878 -38.5064)
		(end 106.0704 -38.5064)
		(width 0.1016)
		(layer "In2.Cu")
		(net "M_B_DQ58")
	)
	(segment
		(start 109.8804 -38.862)
		(end 111.125 -39.497)
		(width 0.1016)
		(layer "In2.Cu")
		(net "M_B_DQ58")
	)
	(segment
		(start 105.289096 -38.42385)
		(end 105.5878 -38.5064)
		(width 0.1016)
		(layer "In2.Cu")
		(net "M_B_DQ58")
	)
	(segment
		(start 188.0108 -9.72439)
		(end 183.86679 -13.8684)
		(width 0.1524)
		(layer "In2.Cu")
		(net "M_B_DQ58")
	)
	(segment
		(start 182.523638 -13.8684)
		(end 157.745938 -38.6461)
		(width 0.1524)
		(layer "In2.Cu")
		(net "M_B_DQ58")
	)
	(via
		(at 44.21124 -12.5984)
		(size 0.508)
		(drill 0.254)
		(layers "F.Cu" "B.Cu")
		(net "CLK_100M_CLKBUFF_ENET_DP")
	)
	(via
		(at 62.32779 -10.250678)
		(size 0.508)
		(drill 0.254)
		(layers "F.Cu" "B.Cu")
		(net "CLK_100M_CLKBUFF_ENET_DP")
	)
	(segment
		(start 44.1706 -15.5702)
		(end 43.9039 -15.3035)
		(width 0.1397)
		(layer "B.Cu")
		(net "CLK_100M_CLKBUFF_ENET_DP")
	)
	(segment
		(start 62.034166 -9.957054)
		(end 62.32779 -10.250678)
		(width 0.1397)
		(layer "B.Cu")
		(net "CLK_100M_CLKBUFF_ENET_DP")
	)
	(segment
		(start 44.1452 -15.5956)
		(end 44.1706 -15.5702)
		(width 0.1397)
		(layer "B.Cu")
		(net "CLK_100M_CLKBUFF_ENET_DP")
	)
	(segment
		(start 62.349888 -8.447278)
		(end 62.034166 -8.763)
		(width 0.1397)
		(layer "B.Cu")
		(net "CLK_100M_CLKBUFF_ENET_DP")
	)
	(segment
		(start 44.1452 -16.3576)
		(end 44.1452 -15.5956)
		(width 0.1397)
		(layer "B.Cu")
		(net "CLK_100M_CLKBUFF_ENET_DP")
	)
	(segment
		(start 43.9039 -15.3035)
		(end 43.9039 -12.90574)
		(width 0.1397)
		(layer "B.Cu")
		(net "CLK_100M_CLKBUFF_ENET_DP")
	)
	(segment
		(start 62.034166 -8.763)
		(end 62.034166 -9.957054)
		(width 0.1397)
		(layer "B.Cu")
		(net "CLK_100M_CLKBUFF_ENET_DP")
	)
	(segment
		(start 62.349888 -5.814568)
		(end 62.349888 -8.447278)
		(width 0.1397)
		(layer "B.Cu")
		(net "CLK_100M_CLKBUFF_ENET_DP")
	)
	(segment
		(start 43.9039 -12.90574)
		(end 44.21124 -12.5984)
		(width 0.1397)
		(layer "B.Cu")
		(net "CLK_100M_CLKBUFF_ENET_DP")
	)
	(segment
		(start 56.982106 -11.0744)
		(end 57.693306 -10.3632)
		(width 0.1143)
		(layer "In2.Cu")
		(net "CLK_100M_CLKBUFF_ENET_DP")
	)
	(segment
		(start 44.21124 -12.5984)
		(end 43.89755 -12.28471)
		(width 0.1143)
		(layer "In2.Cu")
		(net "CLK_100M_CLKBUFF_ENET_DP")
	)
	(segment
		(start 44.942252 -11.0744)
		(end 56.982106 -11.0744)
		(width 0.1143)
		(layer "In2.Cu")
		(net "CLK_100M_CLKBUFF_ENET_DP")
	)
	(segment
		(start 61.687456 -11.2014)
		(end 62.03315 -10.855706)
		(width 0.1143)
		(layer "In2.Cu")
		(net "CLK_100M_CLKBUFF_ENET_DP")
	)
	(segment
		(start 61.0362 -11.2014)
		(end 61.687456 -11.2014)
		(width 0.1143)
		(layer "In2.Cu")
		(net "CLK_100M_CLKBUFF_ENET_DP")
	)
	(segment
		(start 62.03315 -10.545318)
		(end 62.32779 -10.250678)
		(width 0.1143)
		(layer "In2.Cu")
		(net "CLK_100M_CLKBUFF_ENET_DP")
	)
	(segment
		(start 60.198 -10.3632)
		(end 61.0362 -11.2014)
		(width 0.1143)
		(layer "In2.Cu")
		(net "CLK_100M_CLKBUFF_ENET_DP")
	)
	(segment
		(start 43.89755 -12.119102)
		(end 44.942252 -11.0744)
		(width 0.1143)
		(layer "In2.Cu")
		(net "CLK_100M_CLKBUFF_ENET_DP")
	)
	(segment
		(start 62.03315 -10.855706)
		(end 62.03315 -10.545318)
		(width 0.1143)
		(layer "In2.Cu")
		(net "CLK_100M_CLKBUFF_ENET_DP")
	)
	(segment
		(start 57.693306 -10.3632)
		(end 60.198 -10.3632)
		(width 0.1143)
		(layer "In2.Cu")
		(net "CLK_100M_CLKBUFF_ENET_DP")
	)
	(segment
		(start 43.89755 -12.28471)
		(end 43.89755 -12.119102)
		(width 0.1143)
		(layer "In2.Cu")
		(net "CLK_100M_CLKBUFF_ENET_DP")
	)
	(segment
		(start 13.843 -55.1688)
		(end 13.716 -55.2958)
		(width 0.2032)
		(layer "F.Cu")
		(net "VR_PVCCP_IMON")
	)
	(segment
		(start 17.650206 -56.3372)
		(end 16.812006 -55.499)
		(width 0.2032)
		(layer "F.Cu")
		(net "VR_PVCCP_IMON")
	)
	(segment
		(start 17.650206 -56.95315)
		(end 17.650206 -56.3372)
		(width 0.2032)
		(layer "F.Cu")
		(net "VR_PVCCP_IMON")
	)
	(segment
		(start 18.590006 -57.420002)
		(end 18.117058 -57.420002)
		(width 0.2032)
		(layer "F.Cu")
		(net "VR_PVCCP_IMON")
	)
	(segment
		(start 13.716 -55.2958)
		(end 13.081 -55.2958)
		(width 0.2032)
		(layer "F.Cu")
		(net "VR_PVCCP_IMON")
	)
	(segment
		(start 15.63624 -55.499)
		(end 15.272258 -55.135018)
		(width 0.2032)
		(layer "F.Cu")
		(net "VR_PVCCP_IMON")
	)
	(segment
		(start 13.081 -55.2958)
		(end 13.0302 -55.245)
		(width 0.2032)
		(layer "F.Cu")
		(net "VR_PVCCP_IMON")
	)
	(segment
		(start 15.272258 -55.135018)
		(end 15.238476 -55.1688)
		(width 0.2032)
		(layer "F.Cu")
		(net "VR_PVCCP_IMON")
	)
	(segment
		(start 18.117058 -57.420002)
		(end 17.650206 -56.95315)
		(width 0.2032)
		(layer "F.Cu")
		(net "VR_PVCCP_IMON")
	)
	(segment
		(start 16.812006 -55.499)
		(end 15.63624 -55.499)
		(width 0.2032)
		(layer "F.Cu")
		(net "VR_PVCCP_IMON")
	)
	(segment
		(start 15.238476 -55.1688)
		(end 13.843 -55.1688)
		(width 0.2032)
		(layer "F.Cu")
		(net "VR_PVCCP_IMON")
	)
	(via
		(at 15.272258 -55.135018)
		(size 0.7112)
		(drill 0.3556)
		(layers "F.Cu" "B.Cu")
		(net "VR_PVCCP_IMON")
	)
	(segment
		(start 133.3246 -7.846822)
		(end 133.541262 -7.846822)
		(width 0.1778)
		(layer "F.Cu")
		(net "M_B_DQ3")
	)
	(segment
		(start 133.35 -8.332978)
		(end 133.2103 -8.193278)
		(width 0.1778)
		(layer "F.Cu")
		(net "M_B_DQ3")
	)
	(segment
		(start 94.793308 -25.79116)
		(end 94.629732 -25.627584)
		(width 0.1016)
		(layer "F.Cu")
		(net "M_B_DQ3")
	)
	(segment
		(start 133.2103 -8.193278)
		(end 133.2103 -7.961122)
		(width 0.1778)
		(layer "F.Cu")
		(net "M_B_DQ3")
	)
	(segment
		(start 133.449822 -9.897364)
		(end 133.449822 -8.913622)
		(width 0.1778)
		(layer "F.Cu")
		(net "M_B_DQ3")
	)
	(segment
		(start 93.6244 -25.0444)
		(end 93.6244 -24.765)
		(width 0.1016)
		(layer "F.Cu")
		(net "M_B_DQ3")
	)
	(segment
		(start 94.629732 -25.627584)
		(end 94.207584 -25.627584)
		(width 0.1016)
		(layer "F.Cu")
		(net "M_B_DQ3")
	)
	(segment
		(start 94.207584 -25.627584)
		(end 93.6244 -25.0444)
		(width 0.1016)
		(layer "F.Cu")
		(net "M_B_DQ3")
	)
	(segment
		(start 95.286068 -27.404314)
		(end 95.286068 -26.956004)
		(width 0.1016)
		(layer "F.Cu")
		(net "M_B_DQ3")
	)
	(segment
		(start 95.286068 -26.956004)
		(end 94.793308 -26.463244)
		(width 0.1016)
		(layer "F.Cu")
		(net "M_B_DQ3")
	)
	(segment
		(start 94.793308 -26.463244)
		(end 94.793308 -25.79116)
		(width 0.1016)
		(layer "F.Cu")
		(net "M_B_DQ3")
	)
	(segment
		(start 133.35 -8.8138)
		(end 133.35 -8.332978)
		(width 0.1778)
		(layer "F.Cu")
		(net "M_B_DQ3")
	)
	(segment
		(start 133.2103 -7.961122)
		(end 133.3246 -7.846822)
		(width 0.1778)
		(layer "F.Cu")
		(net "M_B_DQ3")
	)
	(segment
		(start 133.449822 -8.913622)
		(end 133.35 -8.8138)
		(width 0.1778)
		(layer "F.Cu")
		(net "M_B_DQ3")
	)
	(via
		(at 133.541262 -7.846822)
		(size 0.4318)
		(drill 0.2032)
		(layers "F.Cu" "B.Cu")
		(net "M_B_DQ3")
	)
	(via
		(at 93.6244 -24.765)
		(size 0.4318)
		(drill 0.2032)
		(layers "F.Cu" "B.Cu")
		(net "M_B_DQ3")
	)
	(segment
		(start 132.5499 -9.89076)
		(end 132.5499 -9.181338)
		(width 0.1778)
		(layer "B.Cu")
		(net "M_B_DQ3")
	)
	(segment
		(start 133.2484 -8.139684)
		(end 133.541262 -7.846822)
		(width 0.1778)
		(layer "B.Cu")
		(net "M_B_DQ3")
	)
	(segment
		(start 133.2484 -8.482838)
		(end 133.2484 -8.139684)
		(width 0.1778)
		(layer "B.Cu")
		(net "M_B_DQ3")
	)
	(segment
		(start 132.5499 -9.181338)
		(end 133.2484 -8.482838)
		(width 0.1778)
		(layer "B.Cu")
		(net "M_B_DQ3")
	)
	(segment
		(start 97.8662 -20.1676)
		(end 98.0186 -20.0152)
		(width 0.1524)
		(layer "In7.Cu")
		(net "M_B_DQ3")
	)
	(segment
		(start 94.615 -26.416)
		(end 94.7674 -26.2636)
		(width 0.1524)
		(layer "In7.Cu")
		(net "M_B_DQ3")
	)
	(segment
		(start 93.6244 -24.765)
		(end 93.6244 -26.2636)
		(width 0.1524)
		(layer "In7.Cu")
		(net "M_B_DQ3")
	)
	(segment
		(start 124.4854 -13.3604)
		(end 124.6378 -13.208)
		(width 0.1524)
		(layer "In7.Cu")
		(net "M_B_DQ3")
	)
	(segment
		(start 125.242574 -12.8524)
		(end 125.394974 -13.0048)
		(width 0.1524)
		(layer "In7.Cu")
		(net "M_B_DQ3")
	)
	(segment
		(start 124.048774 -13.3604)
		(end 124.4854 -13.3604)
		(width 0.1524)
		(layer "In7.Cu")
		(net "M_B_DQ3")
	)
	(segment
		(start 125.394974 -13.0048)
		(end 125.394974 -13.208)
		(width 0.1524)
		(layer "In7.Cu")
		(net "M_B_DQ3")
	)
	(segment
		(start 123.286774 -13.208)
		(end 123.286774 -12.9286)
		(width 0.1524)
		(layer "In7.Cu")
		(net "M_B_DQ3")
	)
	(segment
		(start 133.6802 -8.925814)
		(end 133.357112 -8.602726)
		(width 0.1524)
		(layer "In7.Cu")
		(net "M_B_DQ3")
	)
	(segment
		(start 124.7902 -12.8524)
		(end 125.242574 -12.8524)
		(width 0.1524)
		(layer "In7.Cu")
		(net "M_B_DQ3")
	)
	(segment
		(start 119.3546 -11.6332)
		(end 119.3546 -13.1572)
		(width 0.1524)
		(layer "In7.Cu")
		(net "M_B_DQ3")
	)
	(segment
		(start 94.9198 -25.2476)
		(end 97.3836 -25.2476)
		(width 0.1524)
		(layer "In7.Cu")
		(net "M_B_DQ3")
	)
	(segment
		(start 118.5418 -11.43)
		(end 119.1514 -11.43)
		(width 0.1524)
		(layer "In7.Cu")
		(net "M_B_DQ3")
	)
	(segment
		(start 124.6378 -13.0048)
		(end 124.7902 -12.8524)
		(width 0.1524)
		(layer "In7.Cu")
		(net "M_B_DQ3")
	)
	(segment
		(start 118.1354 -13.3604)
		(end 118.3386 -13.1572)
		(width 0.1524)
		(layer "In7.Cu")
		(net "M_B_DQ3")
	)
	(segment
		(start 125.547374 -13.3604)
		(end 130.9878 -13.3604)
		(width 0.1524)
		(layer "In7.Cu")
		(net "M_B_DQ3")
	)
	(segment
		(start 133.6802 -10.668)
		(end 133.6802 -8.925814)
		(width 0.1524)
		(layer "In7.Cu")
		(net "M_B_DQ3")
	)
	(segment
		(start 123.286774 -12.9286)
		(end 123.439174 -12.7762)
		(width 0.1524)
		(layer "In7.Cu")
		(net "M_B_DQ3")
	)
	(segment
		(start 118.3386 -11.6332)
		(end 118.5418 -11.43)
		(width 0.1524)
		(layer "In7.Cu")
		(net "M_B_DQ3")
	)
	(segment
		(start 94.7674 -25.4)
		(end 94.9198 -25.2476)
		(width 0.1524)
		(layer "In7.Cu")
		(net "M_B_DQ3")
	)
	(segment
		(start 123.896374 -12.9286)
		(end 123.896374 -13.208)
		(width 0.1524)
		(layer "In7.Cu")
		(net "M_B_DQ3")
	)
	(segment
		(start 113.86312 -13.3604)
		(end 118.1354 -13.3604)
		(width 0.1524)
		(layer "In7.Cu")
		(net "M_B_DQ3")
	)
	(segment
		(start 94.7674 -26.2636)
		(end 94.7674 -25.4)
		(width 0.1524)
		(layer "In7.Cu")
		(net "M_B_DQ3")
	)
	(segment
		(start 124.6378 -13.208)
		(end 124.6378 -13.0048)
		(width 0.1524)
		(layer "In7.Cu")
		(net "M_B_DQ3")
	)
	(segment
		(start 123.134374 -13.3604)
		(end 123.286774 -13.208)
		(width 0.1524)
		(layer "In7.Cu")
		(net "M_B_DQ3")
	)
	(segment
		(start 133.357112 -8.030972)
		(end 133.541262 -7.846822)
		(width 0.1524)
		(layer "In7.Cu")
		(net "M_B_DQ3")
	)
	(segment
		(start 93.6244 -26.2636)
		(end 93.7768 -26.416)
		(width 0.1524)
		(layer "In7.Cu")
		(net "M_B_DQ3")
	)
	(segment
		(start 119.5578 -13.3604)
		(end 123.134374 -13.3604)
		(width 0.1524)
		(layer "In7.Cu")
		(net "M_B_DQ3")
	)
	(segment
		(start 119.3546 -13.1572)
		(end 119.5578 -13.3604)
		(width 0.1524)
		(layer "In7.Cu")
		(net "M_B_DQ3")
	)
	(segment
		(start 100.583746 -19.304)
		(end 107.91952 -19.304)
		(width 0.1524)
		(layer "In7.Cu")
		(net "M_B_DQ3")
	)
	(segment
		(start 119.1514 -11.43)
		(end 119.3546 -11.6332)
		(width 0.1524)
		(layer "In7.Cu")
		(net "M_B_DQ3")
	)
	(segment
		(start 123.439174 -12.7762)
		(end 123.743974 -12.7762)
		(width 0.1524)
		(layer "In7.Cu")
		(net "M_B_DQ3")
	)
	(segment
		(start 107.91952 -19.304)
		(end 113.86312 -13.3604)
		(width 0.1524)
		(layer "In7.Cu")
		(net "M_B_DQ3")
	)
	(segment
		(start 98.0186 -20.0152)
		(end 99.872546 -20.0152)
		(width 0.1524)
		(layer "In7.Cu")
		(net "M_B_DQ3")
	)
	(segment
		(start 118.3386 -13.1572)
		(end 118.3386 -11.6332)
		(width 0.1524)
		(layer "In7.Cu")
		(net "M_B_DQ3")
	)
	(segment
		(start 93.7768 -26.416)
		(end 94.615 -26.416)
		(width 0.1524)
		(layer "In7.Cu")
		(net "M_B_DQ3")
	)
	(segment
		(start 99.872546 -20.0152)
		(end 100.583746 -19.304)
		(width 0.1524)
		(layer "In7.Cu")
		(net "M_B_DQ3")
	)
	(segment
		(start 97.3836 -25.2476)
		(end 97.8662 -24.765)
		(width 0.1524)
		(layer "In7.Cu")
		(net "M_B_DQ3")
	)
	(segment
		(start 125.394974 -13.208)
		(end 125.547374 -13.3604)
		(width 0.1524)
		(layer "In7.Cu")
		(net "M_B_DQ3")
	)
	(segment
		(start 130.9878 -13.3604)
		(end 133.6802 -10.668)
		(width 0.1524)
		(layer "In7.Cu")
		(net "M_B_DQ3")
	)
	(segment
		(start 123.743974 -12.7762)
		(end 123.896374 -12.9286)
		(width 0.1524)
		(layer "In7.Cu")
		(net "M_B_DQ3")
	)
	(segment
		(start 133.357112 -8.602726)
		(end 133.357112 -8.030972)
		(width 0.1524)
		(layer "In7.Cu")
		(net "M_B_DQ3")
	)
	(segment
		(start 97.8662 -24.765)
		(end 97.8662 -20.1676)
		(width 0.1524)
		(layer "In7.Cu")
		(net "M_B_DQ3")
	)
	(segment
		(start 123.896374 -13.208)
		(end 124.048774 -13.3604)
		(width 0.1524)
		(layer "In7.Cu")
		(net "M_B_DQ3")
	)
	(segment
		(start 20.3962 -47.4472)
		(end 21.209 -48.26)
		(width 0.2032)
		(layer "F.Cu")
		(net "VR_PVCCP_ISUMP_R2")
	)
	(segment
		(start 21.209 -48.26)
		(end 21.209 -48.514)
		(width 0.2032)
		(layer "F.Cu")
		(net "VR_PVCCP_ISUMP_R2")
	)
	(segment
		(start 20.3962 -47.371)
		(end 20.3962 -47.4472)
		(width 0.2032)
		(layer "F.Cu")
		(net "VR_PVCCP_ISUMP_R2")
	)
	(segment
		(start 20.403058 -49.276)
		(end 21.165058 -48.514)
		(width 0.2032)
		(layer "F.Cu")
		(net "VR_PVCCP_ISUMP_R2")
	)
	(segment
		(start 20.3962 -49.276)
		(end 20.403058 -49.276)
		(width 0.2032)
		(layer "F.Cu")
		(net "VR_PVCCP_ISUMP_R2")
	)
	(segment
		(start 21.165058 -48.514)
		(end 21.209 -48.514)
		(width 0.2032)
		(layer "F.Cu")
		(net "VR_PVCCP_ISUMP_R2")
	)
	(via
		(at 21.209 -48.514)
		(size 0.508)
		(drill 0.254)
		(layers "F.Cu" "B.Cu")
		(net "VR_PVCCP_ISUMP_R2")
	)
	(via
		(at 27.432 -54.356)
		(size 0.7112)
		(drill 0.3556)
		(layers "F.Cu" "B.Cu")
		(net "VR_PVCCP_ISUMP_R2")
	)
	(segment
		(start 29.7942 -55.88)
		(end 28.2702 -54.356)
		(width 0.2032)
		(layer "B.Cu")
		(net "VR_PVCCP_ISUMP_R2")
	)
	(segment
		(start 21.209 -48.597566)
		(end 26.967434 -54.356)
		(width 0.2032)
		(layer "B.Cu")
		(net "VR_PVCCP_ISUMP_R2")
	)
	(segment
		(start 50.673 -57.658)
		(end 49.05375 -56.03875)
		(width 0.2032)
		(layer "B.Cu")
		(net "VR_PVCCP_ISUMP_R2")
	)
	(segment
		(start 35.433 -55.499)
		(end 35.052 -55.88)
		(width 0.2032)
		(layer "B.Cu")
		(net "VR_PVCCP_ISUMP_R2")
	)
	(segment
		(start 28.2702 -54.356)
		(end 27.432 -54.356)
		(width 0.2032)
		(layer "B.Cu")
		(net "VR_PVCCP_ISUMP_R2")
	)
	(segment
		(start 49.05375 -56.03875)
		(end 47.447708 -56.03875)
		(width 0.2032)
		(layer "B.Cu")
		(net "VR_PVCCP_ISUMP_R2")
	)
	(segment
		(start 50.673 -58.3438)
		(end 50.673 -57.658)
		(width 0.2032)
		(layer "B.Cu")
		(net "VR_PVCCP_ISUMP_R2")
	)
	(segment
		(start 26.967434 -54.356)
		(end 27.432 -54.356)
		(width 0.2032)
		(layer "B.Cu")
		(net "VR_PVCCP_ISUMP_R2")
	)
	(segment
		(start 46.907958 -55.499)
		(end 35.433 -55.499)
		(width 0.2032)
		(layer "B.Cu")
		(net "VR_PVCCP_ISUMP_R2")
	)
	(segment
		(start 21.209 -48.514)
		(end 21.209 -48.597566)
		(width 0.2032)
		(layer "B.Cu")
		(net "VR_PVCCP_ISUMP_R2")
	)
	(segment
		(start 50.4698 -58.547)
		(end 50.673 -58.3438)
		(width 0.2032)
		(layer "B.Cu")
		(net "VR_PVCCP_ISUMP_R2")
	)
	(segment
		(start 47.447708 -56.03875)
		(end 46.907958 -55.499)
		(width 0.2032)
		(layer "B.Cu")
		(net "VR_PVCCP_ISUMP_R2")
	)
	(segment
		(start 35.052 -55.88)
		(end 29.7942 -55.88)
		(width 0.2032)
		(layer "B.Cu")
		(net "VR_PVCCP_ISUMP_R2")
	)
	(segment
		(start 137.349992 -2.40157)
		(end 137.874756 -2.926334)
		(width 0.1778)
		(layer "F.Cu")
		(net "M_B_DQ14")
	)
	(segment
		(start 137.874756 -3.655822)
		(end 137.6934 -3.837178)
		(width 0.1778)
		(layer "F.Cu")
		(net "M_B_DQ14")
	)
	(segment
		(start 137.349992 -1.68402)
		(end 137.349992 -2.40157)
		(width 0.1778)
		(layer "F.Cu")
		(net "M_B_DQ14")
	)
	(segment
		(start 98.636328 -27.300174)
		(end 98.636328 -27.299666)
		(width 0.1016)
		(layer "F.Cu")
		(net "M_B_DQ14")
	)
	(segment
		(start 98.2726 -25.5524)
		(end 97.3963 -24.6761)
		(width 0.1016)
		(layer "F.Cu")
		(net "M_B_DQ14")
	)
	(segment
		(start 137.874756 -2.926334)
		(end 137.874756 -3.655822)
		(width 0.1778)
		(layer "F.Cu")
		(net "M_B_DQ14")
	)
	(segment
		(start 98.636328 -27.299666)
		(end 98.2726 -26.935938)
		(width 0.1016)
		(layer "F.Cu")
		(net "M_B_DQ14")
	)
	(segment
		(start 98.2726 -26.935938)
		(end 98.2726 -25.5524)
		(width 0.1016)
		(layer "F.Cu")
		(net "M_B_DQ14")
	)
	(segment
		(start 97.3963 -24.6761)
		(end 97.3963 -22.987)
		(width 0.1016)
		(layer "F.Cu")
		(net "M_B_DQ14")
	)
	(via
		(at 137.6934 -3.837178)
		(size 0.4318)
		(drill 0.2032)
		(layers "F.Cu" "B.Cu")
		(net "M_B_DQ14")
	)
	(via
		(at 97.3963 -22.987)
		(size 0.4318)
		(drill 0.2032)
		(layers "F.Cu" "B.Cu")
		(net "M_B_DQ14")
	)
	(segment
		(start 137.9347 -2.950718)
		(end 137.9347 -3.595878)
		(width 0.1778)
		(layer "B.Cu")
		(net "M_B_DQ14")
	)
	(segment
		(start 138.249914 -2.635504)
		(end 137.9347 -2.950718)
		(width 0.1778)
		(layer "B.Cu")
		(net "M_B_DQ14")
	)
	(segment
		(start 137.9347 -3.595878)
		(end 137.6934 -3.837178)
		(width 0.1778)
		(layer "B.Cu")
		(net "M_B_DQ14")
	)
	(segment
		(start 138.249914 -1.690624)
		(end 138.249914 -2.635504)
		(width 0.1778)
		(layer "B.Cu")
		(net "M_B_DQ14")
	)
	(segment
		(start 135.166862 -11.238738)
		(end 135.166862 -12.064492)
		(width 0.1524)
		(layer "In2.Cu")
		(net "M_B_DQ14")
	)
	(segment
		(start 136.6266 -8.89)
		(end 136.6266 -9.779)
		(width 0.1524)
		(layer "In2.Cu")
		(net "M_B_DQ14")
	)
	(segment
		(start 135.166862 -14.351)
		(end 135.014462 -14.5034)
		(width 0.1524)
		(layer "In2.Cu")
		(net "M_B_DQ14")
	)
	(segment
		(start 109.21365 -15.900146)
		(end 107.053888 -18.059908)
		(width 0.1524)
		(layer "In2.Cu")
		(net "M_B_DQ14")
	)
	(segment
		(start 135.014462 -14.5034)
		(end 118.899686 -14.5034)
		(width 0.1524)
		(layer "In2.Cu")
		(net "M_B_DQ14")
	)
	(segment
		(start 96.8756 -20.9804)
		(end 96.8756 -22.4663)
		(width 0.1524)
		(layer "In2.Cu")
		(net "M_B_DQ14")
	)
	(segment
		(start 135.763 -12.978892)
		(end 135.6106 -13.131292)
		(width 0.1524)
		(layer "In2.Cu")
		(net "M_B_DQ14")
	)
	(segment
		(start 96.8756 -22.4663)
		(end 97.3963 -22.987)
		(width 0.1524)
		(layer "In2.Cu")
		(net "M_B_DQ14")
	)
	(segment
		(start 107.053888 -18.059908)
		(end 101.906578 -18.059908)
		(width 0.1524)
		(layer "In2.Cu")
		(net "M_B_DQ14")
	)
	(segment
		(start 117.50294 -15.900146)
		(end 109.21365 -15.900146)
		(width 0.1524)
		(layer "In2.Cu")
		(net "M_B_DQ14")
	)
	(segment
		(start 135.166862 -13.283692)
		(end 135.166862 -14.351)
		(width 0.1524)
		(layer "In2.Cu")
		(net "M_B_DQ14")
	)
	(segment
		(start 137.6934 -3.837178)
		(end 137.6934 -4.953)
		(width 0.1524)
		(layer "In2.Cu")
		(net "M_B_DQ14")
	)
	(segment
		(start 135.166862 -12.064492)
		(end 135.319262 -12.216892)
		(width 0.1524)
		(layer "In2.Cu")
		(net "M_B_DQ14")
	)
	(segment
		(start 135.319262 -12.216892)
		(end 135.6106 -12.216892)
		(width 0.1524)
		(layer "In2.Cu")
		(net "M_B_DQ14")
	)
	(segment
		(start 136.8806 -5.7658)
		(end 136.8806 -8.636)
		(width 0.1524)
		(layer "In2.Cu")
		(net "M_B_DQ14")
	)
	(segment
		(start 135.6106 -12.216892)
		(end 135.763 -12.369292)
		(width 0.1524)
		(layer "In2.Cu")
		(net "M_B_DQ14")
	)
	(segment
		(start 118.899686 -14.5034)
		(end 117.50294 -15.900146)
		(width 0.1524)
		(layer "In2.Cu")
		(net "M_B_DQ14")
	)
	(segment
		(start 99.849686 -20.1168)
		(end 97.7392 -20.1168)
		(width 0.1524)
		(layer "In2.Cu")
		(net "M_B_DQ14")
	)
	(segment
		(start 97.7392 -20.1168)
		(end 96.8756 -20.9804)
		(width 0.1524)
		(layer "In2.Cu")
		(net "M_B_DQ14")
	)
	(segment
		(start 136.8806 -8.636)
		(end 136.6266 -8.89)
		(width 0.1524)
		(layer "In2.Cu")
		(net "M_B_DQ14")
	)
	(segment
		(start 101.906578 -18.059908)
		(end 99.849686 -20.1168)
		(width 0.1524)
		(layer "In2.Cu")
		(net "M_B_DQ14")
	)
	(segment
		(start 137.6934 -4.953)
		(end 136.8806 -5.7658)
		(width 0.1524)
		(layer "In2.Cu")
		(net "M_B_DQ14")
	)
	(segment
		(start 135.319262 -13.131292)
		(end 135.166862 -13.283692)
		(width 0.1524)
		(layer "In2.Cu")
		(net "M_B_DQ14")
	)
	(segment
		(start 135.763 -12.369292)
		(end 135.763 -12.978892)
		(width 0.1524)
		(layer "In2.Cu")
		(net "M_B_DQ14")
	)
	(segment
		(start 135.6106 -13.131292)
		(end 135.319262 -13.131292)
		(width 0.1524)
		(layer "In2.Cu")
		(net "M_B_DQ14")
	)
	(segment
		(start 136.6266 -9.779)
		(end 135.166862 -11.238738)
		(width 0.1524)
		(layer "In2.Cu")
		(net "M_B_DQ14")
	)
	(segment
		(start 41.300908 -17.427448)
		(end 41.59631 -17.72285)
		(width 0.1397)
		(layer "B.Cu")
		(net "CLK_100M_CLKBUFF_SAS_R_DN")
	)
	(segment
		(start 41.59631 -17.94129)
		(end 41.51757 -18.02003)
		(width 0.1397)
		(layer "B.Cu")
		(net "CLK_100M_CLKBUFF_SAS_R_DN")
	)
	(segment
		(start 40.08755 -16.54175)
		(end 40.08755 -17.00784)
		(width 0.1397)
		(layer "B.Cu")
		(net "CLK_100M_CLKBUFF_SAS_R_DN")
	)
	(segment
		(start 41.51757 -18.02003)
		(end 41.51757 -18.6563)
		(width 0.1397)
		(layer "B.Cu")
		(net "CLK_100M_CLKBUFF_SAS_R_DN")
	)
	(segment
		(start 41.59631 -17.72285)
		(end 41.59631 -17.94129)
		(width 0.1397)
		(layer "B.Cu")
		(net "CLK_100M_CLKBUFF_SAS_R_DN")
	)
	(segment
		(start 39.878 -16.3322)
		(end 40.08755 -16.54175)
		(width 0.1397)
		(layer "B.Cu")
		(net "CLK_100M_CLKBUFF_SAS_R_DN")
	)
	(segment
		(start 40.507158 -17.427448)
		(end 41.300908 -17.427448)
		(width 0.1397)
		(layer "B.Cu")
		(net "CLK_100M_CLKBUFF_SAS_R_DN")
	)
	(segment
		(start 40.08755 -17.00784)
		(end 40.507158 -17.427448)
		(width 0.1397)
		(layer "B.Cu")
		(net "CLK_100M_CLKBUFF_SAS_R_DN")
	)
	(segment
		(start 87.673688 -28.854654)
		(end 87.53094 -28.854654)
		(width 0.1143)
		(layer "F.Cu")
		(net "GBE_OBSP")
	)
	(segment
		(start 87.53094 -28.854654)
		(end 87.26678 -28.590494)
		(width 0.1143)
		(layer "F.Cu")
		(net "GBE_OBSP")
	)
	(via
		(at 87.26678 -28.590494)
		(size 0.4318)
		(drill 0.2032)
		(layers "F.Cu" "B.Cu")
		(net "GBE_OBSP")
	)
	(via
		(at 86.244938 -27.442922)
		(size 0.7112)
		(drill 0.3556)
		(layers "F.Cu" "B.Cu")
		(net "GBE_OBSP")
	)
	(segment
		(start 86.594696 -27.79268)
		(end 86.594696 -27.91841)
		(width 0.1143)
		(layer "B.Cu")
		(net "GBE_OBSP")
	)
	(segment
		(start 86.594696 -27.91841)
		(end 87.26678 -28.590494)
		(width 0.1143)
		(layer "B.Cu")
		(net "GBE_OBSP")
	)
	(segment
		(start 86.244938 -27.442922)
		(end 86.594696 -27.79268)
		(width 0.1143)
		(layer "B.Cu")
		(net "GBE_OBSP")
	)
	(segment
		(start 86.056216 -27.2542)
		(end 86.244938 -27.442922)
		(width 0.1143)
		(layer "B.Cu")
		(net "GBE_OBSP")
	)
	(segment
		(start 85.344 -27.2542)
		(end 86.056216 -27.2542)
		(width 0.1143)
		(layer "B.Cu")
		(net "GBE_OBSP")
	)
	(segment
		(start 17.018 -63.4746)
		(end 16.3576 -63.4746)
		(width 0.2032)
		(layer "F.Cu")
		(net "VR_PVNN_IMON")
	)
	(segment
		(start 16.3576 -63.4746)
		(end 16.3576 -62.604142)
		(width 0.2032)
		(layer "F.Cu")
		(net "VR_PVNN_IMON")
	)
	(segment
		(start 17.907 -60.496958)
		(end 18.18386 -60.220098)
		(width 0.2032)
		(layer "F.Cu")
		(net "VR_PVNN_IMON")
	)
	(segment
		(start 16.4592 -62.502542)
		(end 17.907 -61.054742)
		(width 0.2032)
		(layer "F.Cu")
		(net "VR_PVNN_IMON")
	)
	(segment
		(start 18.18386 -60.220098)
		(end 18.590006 -60.220098)
		(width 0.2032)
		(layer "F.Cu")
		(net "VR_PVNN_IMON")
	)
	(segment
		(start 17.1196 -63.373)
		(end 17.018 -63.4746)
		(width 0.2032)
		(layer "F.Cu")
		(net "VR_PVNN_IMON")
	)
	(segment
		(start 16.3576 -62.604142)
		(end 16.4592 -62.502542)
		(width 0.2032)
		(layer "F.Cu")
		(net "VR_PVNN_IMON")
	)
	(segment
		(start 17.907 -61.054742)
		(end 17.907 -60.496958)
		(width 0.2032)
		(layer "F.Cu")
		(net "VR_PVNN_IMON")
	)
	(via
		(at 16.4592 -62.502542)
		(size 0.7112)
		(drill 0.3556)
		(layers "F.Cu" "B.Cu")
		(net "VR_PVNN_IMON")
	)
	(segment
		(start 96.393 -23.0251)
		(end 96.393 -23.0124)
		(width 0.1016)
		(layer "F.Cu")
		(net "M_B_DQS_DN1")
	)
	(segment
		(start 97.742248 -25.847294)
		(end 96.6343 -24.739346)
		(width 0.1016)
		(layer "F.Cu")
		(net "M_B_DQS_DN1")
	)
	(segment
		(start 97.742248 -26.558494)
		(end 97.742248 -25.847294)
		(width 0.1016)
		(layer "F.Cu")
		(net "M_B_DQS_DN1")
	)
	(segment
		(start 135.697468 -5.55371)
		(end 135.4328 -5.818378)
		(width 0.1778)
		(layer "F.Cu")
		(net "M_B_DQS_DN1")
	)
	(segment
		(start 135.549894 -2.402332)
		(end 135.697468 -2.549906)
		(width 0.1778)
		(layer "F.Cu")
		(net "M_B_DQS_DN1")
	)
	(segment
		(start 135.697468 -2.549906)
		(end 135.697468 -5.55371)
		(width 0.1778)
		(layer "F.Cu")
		(net "M_B_DQS_DN1")
	)
	(segment
		(start 96.6343 -23.2664)
		(end 96.393 -23.0251)
		(width 0.1016)
		(layer "F.Cu")
		(net "M_B_DQS_DN1")
	)
	(segment
		(start 135.549894 -1.68402)
		(end 135.549894 -2.402332)
		(width 0.1778)
		(layer "F.Cu")
		(net "M_B_DQS_DN1")
	)
	(segment
		(start 96.6343 -24.739346)
		(end 96.6343 -23.2664)
		(width 0.1016)
		(layer "F.Cu")
		(net "M_B_DQS_DN1")
	)
	(via
		(at 96.393 -23.0124)
		(size 0.4318)
		(drill 0.2032)
		(layers "F.Cu" "B.Cu")
		(net "M_B_DQS_DN1")
	)
	(via
		(at 135.4328 -5.818378)
		(size 0.4318)
		(drill 0.2032)
		(layers "F.Cu" "B.Cu")
		(net "M_B_DQS_DN1")
	)
	(segment
		(start 135.697468 -6.083046)
		(end 135.4328 -5.818378)
		(width 0.1778)
		(layer "B.Cu")
		(net "M_B_DQS_DN1")
	)
	(segment
		(start 135.549894 -9.130284)
		(end 135.697468 -8.98271)
		(width 0.1778)
		(layer "B.Cu")
		(net "M_B_DQS_DN1")
	)
	(segment
		(start 135.549894 -9.89076)
		(end 135.549894 -9.130284)
		(width 0.1778)
		(layer "B.Cu")
		(net "M_B_DQS_DN1")
	)
	(segment
		(start 135.697468 -8.98271)
		(end 135.697468 -6.083046)
		(width 0.1778)
		(layer "B.Cu")
		(net "M_B_DQS_DN1")
	)
	(segment
		(start 116.435378 -14.732)
		(end 116.435378 -14.349476)
		(width 0.1524)
		(layer "In2.Cu")
		(net "M_B_DQS_DN1")
	)
	(segment
		(start 108.855764 -15.036546)
		(end 106.696002 -17.196308)
		(width 0.1524)
		(layer "In2.Cu")
		(net "M_B_DQS_DN1")
	)
	(segment
		(start 115.266978 -14.884146)
		(end 115.114578 -15.036546)
		(width 0.1524)
		(layer "In2.Cu")
		(net "M_B_DQS_DN1")
	)
	(segment
		(start 116.587778 -14.8844)
		(end 116.435378 -14.732)
		(width 0.1524)
		(layer "In2.Cu")
		(net "M_B_DQS_DN1")
	)
	(segment
		(start 95.92818 -22.54758)
		(end 96.393 -23.0124)
		(width 0.1524)
		(layer "In2.Cu")
		(net "M_B_DQS_DN1")
	)
	(segment
		(start 113.5888 -15.036546)
		(end 113.436654 -14.8844)
		(width 0.1524)
		(layer "In2.Cu")
		(net "M_B_DQS_DN1")
	)
	(segment
		(start 95.92818 -20.98802)
		(end 95.92818 -22.54758)
		(width 0.1524)
		(layer "In2.Cu")
		(net "M_B_DQS_DN1")
	)
	(segment
		(start 134.303262 -13.4874)
		(end 134.150862 -13.6398)
		(width 0.1524)
		(layer "In2.Cu")
		(net "M_B_DQS_DN1")
	)
	(segment
		(start 125.626622 -13.6398)
		(end 125.502162 -13.51534)
		(width 0.1524)
		(layer "In2.Cu")
		(net "M_B_DQS_DN1")
	)
	(segment
		(start 97.6503 -19.2659)
		(end 95.92818 -20.98802)
		(width 0.1524)
		(layer "In2.Cu")
		(net "M_B_DQS_DN1")
	)
	(segment
		(start 124.338842 -13.51534)
		(end 123.881642 -13.51534)
		(width 0.1524)
		(layer "In2.Cu")
		(net "M_B_DQS_DN1")
	)
	(segment
		(start 101.548692 -17.196308)
		(end 99.4791 -19.2659)
		(width 0.1524)
		(layer "In2.Cu")
		(net "M_B_DQS_DN1")
	)
	(segment
		(start 115.582954 -14.0335)
		(end 115.266978 -14.349476)
		(width 0.1524)
		(layer "In2.Cu")
		(net "M_B_DQS_DN1")
	)
	(segment
		(start 119.558562 -13.6398)
		(end 119.434102 -13.51534)
		(width 0.1524)
		(layer "In2.Cu")
		(net "M_B_DQS_DN1")
	)
	(segment
		(start 135.4328 -5.818378)
		(end 135.710168 -6.095746)
		(width 0.1524)
		(layer "In2.Cu")
		(net "M_B_DQS_DN1")
	)
	(segment
		(start 117.4496 -14.732)
		(end 117.2972 -14.8844)
		(width 0.1524)
		(layer "In2.Cu")
		(net "M_B_DQS_DN1")
	)
	(segment
		(start 135.710168 -9.450832)
		(end 134.303262 -10.857738)
		(width 0.1524)
		(layer "In2.Cu")
		(net "M_B_DQS_DN1")
	)
	(segment
		(start 106.696002 -17.196308)
		(end 101.548692 -17.196308)
		(width 0.1524)
		(layer "In2.Cu")
		(net "M_B_DQS_DN1")
	)
	(segment
		(start 118.976902 -13.51534)
		(end 118.852442 -13.6398)
		(width 0.1524)
		(layer "In2.Cu")
		(net "M_B_DQS_DN1")
	)
	(segment
		(start 120.140222 -13.51534)
		(end 120.015762 -13.6398)
		(width 0.1524)
		(layer "In2.Cu")
		(net "M_B_DQS_DN1")
	)
	(segment
		(start 120.721882 -13.6398)
		(end 120.597422 -13.51534)
		(width 0.1524)
		(layer "In2.Cu")
		(net "M_B_DQS_DN1")
	)
	(segment
		(start 117.4496 -13.955776)
		(end 117.4496 -14.732)
		(width 0.1524)
		(layer "In2.Cu")
		(net "M_B_DQS_DN1")
	)
	(segment
		(start 123.881642 -13.51534)
		(end 123.757182 -13.6398)
		(width 0.1524)
		(layer "In2.Cu")
		(net "M_B_DQS_DN1")
	)
	(segment
		(start 120.015762 -13.6398)
		(end 119.558562 -13.6398)
		(width 0.1524)
		(layer "In2.Cu")
		(net "M_B_DQS_DN1")
	)
	(segment
		(start 125.044962 -13.51534)
		(end 124.920502 -13.6398)
		(width 0.1524)
		(layer "In2.Cu")
		(net "M_B_DQS_DN1")
	)
	(segment
		(start 118.852442 -13.6398)
		(end 117.765576 -13.6398)
		(width 0.1524)
		(layer "In2.Cu")
		(net "M_B_DQS_DN1")
	)
	(segment
		(start 115.114578 -15.036546)
		(end 113.5888 -15.036546)
		(width 0.1524)
		(layer "In2.Cu")
		(net "M_B_DQS_DN1")
	)
	(segment
		(start 116.435378 -14.349476)
		(end 116.119402 -14.0335)
		(width 0.1524)
		(layer "In2.Cu")
		(net "M_B_DQS_DN1")
	)
	(segment
		(start 113.436654 -14.8844)
		(end 112.9792 -14.8844)
		(width 0.1524)
		(layer "In2.Cu")
		(net "M_B_DQS_DN1")
	)
	(segment
		(start 125.502162 -13.51534)
		(end 125.044962 -13.51534)
		(width 0.1524)
		(layer "In2.Cu")
		(net "M_B_DQS_DN1")
	)
	(segment
		(start 134.303262 -10.857738)
		(end 134.303262 -13.4874)
		(width 0.1524)
		(layer "In2.Cu")
		(net "M_B_DQS_DN1")
	)
	(segment
		(start 112.827054 -15.036546)
		(end 108.855764 -15.036546)
		(width 0.1524)
		(layer "In2.Cu")
		(net "M_B_DQS_DN1")
	)
	(segment
		(start 121.179082 -13.6398)
		(end 120.721882 -13.6398)
		(width 0.1524)
		(layer "In2.Cu")
		(net "M_B_DQS_DN1")
	)
	(segment
		(start 123.757182 -13.6398)
		(end 121.885202 -13.6398)
		(width 0.1524)
		(layer "In2.Cu")
		(net "M_B_DQS_DN1")
	)
	(segment
		(start 119.434102 -13.51534)
		(end 118.976902 -13.51534)
		(width 0.1524)
		(layer "In2.Cu")
		(net "M_B_DQS_DN1")
	)
	(segment
		(start 121.303542 -13.51534)
		(end 121.179082 -13.6398)
		(width 0.1524)
		(layer "In2.Cu")
		(net "M_B_DQS_DN1")
	)
	(segment
		(start 121.885202 -13.6398)
		(end 121.760742 -13.51534)
		(width 0.1524)
		(layer "In2.Cu")
		(net "M_B_DQS_DN1")
	)
	(segment
		(start 115.266978 -14.349476)
		(end 115.266978 -14.884146)
		(width 0.1524)
		(layer "In2.Cu")
		(net "M_B_DQS_DN1")
	)
	(segment
		(start 116.119402 -14.0335)
		(end 115.582954 -14.0335)
		(width 0.1524)
		(layer "In2.Cu")
		(net "M_B_DQS_DN1")
	)
	(segment
		(start 124.920502 -13.6398)
		(end 124.463302 -13.6398)
		(width 0.1524)
		(layer "In2.Cu")
		(net "M_B_DQS_DN1")
	)
	(segment
		(start 99.4791 -19.2659)
		(end 97.6503 -19.2659)
		(width 0.1524)
		(layer "In2.Cu")
		(net "M_B_DQS_DN1")
	)
	(segment
		(start 117.765576 -13.6398)
		(end 117.4496 -13.955776)
		(width 0.1524)
		(layer "In2.Cu")
		(net "M_B_DQS_DN1")
	)
	(segment
		(start 135.710168 -6.095746)
		(end 135.710168 -9.450832)
		(width 0.1524)
		(layer "In2.Cu")
		(net "M_B_DQS_DN1")
	)
	(segment
		(start 124.463302 -13.6398)
		(end 124.338842 -13.51534)
		(width 0.1524)
		(layer "In2.Cu")
		(net "M_B_DQS_DN1")
	)
	(segment
		(start 120.597422 -13.51534)
		(end 120.140222 -13.51534)
		(width 0.1524)
		(layer "In2.Cu")
		(net "M_B_DQS_DN1")
	)
	(segment
		(start 117.2972 -14.8844)
		(end 116.587778 -14.8844)
		(width 0.1524)
		(layer "In2.Cu")
		(net "M_B_DQS_DN1")
	)
	(segment
		(start 121.760742 -13.51534)
		(end 121.303542 -13.51534)
		(width 0.1524)
		(layer "In2.Cu")
		(net "M_B_DQS_DN1")
	)
	(segment
		(start 112.9792 -14.8844)
		(end 112.827054 -15.036546)
		(width 0.1524)
		(layer "In2.Cu")
		(net "M_B_DQS_DN1")
	)
	(segment
		(start 134.150862 -13.6398)
		(end 125.626622 -13.6398)
		(width 0.1524)
		(layer "In2.Cu")
		(net "M_B_DQS_DN1")
	)
	(segment
		(start 88.135968 -46.497494)
		(end 88.122506 -46.497494)
		(width 0.1397)
		(layer "F.Cu")
		(net "CLK_100M_CLKBUFF_PCIE_DP")
	)
	(segment
		(start 88.122506 -46.497494)
		(end 87.757 -46.863)
		(width 0.1397)
		(layer "F.Cu")
		(net "CLK_100M_CLKBUFF_PCIE_DP")
	)
	(via
		(at 53.151786 -28.897834)
		(size 0.508)
		(drill 0.254)
		(layers "F.Cu" "B.Cu")
		(net "CLK_100M_CLKBUFF_PCIE_DP")
	)
	(via
		(at 87.757 -46.863)
		(size 0.4318)
		(drill 0.2032)
		(layers "F.Cu" "B.Cu")
		(net "CLK_100M_CLKBUFF_PCIE_DP")
	)
	(segment
		(start 48.154844 -32.774636)
		(end 47.954184 -32.975296)
		(width 0.1397)
		(layer "B.Cu")
		(net "CLK_100M_CLKBUFF_PCIE_DP")
	)
	(segment
		(start 46.714664 -32.975296)
		(end 46.295564 -32.975296)
		(width 0.1397)
		(layer "B.Cu")
		(net "CLK_100M_CLKBUFF_PCIE_DP")
	)
	(segment
		(start 47.954184 -32.975296)
		(end 47.535084 -32.975296)
		(width 0.1397)
		(layer "B.Cu")
		(net "CLK_100M_CLKBUFF_PCIE_DP")
	)
	(segment
		(start 49.632616 -32.975296)
		(end 48.774604 -32.975296)
		(width 0.1397)
		(layer "B.Cu")
		(net "CLK_100M_CLKBUFF_PCIE_DP")
	)
	(segment
		(start 42.63771 -31.18485)
		(end 42.43705 -30.98419)
		(width 0.1397)
		(layer "B.Cu")
		(net "CLK_100M_CLKBUFF_PCIE_DP")
	)
	(segment
		(start 42.43705 -31.80461)
		(end 42.63771 -31.60395)
		(width 0.1397)
		(layer "B.Cu")
		(net "CLK_100M_CLKBUFF_PCIE_DP")
	)
	(segment
		(start 48.774604 -32.975296)
		(end 48.573944 -32.774636)
		(width 0.1397)
		(layer "B.Cu")
		(net "CLK_100M_CLKBUFF_PCIE_DP")
	)
	(segment
		(start 42.63771 -31.60395)
		(end 42.63771 -31.18485)
		(width 0.1397)
		(layer "B.Cu")
		(net "CLK_100M_CLKBUFF_PCIE_DP")
	)
	(segment
		(start 45.39996 -33.8709)
		(end 44.08424 -33.8709)
		(width 0.1397)
		(layer "B.Cu")
		(net "CLK_100M_CLKBUFF_PCIE_DP")
	)
	(segment
		(start 42.6466 -28.7274)
		(end 42.672 -28.7528)
		(width 0.1397)
		(layer "B.Cu")
		(net "CLK_100M_CLKBUFF_PCIE_DP")
	)
	(segment
		(start 42.43705 -28.98775)
		(end 42.672 -28.7528)
		(width 0.1397)
		(layer "B.Cu")
		(net "CLK_100M_CLKBUFF_PCIE_DP")
	)
	(segment
		(start 46.915324 -32.774636)
		(end 46.714664 -32.975296)
		(width 0.1397)
		(layer "B.Cu")
		(net "CLK_100M_CLKBUFF_PCIE_DP")
	)
	(segment
		(start 42.43705 -29.74467)
		(end 42.43705 -28.98775)
		(width 0.1397)
		(layer "B.Cu")
		(net "CLK_100M_CLKBUFF_PCIE_DP")
	)
	(segment
		(start 42.43705 -30.56509)
		(end 42.63771 -30.36443)
		(width 0.1397)
		(layer "B.Cu")
		(net "CLK_100M_CLKBUFF_PCIE_DP")
	)
	(segment
		(start 42.43705 -30.98419)
		(end 42.43705 -30.56509)
		(width 0.1397)
		(layer "B.Cu")
		(net "CLK_100M_CLKBUFF_PCIE_DP")
	)
	(segment
		(start 46.295564 -32.975296)
		(end 45.39996 -33.8709)
		(width 0.1397)
		(layer "B.Cu")
		(net "CLK_100M_CLKBUFF_PCIE_DP")
	)
	(segment
		(start 44.08424 -33.8709)
		(end 42.43705 -32.22371)
		(width 0.1397)
		(layer "B.Cu")
		(net "CLK_100M_CLKBUFF_PCIE_DP")
	)
	(segment
		(start 48.573944 -32.774636)
		(end 48.154844 -32.774636)
		(width 0.1397)
		(layer "B.Cu")
		(net "CLK_100M_CLKBUFF_PCIE_DP")
	)
	(segment
		(start 47.535084 -32.975296)
		(end 47.334424 -32.774636)
		(width 0.1397)
		(layer "B.Cu")
		(net "CLK_100M_CLKBUFF_PCIE_DP")
	)
	(segment
		(start 42.6466 -27.9654)
		(end 42.6466 -28.7274)
		(width 0.1397)
		(layer "B.Cu")
		(net "CLK_100M_CLKBUFF_PCIE_DP")
	)
	(segment
		(start 47.334424 -32.774636)
		(end 46.915324 -32.774636)
		(width 0.1397)
		(layer "B.Cu")
		(net "CLK_100M_CLKBUFF_PCIE_DP")
	)
	(segment
		(start 53.151786 -28.897834)
		(end 52.85232 -29.1973)
		(width 0.1397)
		(layer "B.Cu")
		(net "CLK_100M_CLKBUFF_PCIE_DP")
	)
	(segment
		(start 42.63771 -30.36443)
		(end 42.63771 -29.94533)
		(width 0.1397)
		(layer "B.Cu")
		(net "CLK_100M_CLKBUFF_PCIE_DP")
	)
	(segment
		(start 51.4604 -31.147512)
		(end 49.632616 -32.975296)
		(width 0.1397)
		(layer "B.Cu")
		(net "CLK_100M_CLKBUFF_PCIE_DP")
	)
	(segment
		(start 42.63771 -29.94533)
		(end 42.43705 -29.74467)
		(width 0.1397)
		(layer "B.Cu")
		(net "CLK_100M_CLKBUFF_PCIE_DP")
	)
	(segment
		(start 42.43705 -32.22371)
		(end 42.43705 -31.80461)
		(width 0.1397)
		(layer "B.Cu")
		(net "CLK_100M_CLKBUFF_PCIE_DP")
	)
	(segment
		(start 51.4604 -29.6672)
		(end 51.4604 -31.147512)
		(width 0.1397)
		(layer "B.Cu")
		(net "CLK_100M_CLKBUFF_PCIE_DP")
	)
	(segment
		(start 52.85232 -29.1973)
		(end 51.9303 -29.1973)
		(width 0.1397)
		(layer "B.Cu")
		(net "CLK_100M_CLKBUFF_PCIE_DP")
	)
	(segment
		(start 51.9303 -29.1973)
		(end 51.4604 -29.6672)
		(width 0.1397)
		(layer "B.Cu")
		(net "CLK_100M_CLKBUFF_PCIE_DP")
	)
	(segment
		(start 85.583776 -42.497248)
		(end 85.72373 -42.497248)
		(width 0.1016)
		(layer "In7.Cu")
		(net "CLK_100M_CLKBUFF_PCIE_DP")
	)
	(segment
		(start 73.668128 -31.0642)
		(end 74.914506 -32.310578)
		(width 0.1143)
		(layer "In7.Cu")
		(net "CLK_100M_CLKBUFF_PCIE_DP")
	)
	(segment
		(start 81.182972 -39.922704)
		(end 82.042 -40.781732)
		(width 0.1016)
		(layer "In7.Cu")
		(net "CLK_100M_CLKBUFF_PCIE_DP")
	)
	(segment
		(start 85.72373 -42.497248)
		(end 85.939376 -42.71264)
		(width 0.1016)
		(layer "In7.Cu")
		(net "CLK_100M_CLKBUFF_PCIE_DP")
	)
	(segment
		(start 87.170768 -44.947078)
		(end 87.170768 -45.556678)
		(width 0.1016)
		(layer "In7.Cu")
		(net "CLK_100M_CLKBUFF_PCIE_DP")
	)
	(segment
		(start 66.982848 -31.0642)
		(end 73.668128 -31.0642)
		(width 0.1143)
		(layer "In7.Cu")
		(net "CLK_100M_CLKBUFF_PCIE_DP")
	)
	(segment
		(start 54.924706 -29.6926)
		(end 65.611248 -29.6926)
		(width 0.1143)
		(layer "In7.Cu")
		(net "CLK_100M_CLKBUFF_PCIE_DP")
	)
	(segment
		(start 75.41895 -32.79775)
		(end 76.0984 -33.4772)
		(width 0.1143)
		(layer "In7.Cu")
		(net "CLK_100M_CLKBUFF_PCIE_DP")
	)
	(segment
		(start 81.164938 -39.814754)
		(end 81.182972 -39.832788)
		(width 0.1016)
		(layer "In7.Cu")
		(net "CLK_100M_CLKBUFF_PCIE_DP")
	)
	(segment
		(start 82.439256 -41.499536)
		(end 83.110324 -41.499536)
		(width 0.1016)
		(layer "In7.Cu")
		(net "CLK_100M_CLKBUFF_PCIE_DP")
	)
	(segment
		(start 75.15606 -32.79775)
		(end 75.41895 -32.79775)
		(width 0.1143)
		(layer "In7.Cu")
		(net "CLK_100M_CLKBUFF_PCIE_DP")
	)
	(segment
		(start 85.939376 -42.71264)
		(end 85.939376 -42.852848)
		(width 0.1016)
		(layer "In7.Cu")
		(net "CLK_100M_CLKBUFF_PCIE_DP")
	)
	(segment
		(start 87.269828 -44.848018)
		(end 87.170768 -44.947078)
		(width 0.1016)
		(layer "In7.Cu")
		(net "CLK_100M_CLKBUFF_PCIE_DP")
	)
	(segment
		(start 76.0984 -34.748216)
		(end 81.164938 -39.814754)
		(width 0.1143)
		(layer "In7.Cu")
		(net "CLK_100M_CLKBUFF_PCIE_DP")
	)
	(segment
		(start 87.269828 -44.543218)
		(end 87.269828 -44.848018)
		(width 0.1016)
		(layer "In7.Cu")
		(net "CLK_100M_CLKBUFF_PCIE_DP")
	)
	(segment
		(start 85.36813 -42.281602)
		(end 85.583776 -42.497248)
		(width 0.1016)
		(layer "In7.Cu")
		(net "CLK_100M_CLKBUFF_PCIE_DP")
	)
	(segment
		(start 87.541354 -45.927264)
		(end 87.541354 -46.647354)
		(width 0.1016)
		(layer "In7.Cu")
		(net "CLK_100M_CLKBUFF_PCIE_DP")
	)
	(segment
		(start 76.0984 -33.4772)
		(end 76.0984 -34.748216)
		(width 0.1143)
		(layer "In7.Cu")
		(net "CLK_100M_CLKBUFF_PCIE_DP")
	)
	(segment
		(start 83.89239 -42.281602)
		(end 85.36813 -42.281602)
		(width 0.1016)
		(layer "In7.Cu")
		(net "CLK_100M_CLKBUFF_PCIE_DP")
	)
	(segment
		(start 87.170768 -44.444158)
		(end 87.269828 -44.543218)
		(width 0.1016)
		(layer "In7.Cu")
		(net "CLK_100M_CLKBUFF_PCIE_DP")
	)
	(segment
		(start 53.451252 -29.1973)
		(end 54.429406 -29.1973)
		(width 0.1143)
		(layer "In7.Cu")
		(net "CLK_100M_CLKBUFF_PCIE_DP")
	)
	(segment
		(start 81.182972 -39.832788)
		(end 81.182972 -39.922704)
		(width 0.1016)
		(layer "In7.Cu")
		(net "CLK_100M_CLKBUFF_PCIE_DP")
	)
	(segment
		(start 53.151786 -28.897834)
		(end 53.451252 -29.1973)
		(width 0.1143)
		(layer "In7.Cu")
		(net "CLK_100M_CLKBUFF_PCIE_DP")
	)
	(segment
		(start 82.042 -41.10228)
		(end 82.439256 -41.499536)
		(width 0.1016)
		(layer "In7.Cu")
		(net "CLK_100M_CLKBUFF_PCIE_DP")
	)
	(segment
		(start 87.170768 -45.556678)
		(end 87.541354 -45.927264)
		(width 0.1016)
		(layer "In7.Cu")
		(net "CLK_100M_CLKBUFF_PCIE_DP")
	)
	(segment
		(start 74.914506 -32.556196)
		(end 75.15606 -32.79775)
		(width 0.1143)
		(layer "In7.Cu")
		(net "CLK_100M_CLKBUFF_PCIE_DP")
	)
	(segment
		(start 82.042 -40.781732)
		(end 82.042 -41.10228)
		(width 0.1016)
		(layer "In7.Cu")
		(net "CLK_100M_CLKBUFF_PCIE_DP")
	)
	(segment
		(start 83.110324 -41.499536)
		(end 83.89239 -42.281602)
		(width 0.1016)
		(layer "In7.Cu")
		(net "CLK_100M_CLKBUFF_PCIE_DP")
	)
	(segment
		(start 87.541354 -46.647354)
		(end 87.757 -46.863)
		(width 0.1016)
		(layer "In7.Cu")
		(net "CLK_100M_CLKBUFF_PCIE_DP")
	)
	(segment
		(start 85.939376 -42.852848)
		(end 87.170768 -44.08424)
		(width 0.1016)
		(layer "In7.Cu")
		(net "CLK_100M_CLKBUFF_PCIE_DP")
	)
	(segment
		(start 54.429406 -29.1973)
		(end 54.924706 -29.6926)
		(width 0.1143)
		(layer "In7.Cu")
		(net "CLK_100M_CLKBUFF_PCIE_DP")
	)
	(segment
		(start 87.170768 -44.08424)
		(end 87.170768 -44.444158)
		(width 0.1016)
		(layer "In7.Cu")
		(net "CLK_100M_CLKBUFF_PCIE_DP")
	)
	(segment
		(start 65.611248 -29.6926)
		(end 66.982848 -31.0642)
		(width 0.1143)
		(layer "In7.Cu")
		(net "CLK_100M_CLKBUFF_PCIE_DP")
	)
	(segment
		(start 74.914506 -32.310578)
		(end 74.914506 -32.556196)
		(width 0.1143)
		(layer "In7.Cu")
		(net "CLK_100M_CLKBUFF_PCIE_DP")
	)
	(segment
		(start 25.542748 -57.820052)
		(end 26.416 -56.9468)
		(width 0.2032)
		(layer "F.Cu")
		(net "VR_PVCCP_GL")
	)
	(segment
		(start 24.335994 -57.820052)
		(end 25.542748 -57.820052)
		(width 0.2032)
		(layer "F.Cu")
		(net "VR_PVCCP_GL")
	)
	(segment
		(start 106.251248 -30.7594)
		(end 106.251248 -30.759654)
		(width 0.1016)
		(layer "F.Cu")
		(net "M_B_CK_DN3")
	)
	(segment
		(start 106.378248 -30.6324)
		(end 106.251248 -30.7594)
		(width 0.1016)
		(layer "F.Cu")
		(net "M_B_CK_DN3")
	)
	(segment
		(start 164.9857 -7.856728)
		(end 164.9857 -7.824978)
		(width 0.2159)
		(layer "F.Cu")
		(net "M_B_CK_DN3")
	)
	(segment
		(start 106.850688 -30.6324)
		(end 106.378248 -30.6324)
		(width 0.1016)
		(layer "F.Cu")
		(net "M_B_CK_DN3")
	)
	(segment
		(start 164.649912 -8.192516)
		(end 164.9857 -7.856728)
		(width 0.2159)
		(layer "F.Cu")
		(net "M_B_CK_DN3")
	)
	(segment
		(start 164.649912 -9.897364)
		(end 164.649912 -8.192516)
		(width 0.2159)
		(layer "F.Cu")
		(net "M_B_CK_DN3")
	)
	(via
		(at 106.850688 -30.6324)
		(size 0.4318)
		(drill 0.2032)
		(layers "F.Cu" "B.Cu")
		(net "M_B_CK_DN3")
	)
	(via
		(at 164.9857 -7.824978)
		(size 0.4318)
		(drill 0.2032)
		(layers "F.Cu" "B.Cu")
		(net "M_B_CK_DN3")
	)
	(segment
		(start 149.4663 -20.4597)
		(end 114.5413 -20.4597)
		(width 0.1905)
		(layer "In9.Cu")
		(net "M_B_CK_DN3")
	)
	(segment
		(start 162.09645 -11.082528)
		(end 161.798 -11.380978)
		(width 0.1905)
		(layer "In9.Cu")
		(net "M_B_CK_DN3")
	)
	(segment
		(start 106.209084 -28.4861)
		(end 106.209084 -28.972256)
		(width 0.1016)
		(layer "In9.Cu")
		(net "M_B_CK_DN3")
	)
	(segment
		(start 152.7556 -19.198336)
		(end 152.357836 -19.5961)
		(width 0.1905)
		(layer "In9.Cu")
		(net "M_B_CK_DN3")
	)
	(segment
		(start 159.6898 -13.3604)
		(end 156.3878 -16.6624)
		(width 0.1905)
		(layer "In9.Cu")
		(net "M_B_CK_DN3")
	)
	(segment
		(start 151.1554 -19.198336)
		(end 151.1554 -16.8529)
		(width 0.1905)
		(layer "In9.Cu")
		(net "M_B_CK_DN3")
	)
	(segment
		(start 152.357836 -19.5961)
		(end 151.553164 -19.5961)
		(width 0.1905)
		(layer "In9.Cu")
		(net "M_B_CK_DN3")
	)
	(segment
		(start 150.114 -16.8148)
		(end 150.114 -19.812)
		(width 0.1905)
		(layer "In9.Cu")
		(net "M_B_CK_DN3")
	)
	(segment
		(start 164.66185 -10.258298)
		(end 163.83762 -11.082528)
		(width 0.1905)
		(layer "In9.Cu")
		(net "M_B_CK_DN3")
	)
	(segment
		(start 109.6518 -25.254966)
		(end 109.6518 -27.242262)
		(width 0.1016)
		(layer "In9.Cu")
		(net "M_B_CK_DN3")
	)
	(segment
		(start 109.268006 -27.626056)
		(end 107.069128 -27.626056)
		(width 0.1016)
		(layer "In9.Cu")
		(net "M_B_CK_DN3")
	)
	(segment
		(start 150.114 -19.812)
		(end 149.4663 -20.4597)
		(width 0.1905)
		(layer "In9.Cu")
		(net "M_B_CK_DN3")
	)
	(segment
		(start 164.66185 -8.148828)
		(end 164.66185 -10.258298)
		(width 0.1905)
		(layer "In9.Cu")
		(net "M_B_CK_DN3")
	)
	(segment
		(start 107.159044 -30.324044)
		(end 106.850688 -30.6324)
		(width 0.1016)
		(layer "In9.Cu")
		(net "M_B_CK_DN3")
	)
	(segment
		(start 107.069128 -27.626056)
		(end 106.209084 -28.4861)
		(width 0.1016)
		(layer "In9.Cu")
		(net "M_B_CK_DN3")
	)
	(segment
		(start 109.6518 -27.242262)
		(end 109.268006 -27.626056)
		(width 0.1016)
		(layer "In9.Cu")
		(net "M_B_CK_DN3")
	)
	(segment
		(start 152.7556 -16.8529)
		(end 152.7556 -19.198336)
		(width 0.1905)
		(layer "In9.Cu")
		(net "M_B_CK_DN3")
	)
	(segment
		(start 163.83762 -11.082528)
		(end 162.09645 -11.082528)
		(width 0.1905)
		(layer "In9.Cu")
		(net "M_B_CK_DN3")
	)
	(segment
		(start 150.2664 -16.6624)
		(end 150.114 -16.8148)
		(width 0.1905)
		(layer "In9.Cu")
		(net "M_B_CK_DN3")
	)
	(segment
		(start 151.1554 -16.8529)
		(end 150.9649 -16.6624)
		(width 0.1905)
		(layer "In9.Cu")
		(net "M_B_CK_DN3")
	)
	(segment
		(start 156.3878 -16.6624)
		(end 152.9461 -16.6624)
		(width 0.1905)
		(layer "In9.Cu")
		(net "M_B_CK_DN3")
	)
	(segment
		(start 110.1598 -24.8412)
		(end 110.065566 -24.8412)
		(width 0.1016)
		(layer "In9.Cu")
		(net "M_B_CK_DN3")
	)
	(segment
		(start 161.3408 -13.3604)
		(end 159.6898 -13.3604)
		(width 0.1905)
		(layer "In9.Cu")
		(net "M_B_CK_DN3")
	)
	(segment
		(start 151.553164 -19.5961)
		(end 151.1554 -19.198336)
		(width 0.1905)
		(layer "In9.Cu")
		(net "M_B_CK_DN3")
	)
	(segment
		(start 107.1626 -29.7688)
		(end 107.2134 -29.8196)
		(width 0.1016)
		(layer "In9.Cu")
		(net "M_B_CK_DN3")
	)
	(segment
		(start 150.9649 -16.6624)
		(end 150.2664 -16.6624)
		(width 0.1905)
		(layer "In9.Cu")
		(net "M_B_CK_DN3")
	)
	(segment
		(start 110.065566 -24.8412)
		(end 109.6518 -25.254966)
		(width 0.1016)
		(layer "In9.Cu")
		(net "M_B_CK_DN3")
	)
	(segment
		(start 161.798 -11.380978)
		(end 161.798 -12.9032)
		(width 0.1905)
		(layer "In9.Cu")
		(net "M_B_CK_DN3")
	)
	(segment
		(start 161.798 -12.9032)
		(end 161.3408 -13.3604)
		(width 0.1905)
		(layer "In9.Cu")
		(net "M_B_CK_DN3")
	)
	(segment
		(start 114.5413 -20.4597)
		(end 110.1598 -24.8412)
		(width 0.1905)
		(layer "In9.Cu")
		(net "M_B_CK_DN3")
	)
	(segment
		(start 164.9857 -7.824978)
		(end 164.66185 -8.148828)
		(width 0.1905)
		(layer "In9.Cu")
		(net "M_B_CK_DN3")
	)
	(segment
		(start 106.209084 -28.972256)
		(end 106.878628 -29.6418)
		(width 0.1016)
		(layer "In9.Cu")
		(net "M_B_CK_DN3")
	)
	(segment
		(start 152.9461 -16.6624)
		(end 152.7556 -16.8529)
		(width 0.1905)
		(layer "In9.Cu")
		(net "M_B_CK_DN3")
	)
	(arc
		(start 107.2642 -30.0482)
		(mid 107.237014 -30.195799)
		(end 107.159044 -30.324044)
		(width 0.1016)
		(layer "In9.Cu")
		(net "M_B_CK_DN3")
	)
	(arc
		(start 107.2134 -29.8196)
		(mid 107.251347 -29.931112)
		(end 107.2642 -30.0482)
		(width 0.1016)
		(layer "In9.Cu")
		(net "M_B_CK_DN3")
	)
	(arc
		(start 106.878628 -29.6418)
		(mid 107.034168 -29.674995)
		(end 107.1626 -29.7688)
		(width 0.1016)
		(layer "In9.Cu")
		(net "M_B_CK_DN3")
	)
	(segment
		(start 186.4868 -21.1328)
		(end 186.4868 -21.6662)
		(width 0.254)
		(layer "F.Cu")
		(net "PV_VTT_DDR_B_EN")
	)
	(segment
		(start 186.260486 -20.15871)
		(end 186.26836 -20.166584)
		(width 0.254)
		(layer "F.Cu")
		(net "PV_VTT_DDR_B_EN")
	)
	(segment
		(start 186.26836 -20.91436)
		(end 186.4868 -21.1328)
		(width 0.254)
		(layer "F.Cu")
		(net "PV_VTT_DDR_B_EN")
	)
	(segment
		(start 186.26836 -20.166584)
		(end 186.26836 -20.91436)
		(width 0.254)
		(layer "F.Cu")
		(net "PV_VTT_DDR_B_EN")
	)
	(segment
		(start 185.6994 -22.4536)
		(end 186.4868 -21.6662)
		(width 0.254)
		(layer "F.Cu")
		(net "PV_VTT_DDR_B_EN")
	)
	(segment
		(start 185.674 -22.4536)
		(end 185.6994 -22.4536)
		(width 0.254)
		(layer "F.Cu")
		(net "PV_VTT_DDR_B_EN")
	)
	(via
		(at 186.4868 -21.6662)
		(size 0.7112)
		(drill 0.3556)
		(layers "F.Cu" "B.Cu")
		(net "PV_VTT_DDR_B_EN")
	)
	(segment
		(start 143.050006 -9.044432)
		(end 143.16964 -8.924798)
		(width 0.1778)
		(layer "F.Cu")
		(net "M_B_DQ19")
	)
	(segment
		(start 143.16964 -8.924798)
		(end 143.16964 -8.190484)
		(width 0.1778)
		(layer "F.Cu")
		(net "M_B_DQ19")
	)
	(segment
		(start 143.16964 -8.190484)
		(end 143.533114 -7.82701)
		(width 0.1778)
		(layer "F.Cu")
		(net "M_B_DQ19")
	)
	(segment
		(start 102.546404 -21.291804)
		(end 102.997 -21.7424)
		(width 0.1016)
		(layer "F.Cu")
		(net "M_B_DQ19")
	)
	(segment
		(start 102.997 -21.7424)
		(end 102.997 -23.8506)
		(width 0.1016)
		(layer "F.Cu")
		(net "M_B_DQ19")
	)
	(segment
		(start 102.997 -23.8506)
		(end 102.9462 -23.9014)
		(width 0.1016)
		(layer "F.Cu")
		(net "M_B_DQ19")
	)
	(segment
		(start 102.9462 -23.9014)
		(end 102.9462 -26.104088)
		(width 0.1016)
		(layer "F.Cu")
		(net "M_B_DQ19")
	)
	(segment
		(start 102.9462 -26.104088)
		(end 103.170228 -26.328116)
		(width 0.1016)
		(layer "F.Cu")
		(net "M_B_DQ19")
	)
	(segment
		(start 103.170228 -26.328116)
		(end 103.170228 -26.561034)
		(width 0.1016)
		(layer "F.Cu")
		(net "M_B_DQ19")
	)
	(segment
		(start 143.050006 -9.897364)
		(end 143.050006 -9.044432)
		(width 0.1778)
		(layer "F.Cu")
		(net "M_B_DQ19")
	)
	(via
		(at 102.546404 -21.291804)
		(size 0.4318)
		(drill 0.2032)
		(layers "F.Cu" "B.Cu")
		(net "M_B_DQ19")
	)
	(via
		(at 143.533114 -7.82701)
		(size 0.4318)
		(drill 0.2032)
		(layers "F.Cu" "B.Cu")
		(net "M_B_DQ19")
	)
	(segment
		(start 143.14678 -8.213344)
		(end 143.533114 -7.82701)
		(width 0.1778)
		(layer "B.Cu")
		(net "M_B_DQ19")
	)
	(segment
		(start 143.14678 -8.764778)
		(end 143.14678 -8.213344)
		(width 0.1778)
		(layer "B.Cu")
		(net "M_B_DQ19")
	)
	(segment
		(start 143.34998 -8.967978)
		(end 143.14678 -8.764778)
		(width 0.1778)
		(layer "B.Cu")
		(net "M_B_DQ19")
	)
	(segment
		(start 143.34998 -9.89076)
		(end 143.34998 -8.967978)
		(width 0.1778)
		(layer "B.Cu")
		(net "M_B_DQ19")
	)
	(segment
		(start 116.6368 -16.4338)
		(end 116.7892 -16.5862)
		(width 0.1524)
		(layer "In4.Cu")
		(net "M_B_DQ19")
	)
	(segment
		(start 115.57 -17.2212)
		(end 115.7224 -17.3736)
		(width 0.1524)
		(layer "In4.Cu")
		(net "M_B_DQ19")
	)
	(segment
		(start 115.57 -16.5862)
		(end 115.57 -17.2212)
		(width 0.1524)
		(layer "In4.Cu")
		(net "M_B_DQ19")
	)
	(segment
		(start 116.1796 -17.2212)
		(end 116.1796 -16.5862)
		(width 0.1524)
		(layer "In4.Cu")
		(net "M_B_DQ19")
	)
	(segment
		(start 104.7242 -19.9644)
		(end 104.8512 -19.8374)
		(width 0.1524)
		(layer "In4.Cu")
		(net "M_B_DQ19")
	)
	(segment
		(start 115.4176 -16.4338)
		(end 115.57 -16.5862)
		(width 0.1524)
		(layer "In4.Cu")
		(net "M_B_DQ19")
	)
	(segment
		(start 115.7224 -17.3736)
		(end 116.0272 -17.3736)
		(width 0.1524)
		(layer "In4.Cu")
		(net "M_B_DQ19")
	)
	(segment
		(start 117.7036 -17.2212)
		(end 117.7036 -16.2306)
		(width 0.1524)
		(layer "In4.Cu")
		(net "M_B_DQ19")
	)
	(segment
		(start 104.8512 -19.8374)
		(end 110.98911 -19.8374)
		(width 0.1524)
		(layer "In4.Cu")
		(net "M_B_DQ19")
	)
	(segment
		(start 139.3952 -16.0782)
		(end 141.2367 -14.2367)
		(width 0.1524)
		(layer "In4.Cu")
		(net "M_B_DQ19")
	)
	(segment
		(start 114.9604 -16.5862)
		(end 115.1128 -16.4338)
		(width 0.1524)
		(layer "In4.Cu")
		(net "M_B_DQ19")
	)
	(segment
		(start 117.5512 -17.3736)
		(end 117.7036 -17.2212)
		(width 0.1524)
		(layer "In4.Cu")
		(net "M_B_DQ19")
	)
	(segment
		(start 103.5304 -19.9644)
		(end 104.7242 -19.9644)
		(width 0.1016)
		(layer "In4.Cu")
		(net "M_B_DQ19")
	)
	(segment
		(start 116.7892 -16.5862)
		(end 116.7892 -17.2212)
		(width 0.1524)
		(layer "In4.Cu")
		(net "M_B_DQ19")
	)
	(segment
		(start 143.1798 -10.6172)
		(end 143.1798 -8.180324)
		(width 0.1524)
		(layer "In4.Cu")
		(net "M_B_DQ19")
	)
	(segment
		(start 117.856 -16.0782)
		(end 139.3952 -16.0782)
		(width 0.1524)
		(layer "In4.Cu")
		(net "M_B_DQ19")
	)
	(segment
		(start 116.7892 -17.2212)
		(end 116.9416 -17.3736)
		(width 0.1524)
		(layer "In4.Cu")
		(net "M_B_DQ19")
	)
	(segment
		(start 141.2367 -12.5603)
		(end 143.1798 -10.6172)
		(width 0.1524)
		(layer "In4.Cu")
		(net "M_B_DQ19")
	)
	(segment
		(start 115.1128 -16.4338)
		(end 115.4176 -16.4338)
		(width 0.1524)
		(layer "In4.Cu")
		(net "M_B_DQ19")
	)
	(segment
		(start 141.2367 -14.2367)
		(end 141.2367 -12.5603)
		(width 0.1524)
		(layer "In4.Cu")
		(net "M_B_DQ19")
	)
	(segment
		(start 116.9416 -17.3736)
		(end 117.5512 -17.3736)
		(width 0.1524)
		(layer "In4.Cu")
		(net "M_B_DQ19")
	)
	(segment
		(start 116.0272 -17.3736)
		(end 116.1796 -17.2212)
		(width 0.1524)
		(layer "In4.Cu")
		(net "M_B_DQ19")
	)
	(segment
		(start 113.45291 -17.3736)
		(end 114.808 -17.3736)
		(width 0.1524)
		(layer "In4.Cu")
		(net "M_B_DQ19")
	)
	(segment
		(start 114.808 -17.3736)
		(end 114.9604 -17.2212)
		(width 0.1524)
		(layer "In4.Cu")
		(net "M_B_DQ19")
	)
	(segment
		(start 102.546404 -20.948396)
		(end 103.5304 -19.9644)
		(width 0.1016)
		(layer "In4.Cu")
		(net "M_B_DQ19")
	)
	(segment
		(start 117.7036 -16.2306)
		(end 117.856 -16.0782)
		(width 0.1524)
		(layer "In4.Cu")
		(net "M_B_DQ19")
	)
	(segment
		(start 143.1798 -8.180324)
		(end 143.533114 -7.82701)
		(width 0.1524)
		(layer "In4.Cu")
		(net "M_B_DQ19")
	)
	(segment
		(start 102.546404 -21.291804)
		(end 102.546404 -20.948396)
		(width 0.1016)
		(layer "In4.Cu")
		(net "M_B_DQ19")
	)
	(segment
		(start 114.9604 -17.2212)
		(end 114.9604 -16.5862)
		(width 0.1524)
		(layer "In4.Cu")
		(net "M_B_DQ19")
	)
	(segment
		(start 116.332 -16.4338)
		(end 116.6368 -16.4338)
		(width 0.1524)
		(layer "In4.Cu")
		(net "M_B_DQ19")
	)
	(segment
		(start 116.1796 -16.5862)
		(end 116.332 -16.4338)
		(width 0.1524)
		(layer "In4.Cu")
		(net "M_B_DQ19")
	)
	(segment
		(start 110.98911 -19.8374)
		(end 113.45291 -17.3736)
		(width 0.1524)
		(layer "In4.Cu")
		(net "M_B_DQ19")
	)
	(segment
		(start 16.3068 -68.453)
		(end 16.4338 -68.58)
		(width 0.127)
		(layer "F.Cu")
		(net "LED_NGFF_DAS")
	)
	(segment
		(start 16.4338 -68.58)
		(end 16.4338 -69.215)
		(width 0.127)
		(layer "F.Cu")
		(net "LED_NGFF_DAS")
	)
	(via
		(at 7.4676 -45.72)
		(size 0.508)
		(drill 0.254)
		(layers "F.Cu" "B.Cu")
		(net "LED_NGFF_DAS")
	)
	(via
		(at 16.4338 -69.215)
		(size 0.508)
		(drill 0.254)
		(layers "F.Cu" "B.Cu")
		(net "LED_NGFF_DAS")
	)
	(via
		(at 6.9596 -44.0944)
		(size 0.7112)
		(drill 0.3556)
		(layers "F.Cu" "B.Cu")
		(net "LED_NGFF_DAS")
	)
	(segment
		(start 13.125196 -65.699894)
		(end 12.192 -65.699894)
		(width 0.127)
		(layer "B.Cu")
		(net "LED_NGFF_DAS")
	)
	(segment
		(start 11.8237 -66.068194)
		(end 11.8237 -68.7197)
		(width 0.127)
		(layer "B.Cu")
		(net "LED_NGFF_DAS")
	)
	(segment
		(start 7.4676 -44.6024)
		(end 6.9596 -44.0944)
		(width 0.127)
		(layer "B.Cu")
		(net "LED_NGFF_DAS")
	)
	(segment
		(start 5.164074 -44.0944)
		(end 4.826 -44.432474)
		(width 0.127)
		(layer "B.Cu")
		(net "LED_NGFF_DAS")
	)
	(segment
		(start 6.9596 -44.0944)
		(end 5.164074 -44.0944)
		(width 0.127)
		(layer "B.Cu")
		(net "LED_NGFF_DAS")
	)
	(segment
		(start 7.4676 -45.72)
		(end 7.4676 -44.6024)
		(width 0.127)
		(layer "B.Cu")
		(net "LED_NGFF_DAS")
	)
	(segment
		(start 12.573 -69.469)
		(end 15.3162 -69.469)
		(width 0.127)
		(layer "B.Cu")
		(net "LED_NGFF_DAS")
	)
	(segment
		(start 15.3162 -69.469)
		(end 15.621 -69.1642)
		(width 0.127)
		(layer "B.Cu")
		(net "LED_NGFF_DAS")
	)
	(segment
		(start 12.192 -65.699894)
		(end 11.8237 -66.068194)
		(width 0.127)
		(layer "B.Cu")
		(net "LED_NGFF_DAS")
	)
	(segment
		(start 15.621 -69.1642)
		(end 16.383 -69.1642)
		(width 0.127)
		(layer "B.Cu")
		(net "LED_NGFF_DAS")
	)
	(segment
		(start 11.8237 -68.7197)
		(end 12.573 -69.469)
		(width 0.127)
		(layer "B.Cu")
		(net "LED_NGFF_DAS")
	)
	(segment
		(start 16.383 -69.1642)
		(end 16.4338 -69.215)
		(width 0.127)
		(layer "B.Cu")
		(net "LED_NGFF_DAS")
	)
	(segment
		(start 12.6238 -49.62779)
		(end 13.1318 -50.13579)
		(width 0.127)
		(layer "In2.Cu")
		(net "LED_NGFF_DAS")
	)
	(segment
		(start 11.56081 -46.9392)
		(end 12.6238 -48.00219)
		(width 0.127)
		(layer "In2.Cu")
		(net "LED_NGFF_DAS")
	)
	(segment
		(start 12.674346 -69.3293)
		(end 16.3195 -69.3293)
		(width 0.127)
		(layer "In2.Cu")
		(net "LED_NGFF_DAS")
	)
	(segment
		(start 13.1318 -50.13579)
		(end 13.1318 -59.5122)
		(width 0.127)
		(layer "In2.Cu")
		(net "LED_NGFF_DAS")
	)
	(segment
		(start 12.2174 -60.4266)
		(end 12.2174 -67.2338)
		(width 0.127)
		(layer "In2.Cu")
		(net "LED_NGFF_DAS")
	)
	(segment
		(start 12.2047 -67.2465)
		(end 12.2047 -68.859654)
		(width 0.127)
		(layer "In2.Cu")
		(net "LED_NGFF_DAS")
	)
	(segment
		(start 12.2174 -67.2338)
		(end 12.2047 -67.2465)
		(width 0.127)
		(layer "In2.Cu")
		(net "LED_NGFF_DAS")
	)
	(segment
		(start 7.4676 -45.72)
		(end 7.4676 -46.3296)
		(width 0.127)
		(layer "In2.Cu")
		(net "LED_NGFF_DAS")
	)
	(segment
		(start 12.6238 -48.00219)
		(end 12.6238 -49.62779)
		(width 0.127)
		(layer "In2.Cu")
		(net "LED_NGFF_DAS")
	)
	(segment
		(start 7.4676 -46.3296)
		(end 8.0772 -46.9392)
		(width 0.127)
		(layer "In2.Cu")
		(net "LED_NGFF_DAS")
	)
	(segment
		(start 16.3195 -69.3293)
		(end 16.4338 -69.215)
		(width 0.127)
		(layer "In2.Cu")
		(net "LED_NGFF_DAS")
	)
	(segment
		(start 8.0772 -46.9392)
		(end 11.56081 -46.9392)
		(width 0.127)
		(layer "In2.Cu")
		(net "LED_NGFF_DAS")
	)
	(segment
		(start 13.1318 -59.5122)
		(end 12.2174 -60.4266)
		(width 0.127)
		(layer "In2.Cu")
		(net "LED_NGFF_DAS")
	)
	(segment
		(start 12.2047 -68.859654)
		(end 12.674346 -69.3293)
		(width 0.127)
		(layer "In2.Cu")
		(net "LED_NGFF_DAS")
	)
	(segment
		(start 21.9202 -62.468506)
		(end 21.732748 -62.281054)
		(width 0.2032)
		(layer "F.Cu")
		(net "VR_PVNN_NTC")
	)
	(segment
		(start 21.662898 -62.19444)
		(end 21.662898 -61.292994)
		(width 0.2032)
		(layer "F.Cu")
		(net "VR_PVNN_NTC")
	)
	(segment
		(start 21.9202 -63.2968)
		(end 21.9202 -62.468506)
		(width 0.2032)
		(layer "F.Cu")
		(net "VR_PVNN_NTC")
	)
	(segment
		(start 21.9964 -63.373)
		(end 21.9202 -63.2968)
		(width 0.2032)
		(layer "F.Cu")
		(net "VR_PVNN_NTC")
	)
	(segment
		(start 21.732748 -62.26429)
		(end 21.662898 -62.19444)
		(width 0.2032)
		(layer "F.Cu")
		(net "VR_PVNN_NTC")
	)
	(segment
		(start 21.732748 -62.281054)
		(end 21.732748 -62.26429)
		(width 0.2032)
		(layer "F.Cu")
		(net "VR_PVNN_NTC")
	)
	(segment
		(start 134.67461 -56.46039)
		(end 134.543292 -56.591708)
		(width 0.3048)
		(layer "F.Cu")
		(net "PV_VTT_DDR_A")
	)
	(segment
		(start 135.94334 -56.46039)
		(end 134.67461 -56.46039)
		(width 0.3048)
		(layer "F.Cu")
		(net "PV_VTT_DDR_A")
	)
	(segment
		(start 134.543292 -56.591708)
		(end 133.858 -57.277)
		(width 0.3048)
		(layer "F.Cu")
		(net "PV_VTT_DDR_A")
	)
	(via
		(at 134.543292 -56.591708)
		(size 0.7112)
		(drill 0.3556)
		(layers "F.Cu" "B.Cu")
		(net "PV_VTT_DDR_A")
	)
	(via
		(at 133.858 -57.277)
		(size 0.7112)
		(drill 0.4064)
		(layers "F.Cu" "B.Cu")
		(net "PV_VTT_DDR_A")
	)
	(via
		(at 126.238508 -69.9516)
		(size 0.508)
		(drill 0.254)
		(layers "F.Cu" "B.Cu")
		(net "PV_VTT_DDR_A")
	)
	(via
		(at 126.164594 -63.245746)
		(size 0.7112)
		(drill 0.4064)
		(layers "F.Cu" "B.Cu")
		(net "PV_VTT_DDR_A")
	)
	(segment
		(start 126.85014 -70.79996)
		(end 126.85014 -70.13194)
		(width 0.3048)
		(layer "B.Cu")
		(net "PV_VTT_DDR_A")
	)
	(segment
		(start 126.6698 -69.9516)
		(end 126.238508 -69.9516)
		(width 0.3048)
		(layer "B.Cu")
		(net "PV_VTT_DDR_A")
	)
	(segment
		(start 126.85014 -70.13194)
		(end 126.6698 -69.9516)
		(width 0.3048)
		(layer "B.Cu")
		(net "PV_VTT_DDR_A")
	)
	(segment
		(start 97.4598 -31.0642)
		(end 97.4598 -31.376366)
		(width 0.1016)
		(layer "F.Cu")
		(net "M_B_DQ30")
	)
	(segment
		(start 146.949922 -2.44348)
		(end 147.52066 -3.014218)
		(width 0.1778)
		(layer "F.Cu")
		(net "M_B_DQ30")
	)
	(segment
		(start 147.52066 -3.014218)
		(end 147.52066 -3.509518)
		(width 0.1778)
		(layer "F.Cu")
		(net "M_B_DQ30")
	)
	(segment
		(start 96.9264 -30.5308)
		(end 97.4598 -31.0642)
		(width 0.1016)
		(layer "F.Cu")
		(net "M_B_DQ30")
	)
	(segment
		(start 147.52066 -3.509518)
		(end 147.2692 -3.760978)
		(width 0.1778)
		(layer "F.Cu")
		(net "M_B_DQ30")
	)
	(segment
		(start 96.9264 -30.4546)
		(end 96.9264 -30.5308)
		(width 0.1016)
		(layer "F.Cu")
		(net "M_B_DQ30")
	)
	(segment
		(start 146.949922 -1.68402)
		(end 146.949922 -2.44348)
		(width 0.1778)
		(layer "F.Cu")
		(net "M_B_DQ30")
	)
	(segment
		(start 97.4598 -31.376366)
		(end 97.605088 -31.521654)
		(width 0.1016)
		(layer "F.Cu")
		(net "M_B_DQ30")
	)
	(via
		(at 96.9264 -30.4546)
		(size 0.4318)
		(drill 0.2032)
		(layers "F.Cu" "B.Cu")
		(net "M_B_DQ30")
	)
	(via
		(at 147.2692 -3.760978)
		(size 0.4318)
		(drill 0.2032)
		(layers "F.Cu" "B.Cu")
		(net "M_B_DQ30")
	)
	(segment
		(start 147.52066 -3.532378)
		(end 147.29206 -3.760978)
		(width 0.1778)
		(layer "B.Cu")
		(net "M_B_DQ30")
	)
	(segment
		(start 147.849844 -2.635504)
		(end 147.52066 -2.964688)
		(width 0.1778)
		(layer "B.Cu")
		(net "M_B_DQ30")
	)
	(segment
		(start 147.849844 -1.690624)
		(end 147.849844 -2.635504)
		(width 0.1778)
		(layer "B.Cu")
		(net "M_B_DQ30")
	)
	(segment
		(start 147.52066 -2.964688)
		(end 147.52066 -3.532378)
		(width 0.1778)
		(layer "B.Cu")
		(net "M_B_DQ30")
	)
	(segment
		(start 147.29206 -3.760978)
		(end 147.2692 -3.760978)
		(width 0.1778)
		(layer "B.Cu")
		(net "M_B_DQ30")
	)
	(segment
		(start 108.1278 -25.3746)
		(end 107.061 -26.4414)
		(width 0.1524)
		(layer "In4.Cu")
		(net "M_B_DQ30")
	)
	(segment
		(start 102.540562 -27.487372)
		(end 102.38994 -27.637994)
		(width 0.1524)
		(layer "In4.Cu")
		(net "M_B_DQ30")
	)
	(segment
		(start 145.772886 -21.4122)
		(end 115.150138 -21.4122)
		(width 0.1524)
		(layer "In4.Cu")
		(net "M_B_DQ30")
	)
	(segment
		(start 99.213162 -30.353762)
		(end 99.213162 -29.414216)
		(width 0.1016)
		(layer "In4.Cu")
		(net "M_B_DQ30")
	)
	(segment
		(start 101.980746 -28.047188)
		(end 102.38994 -27.637994)
		(width 0.1016)
		(layer "In4.Cu")
		(net "M_B_DQ30")
	)
	(segment
		(start 98.075496 -31.491428)
		(end 99.213162 -30.353762)
		(width 0.1016)
		(layer "In4.Cu")
		(net "M_B_DQ30")
	)
	(segment
		(start 147.2692 -3.760978)
		(end 147.403312 -3.89509)
		(width 0.1524)
		(layer "In4.Cu")
		(net "M_B_DQ30")
	)
	(segment
		(start 96.9264 -30.4546)
		(end 97.409 -30.9372)
		(width 0.1016)
		(layer "In4.Cu")
		(net "M_B_DQ30")
	)
	(segment
		(start 110.10519 -23.8252)
		(end 108.55579 -25.3746)
		(width 0.1524)
		(layer "In4.Cu")
		(net "M_B_DQ30")
	)
	(segment
		(start 106.299 -26.4414)
		(end 105.253028 -27.487372)
		(width 0.1524)
		(layer "In4.Cu")
		(net "M_B_DQ30")
	)
	(segment
		(start 108.55579 -25.3746)
		(end 108.1278 -25.3746)
		(width 0.1524)
		(layer "In4.Cu")
		(net "M_B_DQ30")
	)
	(segment
		(start 107.061 -26.4414)
		(end 106.299 -26.4414)
		(width 0.1524)
		(layer "In4.Cu")
		(net "M_B_DQ30")
	)
	(segment
		(start 146.761454 -8.806942)
		(end 146.761454 -20.423632)
		(width 0.1524)
		(layer "In4.Cu")
		(net "M_B_DQ30")
	)
	(segment
		(start 97.683828 -31.491428)
		(end 98.075496 -31.491428)
		(width 0.1016)
		(layer "In4.Cu")
		(net "M_B_DQ30")
	)
	(segment
		(start 146.6723 -8.717788)
		(end 146.761454 -8.806942)
		(width 0.1524)
		(layer "In4.Cu")
		(net "M_B_DQ30")
	)
	(segment
		(start 100.58019 -28.047188)
		(end 101.980746 -28.047188)
		(width 0.1016)
		(layer "In4.Cu")
		(net "M_B_DQ30")
	)
	(segment
		(start 147.403312 -3.89509)
		(end 147.403312 -6.395466)
		(width 0.1524)
		(layer "In4.Cu")
		(net "M_B_DQ30")
	)
	(segment
		(start 146.761454 -20.423632)
		(end 145.772886 -21.4122)
		(width 0.1524)
		(layer "In4.Cu")
		(net "M_B_DQ30")
	)
	(segment
		(start 97.409 -30.9372)
		(end 97.409 -31.2166)
		(width 0.1016)
		(layer "In4.Cu")
		(net "M_B_DQ30")
	)
	(segment
		(start 97.409 -31.2166)
		(end 97.683828 -31.491428)
		(width 0.1016)
		(layer "In4.Cu")
		(net "M_B_DQ30")
	)
	(segment
		(start 112.737138 -23.8252)
		(end 110.10519 -23.8252)
		(width 0.1524)
		(layer "In4.Cu")
		(net "M_B_DQ30")
	)
	(segment
		(start 115.150138 -21.4122)
		(end 112.737138 -23.8252)
		(width 0.1524)
		(layer "In4.Cu")
		(net "M_B_DQ30")
	)
	(segment
		(start 146.6723 -7.126478)
		(end 146.6723 -8.717788)
		(width 0.1524)
		(layer "In4.Cu")
		(net "M_B_DQ30")
	)
	(segment
		(start 147.403312 -6.395466)
		(end 146.6723 -7.126478)
		(width 0.1524)
		(layer "In4.Cu")
		(net "M_B_DQ30")
	)
	(segment
		(start 105.253028 -27.487372)
		(end 102.540562 -27.487372)
		(width 0.1524)
		(layer "In4.Cu")
		(net "M_B_DQ30")
	)
	(segment
		(start 99.213162 -29.414216)
		(end 100.58019 -28.047188)
		(width 0.1016)
		(layer "In4.Cu")
		(net "M_B_DQ30")
	)
	(segment
		(start 88.13546 -47.259494)
		(end 87.790274 -47.60468)
		(width 0.1397)
		(layer "F.Cu")
		(net "CLK_100M_CLKBUFF_PCIE_DN")
	)
	(segment
		(start 88.135968 -47.259494)
		(end 88.13546 -47.259494)
		(width 0.1397)
		(layer "F.Cu")
		(net "CLK_100M_CLKBUFF_PCIE_DN")
	)
	(via
		(at 87.790274 -47.60468)
		(size 0.4318)
		(drill 0.2032)
		(layers "F.Cu" "B.Cu")
		(net "CLK_100M_CLKBUFF_PCIE_DN")
	)
	(via
		(at 53.151786 -29.82722)
		(size 0.508)
		(drill 0.254)
		(layers "F.Cu" "B.Cu")
		(net "CLK_100M_CLKBUFF_PCIE_DN")
	)
	(segment
		(start 51.8033 -29.80944)
		(end 52.07254 -29.5402)
		(width 0.1397)
		(layer "B.Cu")
		(net "CLK_100M_CLKBUFF_PCIE_DN")
	)
	(segment
		(start 43.942 -34.2138)
		(end 45.5422 -34.2138)
		(width 0.1397)
		(layer "B.Cu")
		(net "CLK_100M_CLKBUFF_PCIE_DN")
	)
	(segment
		(start 41.8846 -28.7274)
		(end 41.8592 -28.7528)
		(width 0.1397)
		(layer "B.Cu")
		(net "CLK_100M_CLKBUFF_PCIE_DN")
	)
	(segment
		(start 41.8592 -28.7528)
		(end 42.09415 -28.98775)
		(width 0.1397)
		(layer "B.Cu")
		(net "CLK_100M_CLKBUFF_PCIE_DN")
	)
	(segment
		(start 41.8846 -27.9654)
		(end 41.8846 -28.7274)
		(width 0.1397)
		(layer "B.Cu")
		(net "CLK_100M_CLKBUFF_PCIE_DN")
	)
	(segment
		(start 42.09415 -28.98775)
		(end 42.09415 -32.36595)
		(width 0.1397)
		(layer "B.Cu")
		(net "CLK_100M_CLKBUFF_PCIE_DN")
	)
	(segment
		(start 51.8033 -31.289752)
		(end 51.8033 -29.80944)
		(width 0.1397)
		(layer "B.Cu")
		(net "CLK_100M_CLKBUFF_PCIE_DN")
	)
	(segment
		(start 49.774856 -33.318196)
		(end 51.8033 -31.289752)
		(width 0.1397)
		(layer "B.Cu")
		(net "CLK_100M_CLKBUFF_PCIE_DN")
	)
	(segment
		(start 46.437804 -33.318196)
		(end 49.774856 -33.318196)
		(width 0.1397)
		(layer "B.Cu")
		(net "CLK_100M_CLKBUFF_PCIE_DN")
	)
	(segment
		(start 45.5422 -34.2138)
		(end 46.437804 -33.318196)
		(width 0.1397)
		(layer "B.Cu")
		(net "CLK_100M_CLKBUFF_PCIE_DN")
	)
	(segment
		(start 52.864766 -29.5402)
		(end 53.151786 -29.82722)
		(width 0.1397)
		(layer "B.Cu")
		(net "CLK_100M_CLKBUFF_PCIE_DN")
	)
	(segment
		(start 52.07254 -29.5402)
		(end 52.864766 -29.5402)
		(width 0.1397)
		(layer "B.Cu")
		(net "CLK_100M_CLKBUFF_PCIE_DN")
	)
	(segment
		(start 42.09415 -32.36595)
		(end 43.942 -34.2138)
		(width 0.1397)
		(layer "B.Cu")
		(net "CLK_100M_CLKBUFF_PCIE_DN")
	)
	(segment
		(start 53.451506 -29.5275)
		(end 54.2925 -29.5275)
		(width 0.1143)
		(layer "In7.Cu")
		(net "CLK_100M_CLKBUFF_PCIE_DN")
	)
	(segment
		(start 80.949292 -40.066214)
		(end 80.949546 -40.066214)
		(width 0.1016)
		(layer "In7.Cu")
		(net "CLK_100M_CLKBUFF_PCIE_DN")
	)
	(segment
		(start 54.2925 -29.5275)
		(end 54.7878 -30.0228)
		(width 0.1143)
		(layer "In7.Cu")
		(net "CLK_100M_CLKBUFF_PCIE_DN")
	)
	(segment
		(start 73.531222 -31.3944)
		(end 74.584306 -32.447484)
		(width 0.1143)
		(layer "In7.Cu")
		(net "CLK_100M_CLKBUFF_PCIE_DN")
	)
	(segment
		(start 81.8388 -41.186608)
		(end 82.354928 -41.702736)
		(width 0.1016)
		(layer "In7.Cu")
		(net "CLK_100M_CLKBUFF_PCIE_DN")
	)
	(segment
		(start 82.354928 -41.702736)
		(end 83.025996 -41.702736)
		(width 0.1016)
		(layer "In7.Cu")
		(net "CLK_100M_CLKBUFF_PCIE_DN")
	)
	(segment
		(start 80.9498 -40.06596)
		(end 81.0387 -40.06596)
		(width 0.1016)
		(layer "In7.Cu")
		(net "CLK_100M_CLKBUFF_PCIE_DN")
	)
	(segment
		(start 81.8388 -40.86606)
		(end 81.8388 -41.186608)
		(width 0.1016)
		(layer "In7.Cu")
		(net "CLK_100M_CLKBUFF_PCIE_DN")
	)
	(segment
		(start 86.967568 -45.641006)
		(end 87.338154 -46.011592)
		(width 0.1016)
		(layer "In7.Cu")
		(net "CLK_100M_CLKBUFF_PCIE_DN")
	)
	(segment
		(start 74.584306 -32.693102)
		(end 75.019154 -33.12795)
		(width 0.1143)
		(layer "In7.Cu")
		(net "CLK_100M_CLKBUFF_PCIE_DN")
	)
	(segment
		(start 83.808062 -42.484802)
		(end 85.283802 -42.484802)
		(width 0.1016)
		(layer "In7.Cu")
		(net "CLK_100M_CLKBUFF_PCIE_DN")
	)
	(segment
		(start 87.338154 -47.15256)
		(end 87.790274 -47.60468)
		(width 0.1016)
		(layer "In7.Cu")
		(net "CLK_100M_CLKBUFF_PCIE_DN")
	)
	(segment
		(start 74.584306 -32.447484)
		(end 74.584306 -32.693102)
		(width 0.1143)
		(layer "In7.Cu")
		(net "CLK_100M_CLKBUFF_PCIE_DN")
	)
	(segment
		(start 81.0387 -40.06596)
		(end 81.8388 -40.86606)
		(width 0.1016)
		(layer "In7.Cu")
		(net "CLK_100M_CLKBUFF_PCIE_DN")
	)
	(segment
		(start 85.283802 -42.484802)
		(end 86.967568 -44.168568)
		(width 0.1016)
		(layer "In7.Cu")
		(net "CLK_100M_CLKBUFF_PCIE_DN")
	)
	(segment
		(start 75.7682 -33.614106)
		(end 75.7682 -34.885122)
		(width 0.1143)
		(layer "In7.Cu")
		(net "CLK_100M_CLKBUFF_PCIE_DN")
	)
	(segment
		(start 83.025996 -41.702736)
		(end 83.808062 -42.484802)
		(width 0.1016)
		(layer "In7.Cu")
		(net "CLK_100M_CLKBUFF_PCIE_DN")
	)
	(segment
		(start 65.474342 -30.0228)
		(end 66.845942 -31.3944)
		(width 0.1143)
		(layer "In7.Cu")
		(net "CLK_100M_CLKBUFF_PCIE_DN")
	)
	(segment
		(start 80.949546 -40.066214)
		(end 80.9498 -40.06596)
		(width 0.1016)
		(layer "In7.Cu")
		(net "CLK_100M_CLKBUFF_PCIE_DN")
	)
	(segment
		(start 75.282044 -33.12795)
		(end 75.7682 -33.614106)
		(width 0.1143)
		(layer "In7.Cu")
		(net "CLK_100M_CLKBUFF_PCIE_DN")
	)
	(segment
		(start 86.967568 -44.168568)
		(end 86.967568 -45.641006)
		(width 0.1016)
		(layer "In7.Cu")
		(net "CLK_100M_CLKBUFF_PCIE_DN")
	)
	(segment
		(start 80.931258 -40.04818)
		(end 80.949292 -40.066214)
		(width 0.1016)
		(layer "In7.Cu")
		(net "CLK_100M_CLKBUFF_PCIE_DN")
	)
	(segment
		(start 87.338154 -46.011592)
		(end 87.338154 -47.15256)
		(width 0.1016)
		(layer "In7.Cu")
		(net "CLK_100M_CLKBUFF_PCIE_DN")
	)
	(segment
		(start 66.845942 -31.3944)
		(end 73.531222 -31.3944)
		(width 0.1143)
		(layer "In7.Cu")
		(net "CLK_100M_CLKBUFF_PCIE_DN")
	)
	(segment
		(start 54.7878 -30.0228)
		(end 65.474342 -30.0228)
		(width 0.1143)
		(layer "In7.Cu")
		(net "CLK_100M_CLKBUFF_PCIE_DN")
	)
	(segment
		(start 53.151786 -29.82722)
		(end 53.451506 -29.5275)
		(width 0.1143)
		(layer "In7.Cu")
		(net "CLK_100M_CLKBUFF_PCIE_DN")
	)
	(segment
		(start 75.019154 -33.12795)
		(end 75.282044 -33.12795)
		(width 0.1143)
		(layer "In7.Cu")
		(net "CLK_100M_CLKBUFF_PCIE_DN")
	)
	(segment
		(start 75.7682 -34.885122)
		(end 80.931258 -40.04818)
		(width 0.1143)
		(layer "In7.Cu")
		(net "CLK_100M_CLKBUFF_PCIE_DN")
	)
	(segment
		(start 84.409788 -41.447212)
		(end 84.074 -41.783)
		(width 0.1143)
		(layer "F.Cu")
		(net "CLK_14M_CPU")
	)
	(segment
		(start 84.409788 -41.417494)
		(end 84.409788 -41.447212)
		(width 0.1143)
		(layer "F.Cu")
		(net "CLK_14M_CPU")
	)
	(segment
		(start 37.7952 -52.07)
		(end 37.7952 -51.4096)
		(width 0.1143)
		(layer "F.Cu")
		(net "CLK_14M_CPU")
	)
	(segment
		(start 37.7952 -51.4096)
		(end 37.33292 -50.94732)
		(width 0.1143)
		(layer "F.Cu")
		(net "CLK_14M_CPU")
	)
	(via
		(at 69.5706 -39.674292)
		(size 0.508)
		(drill 0.254)
		(layers "F.Cu" "B.Cu")
		(net "CLK_14M_CPU")
	)
	(via
		(at 70.3072 -40.3098)
		(size 0.7112)
		(drill 0.3556)
		(layers "F.Cu" "B.Cu")
		(net "CLK_14M_CPU")
	)
	(via
		(at 84.074 -41.783)
		(size 0.4318)
		(drill 0.2032)
		(layers "F.Cu" "B.Cu")
		(net "CLK_14M_CPU")
	)
	(via
		(at 37.33292 -50.94732)
		(size 0.508)
		(drill 0.254)
		(layers "F.Cu" "B.Cu")
		(net "CLK_14M_CPU")
	)
	(segment
		(start 70.3072 -40.3098)
		(end 69.671692 -39.674292)
		(width 0.1143)
		(layer "B.Cu")
		(net "CLK_14M_CPU")
	)
	(segment
		(start 69.671692 -39.674292)
		(end 69.5706 -39.674292)
		(width 0.1143)
		(layer "B.Cu")
		(net "CLK_14M_CPU")
	)
	(segment
		(start 37.33292 -50.94732)
		(end 37.33292 -49.45888)
		(width 0.1143)
		(layer "B.Cu")
		(net "CLK_14M_CPU")
	)
	(segment
		(start 37.9222 -49.403)
		(end 37.3888 -49.403)
		(width 0.1143)
		(layer "B.Cu")
		(net "CLK_14M_CPU")
	)
	(segment
		(start 38.5572 -48.768)
		(end 37.9222 -49.403)
		(width 0.1143)
		(layer "B.Cu")
		(net "CLK_14M_CPU")
	)
	(segment
		(start 37.33292 -49.45888)
		(end 37.3888 -49.403)
		(width 0.1143)
		(layer "B.Cu")
		(net "CLK_14M_CPU")
	)
	(segment
		(start 70.17004 -37.50945)
		(end 69.61505 -38.06444)
		(width 0.0889)
		(layer "In2.Cu")
		(net "CLK_14M_CPU")
	)
	(segment
		(start 69.61505 -39.629842)
		(end 69.5706 -39.674292)
		(width 0.0889)
		(layer "In2.Cu")
		(net "CLK_14M_CPU")
	)
	(segment
		(start 77.597 -39.7002)
		(end 75.40625 -37.50945)
		(width 0.0889)
		(layer "In2.Cu")
		(net "CLK_14M_CPU")
	)
	(segment
		(start 84.074 -41.783)
		(end 83.022694 -41.783)
		(width 0.0889)
		(layer "In2.Cu")
		(net "CLK_14M_CPU")
	)
	(segment
		(start 75.40625 -37.50945)
		(end 70.17004 -37.50945)
		(width 0.0889)
		(layer "In2.Cu")
		(net "CLK_14M_CPU")
	)
	(segment
		(start 69.61505 -38.06444)
		(end 69.61505 -39.629842)
		(width 0.0889)
		(layer "In2.Cu")
		(net "CLK_14M_CPU")
	)
	(segment
		(start 81.36001 -41.709086)
		(end 81.35493 -41.714166)
		(width 0.0889)
		(layer "In2.Cu")
		(net "CLK_14M_CPU")
	)
	(segment
		(start 83.022694 -41.783)
		(end 82.94878 -41.709086)
		(width 0.0889)
		(layer "In2.Cu")
		(net "CLK_14M_CPU")
	)
	(segment
		(start 79.0194 -39.7002)
		(end 77.597 -39.7002)
		(width 0.0889)
		(layer "In2.Cu")
		(net "CLK_14M_CPU")
	)
	(segment
		(start 81.35493 -41.714166)
		(end 81.033366 -41.714166)
		(width 0.0889)
		(layer "In2.Cu")
		(net "CLK_14M_CPU")
	)
	(segment
		(start 81.033366 -41.714166)
		(end 79.0194 -39.7002)
		(width 0.0889)
		(layer "In2.Cu")
		(net "CLK_14M_CPU")
	)
	(segment
		(start 82.94878 -41.709086)
		(end 81.36001 -41.709086)
		(width 0.0889)
		(layer "In2.Cu")
		(net "CLK_14M_CPU")
	)
	(segment
		(start 58.70067 -43.723814)
		(end 59.427364 -42.99712)
		(width 0.0889)
		(layer "In4.Cu")
		(net "CLK_14M_CPU")
	)
	(segment
		(start 57.258966 -45.166534)
		(end 58.70067 -43.72483)
		(width 0.0889)
		(layer "In4.Cu")
		(net "CLK_14M_CPU")
	)
	(segment
		(start 69.122544 -37.39515)
		(end 69.61505 -37.887656)
		(width 0.0889)
		(layer "In4.Cu")
		(net "CLK_14M_CPU")
	)
	(segment
		(start 37.33292 -50.94732)
		(end 38.559486 -50.94732)
		(width 0.0889)
		(layer "In4.Cu")
		(net "CLK_14M_CPU")
	)
	(segment
		(start 51.95316 -50.47615)
		(end 56.4388 -45.99051)
		(width 0.0889)
		(layer "In4.Cu")
		(net "CLK_14M_CPU")
	)
	(segment
		(start 56.913272 -45.166534)
		(end 57.258966 -45.166534)
		(width 0.0889)
		(layer "In4.Cu")
		(net "CLK_14M_CPU")
	)
	(segment
		(start 69.61505 -37.887656)
		(end 69.61505 -39.629842)
		(width 0.0889)
		(layer "In4.Cu")
		(net "CLK_14M_CPU")
	)
	(segment
		(start 56.4388 -45.641006)
		(end 56.913272 -45.166534)
		(width 0.0889)
		(layer "In4.Cu")
		(net "CLK_14M_CPU")
	)
	(segment
		(start 61.3156 -42.99712)
		(end 66.91757 -37.39515)
		(width 0.0889)
		(layer "In4.Cu")
		(net "CLK_14M_CPU")
	)
	(segment
		(start 58.70067 -43.72483)
		(end 58.70067 -43.723814)
		(width 0.0889)
		(layer "In4.Cu")
		(net "CLK_14M_CPU")
	)
	(segment
		(start 66.91757 -37.39515)
		(end 69.122544 -37.39515)
		(width 0.0889)
		(layer "In4.Cu")
		(net "CLK_14M_CPU")
	)
	(segment
		(start 50.423826 -50.47615)
		(end 51.95316 -50.47615)
		(width 0.0889)
		(layer "In4.Cu")
		(net "CLK_14M_CPU")
	)
	(segment
		(start 59.427364 -42.99712)
		(end 61.3156 -42.99712)
		(width 0.0889)
		(layer "In4.Cu")
		(net "CLK_14M_CPU")
	)
	(segment
		(start 56.4388 -45.99051)
		(end 56.4388 -45.641006)
		(width 0.0889)
		(layer "In4.Cu")
		(net "CLK_14M_CPU")
	)
	(segment
		(start 50.322226 -50.57775)
		(end 50.423826 -50.47615)
		(width 0.0889)
		(layer "In4.Cu")
		(net "CLK_14M_CPU")
	)
	(segment
		(start 38.559486 -50.94732)
		(end 38.929056 -50.57775)
		(width 0.0889)
		(layer "In4.Cu")
		(net "CLK_14M_CPU")
	)
	(segment
		(start 38.929056 -50.57775)
		(end 50.322226 -50.57775)
		(width 0.0889)
		(layer "In4.Cu")
		(net "CLK_14M_CPU")
	)
	(segment
		(start 69.61505 -39.629842)
		(end 69.5706 -39.674292)
		(width 0.0889)
		(layer "In4.Cu")
		(net "CLK_14M_CPU")
	)
	(segment
		(start 13.335 -58.674)
		(end 12.954 -58.293)
		(width 0.127)
		(layer "F.Cu")
		(net "TP_PVCCP_CLK")
	)
	(segment
		(start 13.335 -59.6392)
		(end 13.335 -58.674)
		(width 0.127)
		(layer "F.Cu")
		(net "TP_PVCCP_CLK")
	)
	(segment
		(start 185.260234 -20.828)
		(end 184.9628 -21.125434)
		(width 0.254)
		(layer "F.Cu")
		(net "PV_VTT_DDR_B_R_PG")
	)
	(segment
		(start 184.912 -22.4536)
		(end 184.912 -21.59)
		(width 0.254)
		(layer "F.Cu")
		(net "PV_VTT_DDR_B_R_PG")
	)
	(segment
		(start 185.260234 -20.15871)
		(end 185.260234 -20.828)
		(width 0.254)
		(layer "F.Cu")
		(net "PV_VTT_DDR_B_R_PG")
	)
	(segment
		(start 184.9628 -21.125434)
		(end 184.9628 -21.5392)
		(width 0.254)
		(layer "F.Cu")
		(net "PV_VTT_DDR_B_R_PG")
	)
	(segment
		(start 184.912 -21.59)
		(end 184.9628 -21.5392)
		(width 0.254)
		(layer "F.Cu")
		(net "PV_VTT_DDR_B_R_PG")
	)
	(via
		(at 184.9628 -21.5392)
		(size 0.7112)
		(drill 0.3556)
		(layers "F.Cu" "B.Cu")
		(net "PV_VTT_DDR_B_R_PG")
	)
	(segment
		(start 164.049964 -9.183878)
		(end 164.281612 -8.95223)
		(width 0.2159)
		(layer "F.Cu")
		(net "M_B_CK_DP3")
	)
	(segment
		(start 106.4514 -30.2768)
		(end 106.7054 -30.2768)
		(width 0.1016)
		(layer "F.Cu")
		(net "M_B_CK_DP3")
	)
	(segment
		(start 164.049964 -9.897364)
		(end 164.049964 -9.183878)
		(width 0.2159)
		(layer "F.Cu")
		(net "M_B_CK_DP3")
	)
	(segment
		(start 164.281612 -8.95223)
		(end 164.281612 -7.576566)
		(width 0.2159)
		(layer "F.Cu")
		(net "M_B_CK_DP3")
	)
	(segment
		(start 106.8324 -30.1498)
		(end 106.8324 -30.0482)
		(width 0.1016)
		(layer "F.Cu")
		(net "M_B_CK_DP3")
	)
	(segment
		(start 106.7054 -30.2768)
		(end 106.8324 -30.1498)
		(width 0.1016)
		(layer "F.Cu")
		(net "M_B_CK_DP3")
	)
	(segment
		(start 106.251248 -30.076648)
		(end 106.4514 -30.2768)
		(width 0.1016)
		(layer "F.Cu")
		(net "M_B_CK_DP3")
	)
	(segment
		(start 106.251248 -29.997654)
		(end 106.251248 -30.076648)
		(width 0.1016)
		(layer "F.Cu")
		(net "M_B_CK_DP3")
	)
	(segment
		(start 164.281612 -7.576566)
		(end 164.338 -7.520178)
		(width 0.2159)
		(layer "F.Cu")
		(net "M_B_CK_DP3")
	)
	(via
		(at 164.338 -7.520178)
		(size 0.4318)
		(drill 0.2032)
		(layers "F.Cu" "B.Cu")
		(net "M_B_CK_DP3")
	)
	(via
		(at 106.8324 -30.0482)
		(size 0.4318)
		(drill 0.2032)
		(layers "F.Cu" "B.Cu")
		(net "M_B_CK_DP3")
	)
	(segment
		(start 151.5745 -16.679164)
		(end 151.138636 -16.2433)
		(width 0.1905)
		(layer "In9.Cu")
		(net "M_B_CK_DP3")
	)
	(segment
		(start 106.005884 -28.401772)
		(end 106.005884 -29.056584)
		(width 0.1016)
		(layer "In9.Cu")
		(net "M_B_CK_DP3")
	)
	(segment
		(start 149.6949 -16.641064)
		(end 149.6949 -19.638264)
		(width 0.1905)
		(layer "In9.Cu")
		(net "M_B_CK_DP3")
	)
	(segment
		(start 107.153202 -27.422602)
		(end 106.985054 -27.422602)
		(width 0.1016)
		(layer "In9.Cu")
		(net "M_B_CK_DP3")
	)
	(segment
		(start 161.3789 -11.207242)
		(end 161.3789 -12.729464)
		(width 0.1905)
		(layer "In9.Cu")
		(net "M_B_CK_DP3")
	)
	(segment
		(start 161.922714 -10.663428)
		(end 161.3789 -11.207242)
		(width 0.1905)
		(layer "In9.Cu")
		(net "M_B_CK_DP3")
	)
	(segment
		(start 149.292564 -20.0406)
		(end 145.530824 -20.0406)
		(width 0.1905)
		(layer "In9.Cu")
		(net "M_B_CK_DP3")
	)
	(segment
		(start 149.6949 -19.638264)
		(end 149.292564 -20.0406)
		(width 0.1905)
		(layer "In9.Cu")
		(net "M_B_CK_DP3")
	)
	(segment
		(start 106.8324 -29.990034)
		(end 106.8324 -30.0482)
		(width 0.1016)
		(layer "In9.Cu")
		(net "M_B_CK_DP3")
	)
	(segment
		(start 109.887512 -24.520652)
		(end 109.887512 -24.731726)
		(width 0.1016)
		(layer "In9.Cu")
		(net "M_B_CK_DP3")
	)
	(segment
		(start 164.338 -7.520178)
		(end 164.24275 -7.615428)
		(width 0.1905)
		(layer "In9.Cu")
		(net "M_B_CK_DP3")
	)
	(segment
		(start 106.74604 -29.79674)
		(end 106.8324 -29.990034)
		(width 0.1016)
		(layer "In9.Cu")
		(net "M_B_CK_DP3")
	)
	(segment
		(start 152.772364 -16.2433)
		(end 152.3365 -16.679164)
		(width 0.1905)
		(layer "In9.Cu")
		(net "M_B_CK_DP3")
	)
	(segment
		(start 109.4486 -25.170638)
		(end 109.4486 -27.157934)
		(width 0.1016)
		(layer "In9.Cu")
		(net "M_B_CK_DP3")
	)
	(segment
		(start 144.733264 -19.81454)
		(end 144.507204 -20.0406)
		(width 0.1905)
		(layer "In9.Cu")
		(net "M_B_CK_DP3")
	)
	(segment
		(start 108.674662 -27.323796)
		(end 108.369862 -27.323796)
		(width 0.1016)
		(layer "In9.Cu")
		(net "M_B_CK_DP3")
	)
	(segment
		(start 106.57713 -27.830526)
		(end 106.436922 -27.830526)
		(width 0.1016)
		(layer "In9.Cu")
		(net "M_B_CK_DP3")
	)
	(segment
		(start 161.3789 -12.729464)
		(end 161.167064 -12.9413)
		(width 0.1905)
		(layer "In9.Cu")
		(net "M_B_CK_DP3")
	)
	(segment
		(start 164.24275 -10.084562)
		(end 163.663884 -10.663428)
		(width 0.1905)
		(layer "In9.Cu")
		(net "M_B_CK_DP3")
	)
	(segment
		(start 109.183678 -27.422856)
		(end 108.773722 -27.422856)
		(width 0.1016)
		(layer "In9.Cu")
		(net "M_B_CK_DP3")
	)
	(segment
		(start 164.24275 -7.615428)
		(end 164.24275 -10.084562)
		(width 0.1905)
		(layer "In9.Cu")
		(net "M_B_CK_DP3")
	)
	(segment
		(start 156.214064 -16.2433)
		(end 152.772364 -16.2433)
		(width 0.1905)
		(layer "In9.Cu")
		(net "M_B_CK_DP3")
	)
	(segment
		(start 106.985054 -27.422602)
		(end 106.57713 -27.830526)
		(width 0.1016)
		(layer "In9.Cu")
		(net "M_B_CK_DP3")
	)
	(segment
		(start 151.138636 -16.2433)
		(end 150.092664 -16.2433)
		(width 0.1905)
		(layer "In9.Cu")
		(net "M_B_CK_DP3")
	)
	(segment
		(start 109.887512 -24.731726)
		(end 109.4486 -25.170638)
		(width 0.1016)
		(layer "In9.Cu")
		(net "M_B_CK_DP3")
	)
	(segment
		(start 109.4486 -27.157934)
		(end 109.183678 -27.422856)
		(width 0.1016)
		(layer "In9.Cu")
		(net "M_B_CK_DP3")
	)
	(segment
		(start 108.270802 -27.422856)
		(end 107.153456 -27.422856)
		(width 0.1016)
		(layer "In9.Cu")
		(net "M_B_CK_DP3")
	)
	(segment
		(start 152.3365 -16.679164)
		(end 152.3365 -19.0246)
		(width 0.1905)
		(layer "In9.Cu")
		(net "M_B_CK_DP3")
	)
	(segment
		(start 114.367564 -20.0406)
		(end 109.887512 -24.520652)
		(width 0.1905)
		(layer "In9.Cu")
		(net "M_B_CK_DP3")
	)
	(segment
		(start 106.436922 -27.830526)
		(end 106.22153 -28.046172)
		(width 0.1016)
		(layer "In9.Cu")
		(net "M_B_CK_DP3")
	)
	(segment
		(start 152.3365 -19.0246)
		(end 152.1841 -19.177)
		(width 0.1905)
		(layer "In9.Cu")
		(net "M_B_CK_DP3")
	)
	(segment
		(start 161.167064 -12.9413)
		(end 159.516064 -12.9413)
		(width 0.1905)
		(layer "In9.Cu")
		(net "M_B_CK_DP3")
	)
	(segment
		(start 163.663884 -10.663428)
		(end 161.922714 -10.663428)
		(width 0.1905)
		(layer "In9.Cu")
		(net "M_B_CK_DP3")
	)
	(segment
		(start 144.507204 -20.0406)
		(end 114.367564 -20.0406)
		(width 0.1905)
		(layer "In9.Cu")
		(net "M_B_CK_DP3")
	)
	(segment
		(start 151.5745 -19.0246)
		(end 151.5745 -16.679164)
		(width 0.1905)
		(layer "In9.Cu")
		(net "M_B_CK_DP3")
	)
	(segment
		(start 145.304764 -19.81454)
		(end 144.733264 -19.81454)
		(width 0.1905)
		(layer "In9.Cu")
		(net "M_B_CK_DP3")
	)
	(segment
		(start 145.530824 -20.0406)
		(end 145.304764 -19.81454)
		(width 0.1905)
		(layer "In9.Cu")
		(net "M_B_CK_DP3")
	)
	(segment
		(start 106.22153 -28.186126)
		(end 106.005884 -28.401772)
		(width 0.1016)
		(layer "In9.Cu")
		(net "M_B_CK_DP3")
	)
	(segment
		(start 106.005884 -29.056584)
		(end 106.74604 -29.79674)
		(width 0.1016)
		(layer "In9.Cu")
		(net "M_B_CK_DP3")
	)
	(segment
		(start 159.516064 -12.9413)
		(end 156.214064 -16.2433)
		(width 0.1905)
		(layer "In9.Cu")
		(net "M_B_CK_DP3")
	)
	(segment
		(start 108.369862 -27.323796)
		(end 108.270802 -27.422856)
		(width 0.1016)
		(layer "In9.Cu")
		(net "M_B_CK_DP3")
	)
	(segment
		(start 152.1841 -19.177)
		(end 151.7269 -19.177)
		(width 0.1905)
		(layer "In9.Cu")
		(net "M_B_CK_DP3")
	)
	(segment
		(start 150.092664 -16.2433)
		(end 149.6949 -16.641064)
		(width 0.1905)
		(layer "In9.Cu")
		(net "M_B_CK_DP3")
	)
	(segment
		(start 151.7269 -19.177)
		(end 151.5745 -19.0246)
		(width 0.1905)
		(layer "In9.Cu")
		(net "M_B_CK_DP3")
	)
	(segment
		(start 106.22153 -28.046172)
		(end 106.22153 -28.186126)
		(width 0.1016)
		(layer "In9.Cu")
		(net "M_B_CK_DP3")
	)
	(segment
		(start 108.773722 -27.422856)
		(end 108.674662 -27.323796)
		(width 0.1016)
		(layer "In9.Cu")
		(net "M_B_CK_DP3")
	)
	(segment
		(start 107.153456 -27.422856)
		(end 107.153202 -27.422602)
		(width 0.1016)
		(layer "In9.Cu")
		(net "M_B_CK_DP3")
	)
	(segment
		(start 82.144616 -39.0906)
		(end 82.042 -39.0906)
		(width 0.1143)
		(layer "F.Cu")
		(net "CPU_RSVD10")
	)
	(segment
		(start 82.504788 -38.730174)
		(end 82.144616 -39.0906)
		(width 0.1143)
		(layer "F.Cu")
		(net "CPU_RSVD10")
	)
	(via
		(at 82.042 -39.0906)
		(size 0.4318)
		(drill 0.2032)
		(layers "F.Cu" "B.Cu")
		(net "CPU_RSVD10")
	)
	(via
		(at 75.96251 -39.132256)
		(size 0.7112)
		(drill 0.3556)
		(layers "F.Cu" "B.Cu")
		(net "CPU_RSVD10")
	)
	(segment
		(start 79.191866 -40.711374)
		(end 77.795374 -40.711374)
		(width 0.1143)
		(layer "B.Cu")
		(net "CPU_RSVD10")
	)
	(segment
		(start 77.310234 -40.209216)
		(end 76.293218 -39.1922)
		(width 0.1143)
		(layer "B.Cu")
		(net "CPU_RSVD10")
	)
	(segment
		(start 74.4728 -38.354)
		(end 74.8538 -38.735)
		(width 0.1143)
		(layer "B.Cu")
		(net "CPU_RSVD10")
	)
	(segment
		(start 76.022454 -39.1922)
		(end 75.96251 -39.132256)
		(width 0.1143)
		(layer "B.Cu")
		(net "CPU_RSVD10")
	)
	(segment
		(start 74.8538 -38.735)
		(end 75.565 -38.735)
		(width 0.1143)
		(layer "B.Cu")
		(net "CPU_RSVD10")
	)
	(segment
		(start 79.505556 -40.397684)
		(end 79.191866 -40.711374)
		(width 0.1143)
		(layer "B.Cu")
		(net "CPU_RSVD10")
	)
	(segment
		(start 81.8388 -39.0906)
		(end 80.531716 -40.397684)
		(width 0.1143)
		(layer "B.Cu")
		(net "CPU_RSVD10")
	)
	(segment
		(start 80.531716 -40.397684)
		(end 79.505556 -40.397684)
		(width 0.1143)
		(layer "B.Cu")
		(net "CPU_RSVD10")
	)
	(segment
		(start 75.565 -38.735)
		(end 75.962256 -39.132256)
		(width 0.1143)
		(layer "B.Cu")
		(net "CPU_RSVD10")
	)
	(segment
		(start 76.293218 -39.1922)
		(end 76.022454 -39.1922)
		(width 0.1143)
		(layer "B.Cu")
		(net "CPU_RSVD10")
	)
	(segment
		(start 77.310234 -40.226234)
		(end 77.310234 -40.209216)
		(width 0.1143)
		(layer "B.Cu")
		(net "CPU_RSVD10")
	)
	(segment
		(start 75.962256 -39.132256)
		(end 75.96251 -39.132256)
		(width 0.1143)
		(layer "B.Cu")
		(net "CPU_RSVD10")
	)
	(segment
		(start 77.795374 -40.711374)
		(end 77.310234 -40.226234)
		(width 0.1143)
		(layer "B.Cu")
		(net "CPU_RSVD10")
	)
	(segment
		(start 82.042 -39.0906)
		(end 81.8388 -39.0906)
		(width 0.1143)
		(layer "B.Cu")
		(net "CPU_RSVD10")
	)
	(via
		(at 34.163 -57.404)
		(size 0.7112)
		(drill 0.3556)
		(layers "F.Cu" "B.Cu")
		(net "VR_FET_SW_P12V_PVCCP_PVNN")
	)
	(via
		(at 35.306 -62.865)
		(size 0.7112)
		(drill 0.3556)
		(layers "F.Cu" "B.Cu")
		(net "VR_FET_SW_P12V_PVCCP_PVNN")
	)
	(segment
		(start 183.82869 -20.15871)
		(end 183.5404 -20.447)
		(width 0.3048)
		(layer "F.Cu")
		(net "PV_VTT_DDR_B_VIN")
	)
	(segment
		(start 183.9214 -21.59)
		(end 183.9214 -21.463)
		(width 0.508)
		(layer "F.Cu")
		(net "PV_VTT_DDR_B_VIN")
	)
	(segment
		(start 183.9214 -21.463)
		(end 183.5404 -21.082)
		(width 0.508)
		(layer "F.Cu")
		(net "PV_VTT_DDR_B_VIN")
	)
	(segment
		(start 183.5404 -21.082)
		(end 183.5404 -20.447)
		(width 0.508)
		(layer "F.Cu")
		(net "PV_VTT_DDR_B_VIN")
	)
	(segment
		(start 183.9214 -22.86)
		(end 183.9214 -21.59)
		(width 0.508)
		(layer "F.Cu")
		(net "PV_VTT_DDR_B_VIN")
	)
	(segment
		(start 184.760362 -20.15871)
		(end 183.82869 -20.15871)
		(width 0.3048)
		(layer "F.Cu")
		(net "PV_VTT_DDR_B_VIN")
	)
	(via
		(at 183.5404 -20.447)
		(size 0.7112)
		(drill 0.3556)
		(layers "F.Cu" "B.Cu")
		(net "PV_VTT_DDR_B_VIN")
	)
	(segment
		(start 173.649894 -9.897364)
		(end 173.649894 -9.036304)
		(width 0.1778)
		(layer "F.Cu")
		(net "M_B_DQ35")
	)
	(segment
		(start 174.050452 -8.635746)
		(end 174.050452 -7.967726)
		(width 0.1778)
		(layer "F.Cu")
		(net "M_B_DQ35")
	)
	(segment
		(start 174.050452 -7.967726)
		(end 174.1678 -7.850378)
		(width 0.1778)
		(layer "F.Cu")
		(net "M_B_DQ35")
	)
	(segment
		(start 107.290108 -32.841692)
		(end 107.290108 -33.010094)
		(width 0.1016)
		(layer "F.Cu")
		(net "M_B_DQ35")
	)
	(segment
		(start 107.569 -32.5628)
		(end 107.290108 -32.841692)
		(width 0.1016)
		(layer "F.Cu")
		(net "M_B_DQ35")
	)
	(segment
		(start 174.1678 -7.850378)
		(end 174.1678 -7.824978)
		(width 0.1778)
		(layer "F.Cu")
		(net "M_B_DQ35")
	)
	(segment
		(start 173.649894 -9.036304)
		(end 174.050452 -8.635746)
		(width 0.1778)
		(layer "F.Cu")
		(net "M_B_DQ35")
	)
	(via
		(at 107.569 -32.5628)
		(size 0.4318)
		(drill 0.2032)
		(layers "F.Cu" "B.Cu")
		(net "M_B_DQ35")
	)
	(via
		(at 174.1678 -7.824978)
		(size 0.4318)
		(drill 0.2032)
		(layers "F.Cu" "B.Cu")
		(net "M_B_DQ35")
	)
	(segment
		(start 174.07636 -7.916418)
		(end 174.1678 -7.824978)
		(width 0.1778)
		(layer "B.Cu")
		(net "M_B_DQ35")
	)
	(segment
		(start 174.549816 -8.938514)
		(end 174.07636 -8.465058)
		(width 0.1778)
		(layer "B.Cu")
		(net "M_B_DQ35")
	)
	(segment
		(start 174.07636 -8.465058)
		(end 174.07636 -7.916418)
		(width 0.1778)
		(layer "B.Cu")
		(net "M_B_DQ35")
	)
	(segment
		(start 174.549816 -9.89076)
		(end 174.549816 -8.938514)
		(width 0.1778)
		(layer "B.Cu")
		(net "M_B_DQ35")
	)
	(segment
		(start 150.9268 -29.2862)
		(end 150.9268 -29.65323)
		(width 0.1524)
		(layer "In4.Cu")
		(net "M_B_DQ35")
	)
	(segment
		(start 140.223494 -29.2608)
		(end 140.096494 -29.1338)
		(width 0.1524)
		(layer "In4.Cu")
		(net "M_B_DQ35")
	)
	(segment
		(start 148.6662 -29.1338)
		(end 148.3614 -29.1338)
		(width 0.1524)
		(layer "In4.Cu")
		(net "M_B_DQ35")
	)
	(segment
		(start 109.22 -31.880556)
		(end 109.449362 -31.651194)
		(width 0.1016)
		(layer "In4.Cu")
		(net "M_B_DQ35")
	)
	(segment
		(start 140.223494 -29.62783)
		(end 140.223494 -29.2608)
		(width 0.1524)
		(layer "In4.Cu")
		(net "M_B_DQ35")
	)
	(segment
		(start 138.521694 -29.1338)
		(end 138.394694 -29.2608)
		(width 0.1524)
		(layer "In4.Cu")
		(net "M_B_DQ35")
	)
	(segment
		(start 140.096494 -29.1338)
		(end 139.740894 -29.1338)
		(width 0.1524)
		(layer "In4.Cu")
		(net "M_B_DQ35")
	)
	(segment
		(start 150.0378 -29.65323)
		(end 150.0378 -29.2862)
		(width 0.1524)
		(layer "In4.Cu")
		(net "M_B_DQ35")
	)
	(segment
		(start 137.581894 -29.1338)
		(end 114.7572 -29.1338)
		(width 0.1524)
		(layer "In4.Cu")
		(net "M_B_DQ35")
	)
	(segment
		(start 157.630876 -29.1338)
		(end 151.0792 -29.1338)
		(width 0.1524)
		(layer "In4.Cu")
		(net "M_B_DQ35")
	)
	(segment
		(start 149.8854 -29.1338)
		(end 149.5806 -29.1338)
		(width 0.1524)
		(layer "In4.Cu")
		(net "M_B_DQ35")
	)
	(segment
		(start 137.886694 -29.80563)
		(end 137.734294 -29.65323)
		(width 0.1524)
		(layer "In4.Cu")
		(net "M_B_DQ35")
	)
	(segment
		(start 150.9268 -29.65323)
		(end 150.7744 -29.80563)
		(width 0.1524)
		(layer "In4.Cu")
		(net "M_B_DQ35")
	)
	(segment
		(start 111.190278 -30.088332)
		(end 111.745268 -30.088332)
		(width 0.1016)
		(layer "In4.Cu")
		(net "M_B_DQ35")
	)
	(segment
		(start 174.1678 -7.824978)
		(end 174.14875 -7.844028)
		(width 0.1524)
		(layer "In4.Cu")
		(net "M_B_DQ35")
	)
	(segment
		(start 109.22 -32.4612)
		(end 109.22 -31.880556)
		(width 0.1016)
		(layer "In4.Cu")
		(net "M_B_DQ35")
	)
	(segment
		(start 109.449362 -31.651194)
		(end 109.627416 -31.651194)
		(width 0.1016)
		(layer "In4.Cu")
		(net "M_B_DQ35")
	)
	(segment
		(start 107.569 -32.5628)
		(end 107.95 -32.9438)
		(width 0.1016)
		(layer "In4.Cu")
		(net "M_B_DQ35")
	)
	(segment
		(start 139.182094 -29.80563)
		(end 139.004294 -29.62783)
		(width 0.1524)
		(layer "In4.Cu")
		(net "M_B_DQ35")
	)
	(segment
		(start 139.740894 -29.1338)
		(end 139.613894 -29.2608)
		(width 0.1524)
		(layer "In4.Cu")
		(net "M_B_DQ35")
	)
	(segment
		(start 174.14875 -12.615926)
		(end 157.630876 -29.1338)
		(width 0.1524)
		(layer "In4.Cu")
		(net "M_B_DQ35")
	)
	(segment
		(start 114.7572 -29.1338)
		(end 113.751868 -30.139132)
		(width 0.1524)
		(layer "In4.Cu")
		(net "M_B_DQ35")
	)
	(segment
		(start 109.627416 -31.651194)
		(end 111.190278 -30.088332)
		(width 0.1016)
		(layer "In4.Cu")
		(net "M_B_DQ35")
	)
	(segment
		(start 149.5806 -29.1338)
		(end 149.4282 -29.2862)
		(width 0.1524)
		(layer "In4.Cu")
		(net "M_B_DQ35")
	)
	(segment
		(start 137.734294 -29.2862)
		(end 137.581894 -29.1338)
		(width 0.1524)
		(layer "In4.Cu")
		(net "M_B_DQ35")
	)
	(segment
		(start 148.209 -29.2862)
		(end 148.209 -29.65323)
		(width 0.1524)
		(layer "In4.Cu")
		(net "M_B_DQ35")
	)
	(segment
		(start 148.0566 -29.80563)
		(end 140.401294 -29.80563)
		(width 0.1524)
		(layer "In4.Cu")
		(net "M_B_DQ35")
	)
	(segment
		(start 151.0792 -29.1338)
		(end 150.9268 -29.2862)
		(width 0.1524)
		(layer "In4.Cu")
		(net "M_B_DQ35")
	)
	(segment
		(start 148.209 -29.65323)
		(end 148.0566 -29.80563)
		(width 0.1524)
		(layer "In4.Cu")
		(net "M_B_DQ35")
	)
	(segment
		(start 150.0378 -29.2862)
		(end 149.8854 -29.1338)
		(width 0.1524)
		(layer "In4.Cu")
		(net "M_B_DQ35")
	)
	(segment
		(start 149.4282 -29.2862)
		(end 149.4282 -29.65323)
		(width 0.1524)
		(layer "In4.Cu")
		(net "M_B_DQ35")
	)
	(segment
		(start 174.14875 -7.844028)
		(end 174.14875 -12.615926)
		(width 0.1524)
		(layer "In4.Cu")
		(net "M_B_DQ35")
	)
	(segment
		(start 139.004294 -29.62783)
		(end 139.004294 -29.2608)
		(width 0.1524)
		(layer "In4.Cu")
		(net "M_B_DQ35")
	)
	(segment
		(start 139.436094 -29.80563)
		(end 139.182094 -29.80563)
		(width 0.1524)
		(layer "In4.Cu")
		(net "M_B_DQ35")
	)
	(segment
		(start 148.8186 -29.2862)
		(end 148.6662 -29.1338)
		(width 0.1524)
		(layer "In4.Cu")
		(net "M_B_DQ35")
	)
	(segment
		(start 148.3614 -29.1338)
		(end 148.209 -29.2862)
		(width 0.1524)
		(layer "In4.Cu")
		(net "M_B_DQ35")
	)
	(segment
		(start 113.751868 -30.139132)
		(end 113.171732 -30.139132)
		(width 0.1524)
		(layer "In4.Cu")
		(net "M_B_DQ35")
	)
	(segment
		(start 112.8776 -29.845)
		(end 111.9886 -29.845)
		(width 0.1524)
		(layer "In4.Cu")
		(net "M_B_DQ35")
	)
	(segment
		(start 138.394694 -29.62783)
		(end 138.216894 -29.80563)
		(width 0.1524)
		(layer "In4.Cu")
		(net "M_B_DQ35")
	)
	(segment
		(start 140.401294 -29.80563)
		(end 140.223494 -29.62783)
		(width 0.1524)
		(layer "In4.Cu")
		(net "M_B_DQ35")
	)
	(segment
		(start 150.1902 -29.80563)
		(end 150.0378 -29.65323)
		(width 0.1524)
		(layer "In4.Cu")
		(net "M_B_DQ35")
	)
	(segment
		(start 113.171732 -30.139132)
		(end 112.8776 -29.845)
		(width 0.1524)
		(layer "In4.Cu")
		(net "M_B_DQ35")
	)
	(segment
		(start 150.7744 -29.80563)
		(end 150.1902 -29.80563)
		(width 0.1524)
		(layer "In4.Cu")
		(net "M_B_DQ35")
	)
	(segment
		(start 111.9886 -29.845)
		(end 111.745268 -30.088332)
		(width 0.1524)
		(layer "In4.Cu")
		(net "M_B_DQ35")
	)
	(segment
		(start 108.7374 -32.9438)
		(end 109.22 -32.4612)
		(width 0.1016)
		(layer "In4.Cu")
		(net "M_B_DQ35")
	)
	(segment
		(start 149.2758 -29.80563)
		(end 148.971 -29.80563)
		(width 0.1524)
		(layer "In4.Cu")
		(net "M_B_DQ35")
	)
	(segment
		(start 148.971 -29.80563)
		(end 148.8186 -29.65323)
		(width 0.1524)
		(layer "In4.Cu")
		(net "M_B_DQ35")
	)
	(segment
		(start 148.8186 -29.65323)
		(end 148.8186 -29.2862)
		(width 0.1524)
		(layer "In4.Cu")
		(net "M_B_DQ35")
	)
	(segment
		(start 139.613894 -29.2608)
		(end 139.613894 -29.62783)
		(width 0.1524)
		(layer "In4.Cu")
		(net "M_B_DQ35")
	)
	(segment
		(start 138.877294 -29.1338)
		(end 138.521694 -29.1338)
		(width 0.1524)
		(layer "In4.Cu")
		(net "M_B_DQ35")
	)
	(segment
		(start 139.004294 -29.2608)
		(end 138.877294 -29.1338)
		(width 0.1524)
		(layer "In4.Cu")
		(net "M_B_DQ35")
	)
	(segment
		(start 138.394694 -29.2608)
		(end 138.394694 -29.62783)
		(width 0.1524)
		(layer "In4.Cu")
		(net "M_B_DQ35")
	)
	(segment
		(start 137.734294 -29.65323)
		(end 137.734294 -29.2862)
		(width 0.1524)
		(layer "In4.Cu")
		(net "M_B_DQ35")
	)
	(segment
		(start 138.216894 -29.80563)
		(end 137.886694 -29.80563)
		(width 0.1524)
		(layer "In4.Cu")
		(net "M_B_DQ35")
	)
	(segment
		(start 139.613894 -29.62783)
		(end 139.436094 -29.80563)
		(width 0.1524)
		(layer "In4.Cu")
		(net "M_B_DQ35")
	)
	(segment
		(start 107.95 -32.9438)
		(end 108.7374 -32.9438)
		(width 0.1016)
		(layer "In4.Cu")
		(net "M_B_DQ35")
	)
	(segment
		(start 149.4282 -29.65323)
		(end 149.2758 -29.80563)
		(width 0.1524)
		(layer "In4.Cu")
		(net "M_B_DQ35")
	)
	(segment
		(start 21.9456 -52.5526)
		(end 21.9202 -52.5272)
		(width 0.2032)
		(layer "F.Cu")
		(net "VR_PVCCP_ISEN1_R")
	)
	(segment
		(start 20.945602 -54.73954)
		(end 20.945602 -53.70957)
		(width 0.2032)
		(layer "F.Cu")
		(net "VR_PVCCP_ISEN1_R")
	)
	(segment
		(start 21.1836 -52.5272)
		(end 21.195538 -52.539138)
		(width 0.2032)
		(layer "F.Cu")
		(net "VR_PVCCP_ISEN1_R")
	)
	(segment
		(start 21.195538 -52.539138)
		(end 21.195538 -53.459634)
		(width 0.2032)
		(layer "F.Cu")
		(net "VR_PVCCP_ISEN1_R")
	)
	(segment
		(start 20.945602 -53.70957)
		(end 21.195538 -53.459634)
		(width 0.2032)
		(layer "F.Cu")
		(net "VR_PVCCP_ISEN1_R")
	)
	(segment
		(start 20.863052 -54.82209)
		(end 20.945602 -54.73954)
		(width 0.2032)
		(layer "F.Cu")
		(net "VR_PVCCP_ISEN1_R")
	)
	(segment
		(start 20.863052 -55.547006)
		(end 20.863052 -54.82209)
		(width 0.2032)
		(layer "F.Cu")
		(net "VR_PVCCP_ISEN1_R")
	)
	(segment
		(start 21.9202 -52.5272)
		(end 21.1836 -52.5272)
		(width 0.2032)
		(layer "F.Cu")
		(net "VR_PVCCP_ISEN1_R")
	)
	(via
		(at 21.195538 -53.459634)
		(size 0.7112)
		(drill 0.3556)
		(layers "F.Cu" "B.Cu")
		(net "VR_PVCCP_ISEN1_R")
	)
	(segment
		(start 189.1538 -17.7038)
		(end 189.1538 -17.3482)
		(width 0.254)
		(layer "F.Cu")
		(net "PV_VTT_DDR_B_SNS")
	)
	(segment
		(start 187.7568 -17.8308)
		(end 187.16371 -17.23771)
		(width 0.254)
		(layer "F.Cu")
		(net "PV_VTT_DDR_B_SNS")
	)
	(segment
		(start 189.1538 -17.7038)
		(end 189.0268 -17.8308)
		(width 0.254)
		(layer "F.Cu")
		(net "PV_VTT_DDR_B_SNS")
	)
	(segment
		(start 189.1538 -17.3482)
		(end 188.595 -16.7894)
		(width 0.254)
		(layer "F.Cu")
		(net "PV_VTT_DDR_B_SNS")
	)
	(segment
		(start 189.0268 -17.8308)
		(end 188.0362 -17.8308)
		(width 0.254)
		(layer "F.Cu")
		(net "PV_VTT_DDR_B_SNS")
	)
	(segment
		(start 187.16371 -17.23771)
		(end 186.760358 -17.23771)
		(width 0.254)
		(layer "F.Cu")
		(net "PV_VTT_DDR_B_SNS")
	)
	(segment
		(start 188.0362 -17.8308)
		(end 187.7568 -17.8308)
		(width 0.254)
		(layer "F.Cu")
		(net "PV_VTT_DDR_B_SNS")
	)
	(via
		(at 188.0362 -17.8308)
		(size 0.7112)
		(drill 0.3556)
		(layers "F.Cu" "B.Cu")
		(net "PV_VTT_DDR_B_SNS")
	)
	(segment
		(start 112.747806 -35.080194)
		(end 111.003588 -35.080194)
		(width 0.1016)
		(layer "F.Cu")
		(net "M_B_DQ46")
	)
	(segment
		(start 178.150012 -3.04419)
		(end 178.308 -3.202178)
		(width 0.1778)
		(layer "F.Cu")
		(net "M_B_DQ46")
	)
	(segment
		(start 178.150012 -1.68402)
		(end 178.150012 -3.04419)
		(width 0.1778)
		(layer "F.Cu")
		(net "M_B_DQ46")
	)
	(segment
		(start 111.003588 -35.080194)
		(end 110.602268 -35.481514)
		(width 0.1016)
		(layer "F.Cu")
		(net "M_B_DQ46")
	)
	(segment
		(start 114.8588 -32.9692)
		(end 112.747806 -35.080194)
		(width 0.1016)
		(layer "F.Cu")
		(net "M_B_DQ46")
	)
	(via
		(at 114.8588 -32.9692)
		(size 0.4318)
		(drill 0.2032)
		(layers "F.Cu" "B.Cu")
		(net "M_B_DQ46")
	)
	(via
		(at 178.308 -3.202178)
		(size 0.4318)
		(drill 0.2032)
		(layers "F.Cu" "B.Cu")
		(net "M_B_DQ46")
	)
	(segment
		(start 178.449986 -3.009392)
		(end 178.308 -3.151378)
		(width 0.1778)
		(layer "B.Cu")
		(net "M_B_DQ46")
	)
	(segment
		(start 178.308 -3.151378)
		(end 178.308 -3.202178)
		(width 0.1778)
		(layer "B.Cu")
		(net "M_B_DQ46")
	)
	(segment
		(start 178.449986 -1.690624)
		(end 178.449986 -3.009392)
		(width 0.1778)
		(layer "B.Cu")
		(net "M_B_DQ46")
	)
	(segment
		(start 117.983 -32.4612)
		(end 118.927626 -31.516574)
		(width 0.1016)
		(layer "In2.Cu")
		(net "M_B_DQ46")
	)
	(segment
		(start 177.31232 -6.890258)
		(end 178.308 -5.894578)
		(width 0.1524)
		(layer "In2.Cu")
		(net "M_B_DQ46")
	)
	(segment
		(start 163.740338 -20.3454)
		(end 166.203376 -20.3454)
		(width 0.1524)
		(layer "In2.Cu")
		(net "M_B_DQ46")
	)
	(segment
		(start 128.9939 -29.6291)
		(end 130.38328 -29.6291)
		(width 0.1524)
		(layer "In2.Cu")
		(net "M_B_DQ46")
	)
	(segment
		(start 115.3668 -32.4612)
		(end 117.983 -32.4612)
		(width 0.1016)
		(layer "In2.Cu")
		(net "M_B_DQ46")
	)
	(segment
		(start 154.857958 -29.22778)
		(end 163.740338 -20.3454)
		(width 0.1524)
		(layer "In2.Cu")
		(net "M_B_DQ46")
	)
	(segment
		(start 118.927626 -31.516574)
		(end 127.106426 -31.516574)
		(width 0.1524)
		(layer "In2.Cu")
		(net "M_B_DQ46")
	)
	(segment
		(start 176.5554 -10.3378)
		(end 177.31232 -9.58088)
		(width 0.1524)
		(layer "In2.Cu")
		(net "M_B_DQ46")
	)
	(segment
		(start 178.308 -5.894578)
		(end 178.308 -3.202178)
		(width 0.1524)
		(layer "In2.Cu")
		(net "M_B_DQ46")
	)
	(segment
		(start 114.8588 -32.9692)
		(end 115.3668 -32.4612)
		(width 0.1016)
		(layer "In2.Cu")
		(net "M_B_DQ46")
	)
	(segment
		(start 166.203376 -20.3454)
		(end 176.210976 -10.3378)
		(width 0.1524)
		(layer "In2.Cu")
		(net "M_B_DQ46")
	)
	(segment
		(start 127.106426 -31.516574)
		(end 128.9939 -29.6291)
		(width 0.1524)
		(layer "In2.Cu")
		(net "M_B_DQ46")
	)
	(segment
		(start 130.38328 -29.6291)
		(end 130.7846 -29.22778)
		(width 0.1524)
		(layer "In2.Cu")
		(net "M_B_DQ46")
	)
	(segment
		(start 176.210976 -10.3378)
		(end 176.5554 -10.3378)
		(width 0.1524)
		(layer "In2.Cu")
		(net "M_B_DQ46")
	)
	(segment
		(start 130.7846 -29.22778)
		(end 154.857958 -29.22778)
		(width 0.1524)
		(layer "In2.Cu")
		(net "M_B_DQ46")
	)
	(segment
		(start 177.31232 -9.58088)
		(end 177.31232 -6.890258)
		(width 0.1524)
		(layer "In2.Cu")
		(net "M_B_DQ46")
	)
	(segment
		(start 93.632528 -29.954474)
		(end 93.98 -29.607002)
		(width 0.127)
		(layer "F.Cu")
		(net "TP_CPU_RSVD17")
	)
	(segment
		(start 93.632528 -29.997654)
		(end 93.632528 -29.954474)
		(width 0.127)
		(layer "F.Cu")
		(net "TP_CPU_RSVD17")
	)
	(via
		(at 93.98 -29.607002)
		(size 0.4318)
		(drill 0.2032)
		(layers "F.Cu" "B.Cu")
		(net "TP_CPU_RSVD17")
	)
	(segment
		(start 94.234 -29.607002)
		(end 93.98 -29.607002)
		(width 0.127)
		(layer "B.Cu")
		(net "TP_CPU_RSVD17")
	)
	(segment
		(start 94.869 -28.972002)
		(end 94.234 -29.607002)
		(width 0.127)
		(layer "B.Cu")
		(net "TP_CPU_RSVD17")
	)
	(segment
		(start 99.451668 -36.799774)
		(end 99.44989 -36.799774)
		(width 0.127)
		(layer "F.Cu")
		(net "TP_CPU_RSVD11")
	)
	(segment
		(start 99.44989 -36.799774)
		(end 99.021392 -37.228272)
		(width 0.127)
		(layer "F.Cu")
		(net "TP_CPU_RSVD11")
	)
	(via
		(at 99.021392 -37.228272)
		(size 0.4318)
		(drill 0.2032)
		(layers "F.Cu" "B.Cu")
		(net "TP_CPU_RSVD11")
	)
	(segment
		(start 99.020376 -37.229288)
		(end 99.021392 -37.228272)
		(width 0.127)
		(layer "B.Cu")
		(net "TP_CPU_RSVD11")
	)
	(segment
		(start 98.282252 -37.229288)
		(end 99.020376 -37.229288)
		(width 0.127)
		(layer "B.Cu")
		(net "TP_CPU_RSVD11")
	)
	(segment
		(start 27.7368 -56.9468)
		(end 28.0416 -57.2516)
		(width 0.508)
		(layer "F.Cu")
		(net "VR_PVCCP_LH_R")
	)
	(segment
		(start 43.322494 -61.147706)
		(end 43.322494 -59.944)
		(width 0.508)
		(layer "F.Cu")
		(net "VR_PVCCP_LH_R")
	)
	(segment
		(start 42.291 -61.214)
		(end 43.2562 -61.214)
		(width 0.508)
		(layer "F.Cu")
		(net "VR_PVCCP_LH_R")
	)
	(segment
		(start 28.0416 -57.2516)
		(end 28.6512 -57.2516)
		(width 0.508)
		(layer "F.Cu")
		(net "VR_PVCCP_LH_R")
	)
	(segment
		(start 43.2562 -61.214)
		(end 43.322494 -61.147706)
		(width 0.508)
		(layer "F.Cu")
		(net "VR_PVCCP_LH_R")
	)
	(via
		(at 41.4528 -61.214)
		(size 0.7112)
		(drill 0.3556)
		(layers "F.Cu" "B.Cu")
		(net "VR_PVCCP_LH_R")
	)
	(via
		(at 28.6512 -57.2516)
		(size 0.508)
		(drill 0.254)
		(layers "F.Cu" "B.Cu")
		(net "VR_PVCCP_LH_R")
	)
	(via
		(at 42.291 -61.214)
		(size 0.7112)
		(drill 0.4064)
		(layers "F.Cu" "B.Cu")
		(net "VR_PVCCP_LH_R")
	)
	(segment
		(start 42.291 -61.214)
		(end 41.4528 -61.214)
		(width 0.635)
		(layer "B.Cu")
		(net "VR_PVCCP_LH_R")
	)
	(segment
		(start 31.7246 -57.2516)
		(end 35.687 -61.214)
		(width 0.635)
		(layer "In2.Cu")
		(net "VR_PVCCP_LH_R")
	)
	(segment
		(start 28.6512 -57.2516)
		(end 31.7246 -57.2516)
		(width 0.635)
		(layer "In2.Cu")
		(net "VR_PVCCP_LH_R")
	)
	(segment
		(start 35.687 -61.214)
		(end 42.291 -61.214)
		(width 0.635)
		(layer "In2.Cu")
		(net "VR_PVCCP_LH_R")
	)
	(segment
		(start 185.76036 -16.29664)
		(end 185.76036 -17.23771)
		(width 0.3048)
		(layer "F.Cu")
		(net "PV_VTT_DDR_B")
	)
	(segment
		(start 185.928 -16.129)
		(end 185.76036 -16.29664)
		(width 0.3048)
		(layer "F.Cu")
		(net "PV_VTT_DDR_B")
	)
	(via
		(at 195.707 -3.303778)
		(size 0.7112)
		(drill 0.4064)
		(layers "F.Cu" "B.Cu")
		(net "PV_VTT_DDR_B")
	)
	(via
		(at 186.944 -15.748)
		(size 0.7112)
		(drill 0.3556)
		(layers "F.Cu" "B.Cu")
		(net "PV_VTT_DDR_B")
	)
	(via
		(at 192.786 -9.526778)
		(size 0.7112)
		(drill 0.4064)
		(layers "F.Cu" "B.Cu")
		(net "PV_VTT_DDR_B")
	)
	(via
		(at 185.928 -16.129)
		(size 0.7112)
		(drill 0.4064)
		(layers "F.Cu" "B.Cu")
		(net "PV_VTT_DDR_B")
	)
	(segment
		(start 187.0202 -20.701)
		(end 187.406788 -20.701)
		(width 0.254)
		(layer "F.Cu")
		(net "PV_VTT_DDR_B_REFO")
	)
	(segment
		(start 186.760358 -20.15871)
		(end 186.760358 -20.441158)
		(width 0.254)
		(layer "F.Cu")
		(net "PV_VTT_DDR_B_REFO")
	)
	(segment
		(start 187.406788 -20.701)
		(end 187.937394 -21.231606)
		(width 0.254)
		(layer "F.Cu")
		(net "PV_VTT_DDR_B_REFO")
	)
	(segment
		(start 186.760358 -20.441158)
		(end 187.0202 -20.701)
		(width 0.254)
		(layer "F.Cu")
		(net "PV_VTT_DDR_B_REFO")
	)
	(segment
		(start 188.341 -21.635212)
		(end 187.937394 -21.231606)
		(width 0.254)
		(layer "F.Cu")
		(net "PV_VTT_DDR_B_REFO")
	)
	(segment
		(start 188.341 -22.0218)
		(end 188.341 -21.635212)
		(width 0.254)
		(layer "F.Cu")
		(net "PV_VTT_DDR_B_REFO")
	)
	(via
		(at 187.937394 -21.231606)
		(size 0.7112)
		(drill 0.3556)
		(layers "F.Cu" "B.Cu")
		(net "PV_VTT_DDR_B_REFO")
	)
	(segment
		(start 106.669586 -35.697414)
		(end 106.172 -36.195)
		(width 0.1016)
		(layer "F.Cu")
		(net "M_B_DQ51")
	)
	(segment
		(start 183.249824 -9.055354)
		(end 183.769 -8.536178)
		(width 0.1778)
		(layer "F.Cu")
		(net "M_B_DQ51")
	)
	(segment
		(start 183.249824 -9.897364)
		(end 183.249824 -9.055354)
		(width 0.1778)
		(layer "F.Cu")
		(net "M_B_DQ51")
	)
	(segment
		(start 106.909108 -35.697414)
		(end 106.669586 -35.697414)
		(width 0.1016)
		(layer "F.Cu")
		(net "M_B_DQ51")
	)
	(segment
		(start 183.769 -8.536178)
		(end 183.769 -7.596378)
		(width 0.1778)
		(layer "F.Cu")
		(net "M_B_DQ51")
	)
	(via
		(at 183.769 -7.596378)
		(size 0.4318)
		(drill 0.2032)
		(layers "F.Cu" "B.Cu")
		(net "M_B_DQ51")
	)
	(via
		(at 106.172 -36.195)
		(size 0.4318)
		(drill 0.2032)
		(layers "F.Cu" "B.Cu")
		(net "M_B_DQ51")
	)
	(segment
		(start 183.78551 -7.654798)
		(end 183.769 -7.638288)
		(width 0.1778)
		(layer "B.Cu")
		(net "M_B_DQ51")
	)
	(segment
		(start 184.15 -9.89076)
		(end 184.15 -8.739378)
		(width 0.1778)
		(layer "B.Cu")
		(net "M_B_DQ51")
	)
	(segment
		(start 183.769 -7.638288)
		(end 183.769 -7.596378)
		(width 0.1778)
		(layer "B.Cu")
		(net "M_B_DQ51")
	)
	(segment
		(start 184.15 -8.739378)
		(end 183.78551 -8.374888)
		(width 0.1778)
		(layer "B.Cu")
		(net "M_B_DQ51")
	)
	(segment
		(start 183.78551 -8.374888)
		(end 183.78551 -7.654798)
		(width 0.1778)
		(layer "B.Cu")
		(net "M_B_DQ51")
	)
	(segment
		(start 107.05338 -38.59784)
		(end 107.293664 -38.650672)
		(width 0.1016)
		(layer "In9.Cu")
		(net "M_B_DQ51")
	)
	(segment
		(start 181.1782 -16.51)
		(end 182.626 -12.954)
		(width 0.1524)
		(layer "In9.Cu")
		(net "M_B_DQ51")
	)
	(segment
		(start 168.079166 -30.791912)
		(end 181.1782 -16.51)
		(width 0.1524)
		(layer "In9.Cu")
		(net "M_B_DQ51")
	)
	(segment
		(start 156.7815 -39.621714)
		(end 157.894782 -39.621714)
		(width 0.1524)
		(layer "In9.Cu")
		(net "M_B_DQ51")
	)
	(segment
		(start 111.428276 -39.600124)
		(end 111.604552 -39.7764)
		(width 0.1016)
		(layer "In9.Cu")
		(net "M_B_DQ51")
	)
	(segment
		(start 182.626 -12.954)
		(end 183.78551 -10.75309)
		(width 0.1524)
		(layer "In9.Cu")
		(net "M_B_DQ51")
	)
	(segment
		(start 110.215426 -38.90899)
		(end 111.428276 -39.600124)
		(width 0.1016)
		(layer "In9.Cu")
		(net "M_B_DQ51")
	)
	(segment
		(start 106.56316 -38.33368)
		(end 107.05338 -38.59784)
		(width 0.1016)
		(layer "In9.Cu")
		(net "M_B_DQ51")
	)
	(segment
		(start 109.986318 -38.82517)
		(end 110.215426 -38.90899)
		(width 0.1016)
		(layer "In9.Cu")
		(net "M_B_DQ51")
	)
	(segment
		(start 106.5276 -37.1602)
		(end 106.515154 -37.58819)
		(width 0.1016)
		(layer "In9.Cu")
		(net "M_B_DQ51")
	)
	(segment
		(start 183.78551 -7.654798)
		(end 183.769 -7.638288)
		(width 0.1524)
		(layer "In9.Cu")
		(net "M_B_DQ51")
	)
	(segment
		(start 127.802386 -39.757604)
		(end 156.7815 -39.621714)
		(width 0.1524)
		(layer "In9.Cu")
		(net "M_B_DQ51")
	)
	(segment
		(start 106.172 -36.195)
		(end 106.481118 -37.00526)
		(width 0.1016)
		(layer "In9.Cu")
		(net "M_B_DQ51")
	)
	(segment
		(start 127.79756 -39.76243)
		(end 127.802386 -39.757604)
		(width 0.1524)
		(layer "In9.Cu")
		(net "M_B_DQ51")
	)
	(segment
		(start 106.50982 -38.17366)
		(end 106.56316 -38.33368)
		(width 0.1016)
		(layer "In9.Cu")
		(net "M_B_DQ51")
	)
	(segment
		(start 183.769 -7.638288)
		(end 183.769 -7.596378)
		(width 0.1524)
		(layer "In9.Cu")
		(net "M_B_DQ51")
	)
	(segment
		(start 111.604552 -39.7764)
		(end 123.7742 -39.7764)
		(width 0.1524)
		(layer "In9.Cu")
		(net "M_B_DQ51")
	)
	(segment
		(start 123.7742 -39.7764)
		(end 126.751334 -39.76243)
		(width 0.1524)
		(layer "In9.Cu")
		(net "M_B_DQ51")
	)
	(segment
		(start 106.515154 -37.58819)
		(end 106.50982 -38.17366)
		(width 0.1016)
		(layer "In9.Cu")
		(net "M_B_DQ51")
	)
	(segment
		(start 107.293664 -38.650672)
		(end 109.024166 -38.675818)
		(width 0.1016)
		(layer "In9.Cu")
		(net "M_B_DQ51")
	)
	(segment
		(start 126.751334 -39.76243)
		(end 127.79756 -39.76243)
		(width 0.1524)
		(layer "In9.Cu")
		(net "M_B_DQ51")
	)
	(segment
		(start 109.024166 -38.675818)
		(end 109.986318 -38.82517)
		(width 0.1016)
		(layer "In9.Cu")
		(net "M_B_DQ51")
	)
	(segment
		(start 183.78551 -10.75309)
		(end 183.78551 -7.654798)
		(width 0.1524)
		(layer "In9.Cu")
		(net "M_B_DQ51")
	)
	(segment
		(start 157.894782 -39.621714)
		(end 163.176712 -35.694366)
		(width 0.1524)
		(layer "In9.Cu")
		(net "M_B_DQ51")
	)
	(segment
		(start 163.176712 -35.694366)
		(end 168.079166 -30.791912)
		(width 0.1524)
		(layer "In9.Cu")
		(net "M_B_DQ51")
	)
	(segment
		(start 106.481118 -37.00526)
		(end 106.5276 -37.1602)
		(width 0.1016)
		(layer "In9.Cu")
		(net "M_B_DQ51")
	)
	(segment
		(start 100.249228 -36.819332)
		(end 99.873816 -37.194744)
		(width 0.127)
		(layer "F.Cu")
		(net "TP_CPU_RSVD12")
	)
	(segment
		(start 100.249228 -36.799774)
		(end 100.249228 -36.819332)
		(width 0.127)
		(layer "F.Cu")
		(net "TP_CPU_RSVD12")
	)
	(via
		(at 99.873816 -37.194744)
		(size 0.4318)
		(drill 0.2032)
		(layers "F.Cu" "B.Cu")
		(net "TP_CPU_RSVD12")
	)
	(segment
		(start 99.370134 -36.028122)
		(end 99.370134 -36.691062)
		(width 0.127)
		(layer "B.Cu")
		(net "TP_CPU_RSVD12")
	)
	(segment
		(start 98.964496 -35.622484)
		(end 99.370134 -36.028122)
		(width 0.127)
		(layer "B.Cu")
		(net "TP_CPU_RSVD12")
	)
	(segment
		(start 99.370134 -36.691062)
		(end 99.873816 -37.194744)
		(width 0.127)
		(layer "B.Cu")
		(net "TP_CPU_RSVD12")
	)
	(segment
		(start 24.335994 -58.220102)
		(end 26.67 -58.220102)
		(width 0.2032)
		(layer "F.Cu")
		(net "VR_PVCCP_PWM3")
	)
	(segment
		(start 27.6352 -58.0136)
		(end 26.876502 -58.0136)
		(width 0.2032)
		(layer "F.Cu")
		(net "VR_PVCCP_PWM3")
	)
	(segment
		(start 26.876502 -58.0136)
		(end 26.67 -58.220102)
		(width 0.2032)
		(layer "F.Cu")
		(net "VR_PVCCP_PWM3")
	)
	(via
		(at 26.67 -58.220102)
		(size 0.7112)
		(drill 0.3556)
		(layers "F.Cu" "B.Cu")
		(net "VR_PVCCP_PWM3")
	)
	(segment
		(start 180.8734 -17.2212)
		(end 180.594 -16.9418)
		(width 0.254)
		(layer "F.Cu")
		(net "PV_VTT_DDR_B_REFIN")
	)
	(segment
		(start 183.6674 -17.653)
		(end 183.134 -17.653)
		(width 0.254)
		(layer "F.Cu")
		(net "PV_VTT_DDR_B_REFIN")
	)
	(segment
		(start 182.118 -17.1958)
		(end 181.3814 -17.1958)
		(width 0.254)
		(layer "F.Cu")
		(net "PV_VTT_DDR_B_REFIN")
	)
	(segment
		(start 184.760362 -17.23771)
		(end 184.08269 -17.23771)
		(width 0.254)
		(layer "F.Cu")
		(net "PV_VTT_DDR_B_REFIN")
	)
	(segment
		(start 181.3814 -17.1958)
		(end 181.356 -17.2212)
		(width 0.254)
		(layer "F.Cu")
		(net "PV_VTT_DDR_B_REFIN")
	)
	(segment
		(start 181.356 -17.2212)
		(end 180.8734 -17.2212)
		(width 0.254)
		(layer "F.Cu")
		(net "PV_VTT_DDR_B_REFIN")
	)
	(segment
		(start 184.08269 -17.23771)
		(end 183.6674 -17.653)
		(width 0.254)
		(layer "F.Cu")
		(net "PV_VTT_DDR_B_REFIN")
	)
	(segment
		(start 182.118 -17.1958)
		(end 182.6768 -17.1958)
		(width 0.254)
		(layer "F.Cu")
		(net "PV_VTT_DDR_B_REFIN")
	)
	(segment
		(start 182.6768 -17.1958)
		(end 183.134 -17.653)
		(width 0.254)
		(layer "F.Cu")
		(net "PV_VTT_DDR_B_REFIN")
	)
	(via
		(at 183.134 -17.653)
		(size 0.7112)
		(drill 0.3556)
		(layers "F.Cu" "B.Cu")
		(net "PV_VTT_DDR_B_REFIN")
	)
	(segment
		(start 141.549882 -1.68402)
		(end 141.549882 -2.436876)
		(width 0.1778)
		(layer "F.Cu")
		(net "M_B_DQS_DP2")
	)
	(segment
		(start 141.402308 -2.58445)
		(end 141.402308 -5.553456)
		(width 0.1778)
		(layer "F.Cu")
		(net "M_B_DQS_DP2")
	)
	(segment
		(start 100.9142 -22.648672)
		(end 101.2952 -23.029672)
		(width 0.1016)
		(layer "F.Cu")
		(net "M_B_DQS_DP2")
	)
	(segment
		(start 101.2952 -25.197816)
		(end 101.759512 -25.662128)
		(width 0.1016)
		(layer "F.Cu")
		(net "M_B_DQS_DP2")
	)
	(segment
		(start 101.2952 -23.029672)
		(end 101.2952 -25.197816)
		(width 0.1016)
		(layer "F.Cu")
		(net "M_B_DQS_DP2")
	)
	(segment
		(start 141.549882 -2.436876)
		(end 141.402308 -2.58445)
		(width 0.1778)
		(layer "F.Cu")
		(net "M_B_DQS_DP2")
	)
	(segment
		(start 101.895148 -25.950926)
		(end 101.895148 -25.951434)
		(width 0.1016)
		(layer "F.Cu")
		(net "M_B_DQS_DP2")
	)
	(segment
		(start 141.402308 -5.553456)
		(end 141.66723 -5.818378)
		(width 0.1778)
		(layer "F.Cu")
		(net "M_B_DQS_DP2")
	)
	(segment
		(start 101.759512 -25.81529)
		(end 101.895148 -25.950926)
		(width 0.1016)
		(layer "F.Cu")
		(net "M_B_DQS_DP2")
	)
	(segment
		(start 101.759512 -25.662128)
		(end 101.759512 -25.81529)
		(width 0.1016)
		(layer "F.Cu")
		(net "M_B_DQS_DP2")
	)
	(via
		(at 100.9142 -22.648672)
		(size 0.4318)
		(drill 0.2032)
		(layers "F.Cu" "B.Cu")
		(net "M_B_DQS_DP2")
	)
	(via
		(at 141.66723 -5.818378)
		(size 0.4318)
		(drill 0.2032)
		(layers "F.Cu" "B.Cu")
		(net "M_B_DQS_DP2")
	)
	(segment
		(start 141.549882 -9.89076)
		(end 141.549882 -9.14146)
		(width 0.1778)
		(layer "B.Cu")
		(net "M_B_DQS_DP2")
	)
	(segment
		(start 141.402308 -8.993886)
		(end 141.402308 -6.0833)
		(width 0.1778)
		(layer "B.Cu")
		(net "M_B_DQS_DP2")
	)
	(segment
		(start 141.402308 -6.0833)
		(end 141.66723 -5.818378)
		(width 0.1778)
		(layer "B.Cu")
		(net "M_B_DQS_DP2")
	)
	(segment
		(start 141.549882 -9.14146)
		(end 141.402308 -8.993886)
		(width 0.1778)
		(layer "B.Cu")
		(net "M_B_DQS_DP2")
	)
	(segment
		(start 123.17095 -13.4874)
		(end 123.04649 -13.61186)
		(width 0.1524)
		(layer "In4.Cu")
		(net "M_B_DQS_DP2")
	)
	(segment
		(start 128.434592 -13.61186)
		(end 127.977392 -13.61186)
		(width 0.1524)
		(layer "In4.Cu")
		(net "M_B_DQS_DP2")
	)
	(segment
		(start 120.106948 -13.61186)
		(end 119.982488 -13.4874)
		(width 0.1524)
		(layer "In4.Cu")
		(net "M_B_DQS_DP2")
	)
	(segment
		(start 119.400828 -13.61186)
		(end 118.943628 -13.61186)
		(width 0.1524)
		(layer "In4.Cu")
		(net "M_B_DQS_DP2")
	)
	(segment
		(start 132.5372 -13.171424)
		(end 132.221224 -13.4874)
		(width 0.1524)
		(layer "In4.Cu")
		(net "M_B_DQS_DP2")
	)
	(segment
		(start 130.885692 -13.4874)
		(end 130.761232 -13.61186)
		(width 0.1524)
		(layer "In4.Cu")
		(net "M_B_DQS_DP2")
	)
	(segment
		(start 123.75261 -13.61186)
		(end 123.62815 -13.4874)
		(width 0.1524)
		(layer "In4.Cu")
		(net "M_B_DQS_DP2")
	)
	(segment
		(start 141.66723 -5.818378)
		(end 141.6304 -5.818378)
		(width 0.1524)
		(layer "In4.Cu")
		(net "M_B_DQS_DP2")
	)
	(segment
		(start 113.841276 -13.4874)
		(end 109.828076 -17.5006)
		(width 0.1524)
		(layer "In4.Cu")
		(net "M_B_DQS_DP2")
	)
	(segment
		(start 122.58929 -13.61186)
		(end 122.46483 -13.4874)
		(width 0.1524)
		(layer "In4.Cu")
		(net "M_B_DQS_DP2")
	)
	(segment
		(start 130.304032 -13.61186)
		(end 130.179572 -13.4874)
		(width 0.1524)
		(layer "In4.Cu")
		(net "M_B_DQS_DP2")
	)
	(segment
		(start 123.62815 -13.4874)
		(end 123.17095 -13.4874)
		(width 0.1524)
		(layer "In4.Cu")
		(net "M_B_DQS_DP2")
	)
	(segment
		(start 124.79147 -13.4874)
		(end 124.33427 -13.4874)
		(width 0.1524)
		(layer "In4.Cu")
		(net "M_B_DQS_DP2")
	)
	(segment
		(start 128.559052 -13.4874)
		(end 128.434592 -13.61186)
		(width 0.1524)
		(layer "In4.Cu")
		(net "M_B_DQS_DP2")
	)
	(segment
		(start 119.525288 -13.4874)
		(end 119.400828 -13.61186)
		(width 0.1524)
		(layer "In4.Cu")
		(net "M_B_DQS_DP2")
	)
	(segment
		(start 141.6304 -5.818378)
		(end 141.478 -5.970778)
		(width 0.1524)
		(layer "In4.Cu")
		(net "M_B_DQS_DP2")
	)
	(segment
		(start 129.140712 -13.61186)
		(end 129.016252 -13.4874)
		(width 0.1524)
		(layer "In4.Cu")
		(net "M_B_DQS_DP2")
	)
	(segment
		(start 120.564148 -13.61186)
		(end 120.106948 -13.61186)
		(width 0.1524)
		(layer "In4.Cu")
		(net "M_B_DQS_DP2")
	)
	(segment
		(start 141.478 -5.970778)
		(end 141.478 -6.758178)
		(width 0.1524)
		(layer "In4.Cu")
		(net "M_B_DQS_DP2")
	)
	(segment
		(start 125.37313 -13.61186)
		(end 124.91593 -13.61186)
		(width 0.1524)
		(layer "In4.Cu")
		(net "M_B_DQS_DP2")
	)
	(segment
		(start 130.761232 -13.61186)
		(end 130.304032 -13.61186)
		(width 0.1524)
		(layer "In4.Cu")
		(net "M_B_DQS_DP2")
	)
	(segment
		(start 117.780308 -13.61186)
		(end 117.655848 -13.4874)
		(width 0.1524)
		(layer "In4.Cu")
		(net "M_B_DQS_DP2")
	)
	(segment
		(start 141.224 -9.590024)
		(end 139.460224 -11.3538)
		(width 0.1524)
		(layer "In4.Cu")
		(net "M_B_DQS_DP2")
	)
	(segment
		(start 104.148128 -17.5006)
		(end 104.3432 -17.5006)
		(width 0.1016)
		(layer "In4.Cu")
		(net "M_B_DQS_DP2")
	)
	(segment
		(start 109.828076 -17.5006)
		(end 104.3432 -17.5006)
		(width 0.1524)
		(layer "In4.Cu")
		(net "M_B_DQS_DP2")
	)
	(segment
		(start 123.04649 -13.61186)
		(end 122.58929 -13.61186)
		(width 0.1524)
		(layer "In4.Cu")
		(net "M_B_DQS_DP2")
	)
	(segment
		(start 119.982488 -13.4874)
		(end 119.525288 -13.4874)
		(width 0.1524)
		(layer "In4.Cu")
		(net "M_B_DQS_DP2")
	)
	(segment
		(start 100.9142 -22.648672)
		(end 100.9142 -22.64791)
		(width 0.1016)
		(layer "In4.Cu")
		(net "M_B_DQS_DP2")
	)
	(segment
		(start 116.6114 -13.6144)
		(end 116.4844 -13.4874)
		(width 0.1524)
		(layer "In4.Cu")
		(net "M_B_DQS_DP2")
	)
	(segment
		(start 120.688608 -13.4874)
		(end 120.564148 -13.61186)
		(width 0.1524)
		(layer "In4.Cu")
		(net "M_B_DQS_DP2")
	)
	(segment
		(start 129.597912 -13.61186)
		(end 129.140712 -13.61186)
		(width 0.1524)
		(layer "In4.Cu")
		(net "M_B_DQS_DP2")
	)
	(segment
		(start 138.147552 -11.3538)
		(end 135.759952 -13.7414)
		(width 0.1524)
		(layer "In4.Cu")
		(net "M_B_DQS_DP2")
	)
	(segment
		(start 124.20981 -13.61186)
		(end 123.75261 -13.61186)
		(width 0.1524)
		(layer "In4.Cu")
		(net "M_B_DQS_DP2")
	)
	(segment
		(start 132.6896 -12.7254)
		(end 132.5372 -12.8778)
		(width 0.1524)
		(layer "In4.Cu")
		(net "M_B_DQS_DP2")
	)
	(segment
		(start 116.4844 -13.4874)
		(end 113.841276 -13.4874)
		(width 0.1524)
		(layer "In4.Cu")
		(net "M_B_DQS_DP2")
	)
	(segment
		(start 132.221224 -13.4874)
		(end 130.885692 -13.4874)
		(width 0.1524)
		(layer "In4.Cu")
		(net "M_B_DQS_DP2")
	)
	(segment
		(start 125.49759 -13.4874)
		(end 125.37313 -13.61186)
		(width 0.1524)
		(layer "In4.Cu")
		(net "M_B_DQS_DP2")
	)
	(segment
		(start 100.71989 -20.928838)
		(end 104.148128 -17.5006)
		(width 0.1016)
		(layer "In4.Cu")
		(net "M_B_DQS_DP2")
	)
	(segment
		(start 127.852932 -13.4874)
		(end 125.49759 -13.4874)
		(width 0.1524)
		(layer "In4.Cu")
		(net "M_B_DQS_DP2")
	)
	(segment
		(start 129.722372 -13.4874)
		(end 129.597912 -13.61186)
		(width 0.1524)
		(layer "In4.Cu")
		(net "M_B_DQS_DP2")
	)
	(segment
		(start 117.655848 -13.4874)
		(end 117.1956 -13.4874)
		(width 0.1524)
		(layer "In4.Cu")
		(net "M_B_DQS_DP2")
	)
	(segment
		(start 141.478 -6.758178)
		(end 141.224 -7.012178)
		(width 0.1524)
		(layer "In4.Cu")
		(net "M_B_DQS_DP2")
	)
	(segment
		(start 130.179572 -13.4874)
		(end 129.722372 -13.4874)
		(width 0.1524)
		(layer "In4.Cu")
		(net "M_B_DQS_DP2")
	)
	(segment
		(start 133.716776 -13.7414)
		(end 133.4262 -13.450824)
		(width 0.1524)
		(layer "In4.Cu")
		(net "M_B_DQS_DP2")
	)
	(segment
		(start 132.5372 -12.8778)
		(end 132.5372 -13.171424)
		(width 0.1524)
		(layer "In4.Cu")
		(net "M_B_DQS_DP2")
	)
	(segment
		(start 118.943628 -13.61186)
		(end 118.819168 -13.4874)
		(width 0.1524)
		(layer "In4.Cu")
		(net "M_B_DQS_DP2")
	)
	(segment
		(start 124.33427 -13.4874)
		(end 124.20981 -13.61186)
		(width 0.1524)
		(layer "In4.Cu")
		(net "M_B_DQS_DP2")
	)
	(segment
		(start 117.1956 -13.4874)
		(end 117.0686 -13.6144)
		(width 0.1524)
		(layer "In4.Cu")
		(net "M_B_DQS_DP2")
	)
	(segment
		(start 139.460224 -11.3538)
		(end 138.147552 -11.3538)
		(width 0.1524)
		(layer "In4.Cu")
		(net "M_B_DQS_DP2")
	)
	(segment
		(start 133.2738 -12.7254)
		(end 132.6896 -12.7254)
		(width 0.1524)
		(layer "In4.Cu")
		(net "M_B_DQS_DP2")
	)
	(segment
		(start 133.4262 -12.8778)
		(end 133.2738 -12.7254)
		(width 0.1524)
		(layer "In4.Cu")
		(net "M_B_DQS_DP2")
	)
	(segment
		(start 118.819168 -13.4874)
		(end 118.361968 -13.4874)
		(width 0.1524)
		(layer "In4.Cu")
		(net "M_B_DQS_DP2")
	)
	(segment
		(start 127.977392 -13.61186)
		(end 127.852932 -13.4874)
		(width 0.1524)
		(layer "In4.Cu")
		(net "M_B_DQS_DP2")
	)
	(segment
		(start 135.759952 -13.7414)
		(end 133.716776 -13.7414)
		(width 0.1524)
		(layer "In4.Cu")
		(net "M_B_DQS_DP2")
	)
	(segment
		(start 141.224 -7.012178)
		(end 141.224 -9.590024)
		(width 0.1524)
		(layer "In4.Cu")
		(net "M_B_DQS_DP2")
	)
	(segment
		(start 117.0686 -13.6144)
		(end 116.6114 -13.6144)
		(width 0.1524)
		(layer "In4.Cu")
		(net "M_B_DQS_DP2")
	)
	(segment
		(start 100.9142 -22.64791)
		(end 100.71989 -22.4536)
		(width 0.1016)
		(layer "In4.Cu")
		(net "M_B_DQS_DP2")
	)
	(segment
		(start 129.016252 -13.4874)
		(end 128.559052 -13.4874)
		(width 0.1524)
		(layer "In4.Cu")
		(net "M_B_DQS_DP2")
	)
	(segment
		(start 118.361968 -13.4874)
		(end 118.237508 -13.61186)
		(width 0.1524)
		(layer "In4.Cu")
		(net "M_B_DQS_DP2")
	)
	(segment
		(start 118.237508 -13.61186)
		(end 117.780308 -13.61186)
		(width 0.1524)
		(layer "In4.Cu")
		(net "M_B_DQS_DP2")
	)
	(segment
		(start 124.91593 -13.61186)
		(end 124.79147 -13.4874)
		(width 0.1524)
		(layer "In4.Cu")
		(net "M_B_DQS_DP2")
	)
	(segment
		(start 100.71989 -22.4536)
		(end 100.71989 -20.928838)
		(width 0.1016)
		(layer "In4.Cu")
		(net "M_B_DQS_DP2")
	)
	(segment
		(start 133.4262 -13.450824)
		(end 133.4262 -12.8778)
		(width 0.1524)
		(layer "In4.Cu")
		(net "M_B_DQS_DP2")
	)
	(segment
		(start 122.46483 -13.4874)
		(end 120.688608 -13.4874)
		(width 0.1524)
		(layer "In4.Cu")
		(net "M_B_DQS_DP2")
	)
	(segment
		(start 20.447 -68.453)
		(end 20.7518 -68.7578)
		(width 0.2032)
		(layer "F.Cu")
		(net "VR_PVNN_ISUMP_R2")
	)
	(segment
		(start 20.7518 -68.7578)
		(end 20.7518 -69.2404)
		(width 0.2032)
		(layer "F.Cu")
		(net "VR_PVNN_ISUMP_R2")
	)
	(segment
		(start 19.6342 -69.2404)
		(end 19.5834 -69.1896)
		(width 0.2032)
		(layer "F.Cu")
		(net "VR_PVNN_ISUMP_R2")
	)
	(segment
		(start 20.7518 -69.2404)
		(end 19.6342 -69.2404)
		(width 0.2032)
		(layer "F.Cu")
		(net "VR_PVNN_ISUMP_R2")
	)
	(via
		(at 20.7518 -69.2404)
		(size 0.7112)
		(drill 0.3556)
		(layers "F.Cu" "B.Cu")
		(net "VR_PVNN_ISUMP_R2")
	)
	(via
		(at 20.447 -68.453)
		(size 0.508)
		(drill 0.254)
		(layers "F.Cu" "B.Cu")
		(net "VR_PVNN_ISUMP_R2")
	)
	(segment
		(start 23.0505 -69.4563)
		(end 29.355288 -69.4563)
		(width 0.2032)
		(layer "B.Cu")
		(net "VR_PVNN_ISUMP_R2")
	)
	(segment
		(start 37.23513 -70.07987)
		(end 40.513 -66.802)
		(width 0.2032)
		(layer "B.Cu")
		(net "VR_PVNN_ISUMP_R2")
	)
	(segment
		(start 20.447 -68.453)
		(end 20.955 -67.945)
		(width 0.2032)
		(layer "B.Cu")
		(net "VR_PVNN_ISUMP_R2")
	)
	(segment
		(start 29.355288 -69.4563)
		(end 29.979112 -70.07987)
		(width 0.2032)
		(layer "B.Cu")
		(net "VR_PVNN_ISUMP_R2")
	)
	(segment
		(start 40.513 -65.4812)
		(end 40.3098 -65.278)
		(width 0.2032)
		(layer "B.Cu")
		(net "VR_PVNN_ISUMP_R2")
	)
	(segment
		(start 40.513 -66.802)
		(end 40.513 -65.4812)
		(width 0.2032)
		(layer "B.Cu")
		(net "VR_PVNN_ISUMP_R2")
	)
	(segment
		(start 29.979112 -70.07987)
		(end 37.23513 -70.07987)
		(width 0.2032)
		(layer "B.Cu")
		(net "VR_PVNN_ISUMP_R2")
	)
	(segment
		(start 21.5392 -67.945)
		(end 23.0505 -69.4563)
		(width 0.2032)
		(layer "B.Cu")
		(net "VR_PVNN_ISUMP_R2")
	)
	(segment
		(start 20.955 -67.945)
		(end 21.5392 -67.945)
		(width 0.2032)
		(layer "B.Cu")
		(net "VR_PVNN_ISUMP_R2")
	)
	(segment
		(start 158.37027 -7.569454)
		(end 158.37027 -6.389878)
		(width 0.2413)
		(layer "F.Cu")
		(net "M_B_MA11")
	)
	(segment
		(start 101.219 -31.903416)
		(end 101.245416 -31.929832)
		(width 0.1016)
		(layer "F.Cu")
		(net "M_B_MA11")
	)
	(segment
		(start 159.249872 -8.449056)
		(end 158.37027 -7.569454)
		(width 0.2413)
		(layer "F.Cu")
		(net "M_B_MA11")
	)
	(segment
		(start 101.245416 -31.951422)
		(end 101.577648 -32.283654)
		(width 0.1016)
		(layer "F.Cu")
		(net "M_B_MA11")
	)
	(segment
		(start 101.245416 -31.929832)
		(end 101.245416 -31.951422)
		(width 0.1016)
		(layer "F.Cu")
		(net "M_B_MA11")
	)
	(segment
		(start 158.37027 -6.389878)
		(end 158.38297 -6.377178)
		(width 0.2413)
		(layer "F.Cu")
		(net "M_B_MA11")
	)
	(segment
		(start 159.249872 -9.897364)
		(end 159.249872 -8.449056)
		(width 0.2413)
		(layer "F.Cu")
		(net "M_B_MA11")
	)
	(via
		(at 101.219 -31.903416)
		(size 0.4318)
		(drill 0.2032)
		(layers "F.Cu" "B.Cu")
		(net "M_B_MA11")
	)
	(via
		(at 158.38297 -6.377178)
		(size 0.4318)
		(drill 0.2032)
		(layers "F.Cu" "B.Cu")
		(net "M_B_MA11")
	)
	(segment
		(start 158.840678 -5.928106)
		(end 158.561278 -6.207506)
		(width 0.2413)
		(layer "B.Cu")
		(net "M_B_MA11")
	)
	(segment
		(start 159.249872 -3.783838)
		(end 158.840678 -4.192778)
		(width 0.2413)
		(layer "B.Cu")
		(net "M_B_MA11")
	)
	(segment
		(start 158.552642 -6.207506)
		(end 158.38297 -6.377178)
		(width 0.2413)
		(layer "B.Cu")
		(net "M_B_MA11")
	)
	(segment
		(start 158.561278 -6.207506)
		(end 158.552642 -6.207506)
		(width 0.2413)
		(layer "B.Cu")
		(net "M_B_MA11")
	)
	(segment
		(start 158.840678 -4.192778)
		(end 158.840678 -5.928106)
		(width 0.2413)
		(layer "B.Cu")
		(net "M_B_MA11")
	)
	(segment
		(start 159.249872 -1.690624)
		(end 159.249872 -3.783838)
		(width 0.2413)
		(layer "B.Cu")
		(net "M_B_MA11")
	)
	(segment
		(start 106.045 -22.7076)
		(end 105.791 -22.9616)
		(width 0.1905)
		(layer "In7.Cu")
		(net "M_B_MA11")
	)
	(segment
		(start 143.7132 -18.3388)
		(end 143.4338 -18.0594)
		(width 0.1905)
		(layer "In7.Cu")
		(net "M_B_MA11")
	)
	(segment
		(start 143.2306 -16.6878)
		(end 138.938 -16.6878)
		(width 0.1905)
		(layer "In7.Cu")
		(net "M_B_MA11")
	)
	(segment
		(start 101.6 -30.806644)
		(end 101.3714 -30.578044)
		(width 0.1016)
		(layer "In7.Cu")
		(net "M_B_MA11")
	)
	(segment
		(start 138.938 -16.6878)
		(end 138.7348 -16.891)
		(width 0.1905)
		(layer "In7.Cu")
		(net "M_B_MA11")
	)
	(segment
		(start 105.791 -22.9616)
		(end 105.791 -25.0952)
		(width 0.1905)
		(layer "In7.Cu")
		(net "M_B_MA11")
	)
	(segment
		(start 157.6832 -9.371076)
		(end 157.387544 -9.666732)
		(width 0.1905)
		(layer "In7.Cu")
		(net "M_B_MA11")
	)
	(segment
		(start 158.38297 -6.377178)
		(end 158.37027 -6.389878)
		(width 0.1905)
		(layer "In7.Cu")
		(net "M_B_MA11")
	)
	(segment
		(start 101.219 -31.903416)
		(end 101.243384 -31.903416)
		(width 0.1016)
		(layer "In7.Cu")
		(net "M_B_MA11")
	)
	(segment
		(start 101.243384 -31.903416)
		(end 101.6 -31.5468)
		(width 0.1016)
		(layer "In7.Cu")
		(net "M_B_MA11")
	)
	(segment
		(start 145.271236 -18.3388)
		(end 143.7132 -18.3388)
		(width 0.1905)
		(layer "In7.Cu")
		(net "M_B_MA11")
	)
	(segment
		(start 110.92815 -22.7076)
		(end 106.045 -22.7076)
		(width 0.1905)
		(layer "In7.Cu")
		(net "M_B_MA11")
	)
	(segment
		(start 143.4338 -18.0594)
		(end 143.4338 -16.891)
		(width 0.1905)
		(layer "In7.Cu")
		(net "M_B_MA11")
	)
	(segment
		(start 101.3714 -30.578044)
		(end 101.3714 -27.4828)
		(width 0.1016)
		(layer "In7.Cu")
		(net "M_B_MA11")
	)
	(segment
		(start 138.5443 -17.817846)
		(end 115.817904 -17.817846)
		(width 0.1905)
		(layer "In7.Cu")
		(net "M_B_MA11")
	)
	(segment
		(start 104.8512 -26.6446)
		(end 105.7529 -25.7429)
		(width 0.1016)
		(layer "In7.Cu")
		(net "M_B_MA11")
	)
	(segment
		(start 102.2096 -26.6446)
		(end 104.8512 -26.6446)
		(width 0.1016)
		(layer "In7.Cu")
		(net "M_B_MA11")
	)
	(segment
		(start 101.3714 -27.4828)
		(end 102.2096 -26.6446)
		(width 0.1016)
		(layer "In7.Cu")
		(net "M_B_MA11")
	)
	(segment
		(start 143.4338 -16.891)
		(end 143.2306 -16.6878)
		(width 0.1905)
		(layer "In7.Cu")
		(net "M_B_MA11")
	)
	(segment
		(start 115.817904 -17.817846)
		(end 110.92815 -22.7076)
		(width 0.1905)
		(layer "In7.Cu")
		(net "M_B_MA11")
	)
	(segment
		(start 138.7348 -16.891)
		(end 138.7348 -17.627346)
		(width 0.1905)
		(layer "In7.Cu")
		(net "M_B_MA11")
	)
	(segment
		(start 149.22119 -17.817846)
		(end 145.79219 -17.817846)
		(width 0.1905)
		(layer "In7.Cu")
		(net "M_B_MA11")
	)
	(segment
		(start 157.387544 -9.666732)
		(end 157.372304 -9.666732)
		(width 0.1905)
		(layer "In7.Cu")
		(net "M_B_MA11")
	)
	(segment
		(start 157.6832 -7.570978)
		(end 157.6832 -9.371076)
		(width 0.1905)
		(layer "In7.Cu")
		(net "M_B_MA11")
	)
	(segment
		(start 138.7348 -17.627346)
		(end 138.5443 -17.817846)
		(width 0.1905)
		(layer "In7.Cu")
		(net "M_B_MA11")
	)
	(segment
		(start 158.37027 -6.883908)
		(end 157.6832 -7.570978)
		(width 0.1905)
		(layer "In7.Cu")
		(net "M_B_MA11")
	)
	(segment
		(start 105.7529 -25.7429)
		(end 105.7529 -25.1333)
		(width 0.1016)
		(layer "In7.Cu")
		(net "M_B_MA11")
	)
	(segment
		(start 105.7529 -25.1333)
		(end 105.791 -25.0952)
		(width 0.1016)
		(layer "In7.Cu")
		(net "M_B_MA11")
	)
	(segment
		(start 157.372304 -9.666732)
		(end 149.22119 -17.817846)
		(width 0.1905)
		(layer "In7.Cu")
		(net "M_B_MA11")
	)
	(segment
		(start 101.6 -31.5468)
		(end 101.6 -30.806644)
		(width 0.1016)
		(layer "In7.Cu")
		(net "M_B_MA11")
	)
	(segment
		(start 158.37027 -6.389878)
		(end 158.37027 -6.883908)
		(width 0.1905)
		(layer "In7.Cu")
		(net "M_B_MA11")
	)
	(segment
		(start 145.79219 -17.817846)
		(end 145.271236 -18.3388)
		(width 0.1905)
		(layer "In7.Cu")
		(net "M_B_MA11")
	)
	(segment
		(start 96.605344 -41.15435)
		(end 96.251268 -40.800274)
		(width 0.127)
		(layer "F.Cu")
		(net "VCCCORE6VIDSI0GT_1P03")
	)
	(segment
		(start 96.647 -41.15435)
		(end 96.605344 -41.15435)
		(width 0.127)
		(layer "F.Cu")
		(net "VCCCORE6VIDSI0GT_1P03")
	)
	(via
		(at 96.647 -41.15435)
		(size 0.4318)
		(drill 0.2032)
		(layers "F.Cu" "B.Cu")
		(net "VCCCORE6VIDSI0GT_1P03")
	)
	(segment
		(start 95.5802 -40.8686)
		(end 96.36125 -40.8686)
		(width 0.127)
		(layer "B.Cu")
		(net "VCCCORE6VIDSI0GT_1P03")
	)
	(segment
		(start 96.36125 -40.8686)
		(end 96.647 -41.15435)
		(width 0.127)
		(layer "B.Cu")
		(net "VCCCORE6VIDSI0GT_1P03")
	)
	(segment
		(start 17.9832 -64.1604)
		(end 17.9832 -64.135)
		(width 0.2032)
		(layer "F.Cu")
		(net "VR_PVNN_VW")
	)
	(segment
		(start 17.145 -62.283848)
		(end 18.2372 -61.191648)
		(width 0.2032)
		(layer "F.Cu")
		(net "VR_PVNN_VW")
	)
	(segment
		(start 18.669 -65.0748)
		(end 17.9832 -64.389)
		(width 0.2032)
		(layer "F.Cu")
		(net "VR_PVNN_VW")
	)
	(segment
		(start 18.2372 -60.8076)
		(end 18.424906 -60.619894)
		(width 0.2032)
		(layer "F.Cu")
		(net "VR_PVNN_VW")
	)
	(segment
		(start 17.9832 -64.389)
		(end 17.9832 -64.1604)
		(width 0.2032)
		(layer "F.Cu")
		(net "VR_PVNN_VW")
	)
	(segment
		(start 18.051018 -64.067182)
		(end 18.051018 -63.375286)
		(width 0.2032)
		(layer "F.Cu")
		(net "VR_PVNN_VW")
	)
	(segment
		(start 17.9832 -64.135)
		(end 18.051018 -64.067182)
		(width 0.2032)
		(layer "F.Cu")
		(net "VR_PVNN_VW")
	)
	(segment
		(start 17.7546 -63.2968)
		(end 17.145 -62.6872)
		(width 0.2032)
		(layer "F.Cu")
		(net "VR_PVNN_VW")
	)
	(segment
		(start 18.424906 -60.619894)
		(end 18.590006 -60.619894)
		(width 0.2032)
		(layer "F.Cu")
		(net "VR_PVNN_VW")
	)
	(segment
		(start 17.972532 -63.2968)
		(end 17.7546 -63.2968)
		(width 0.2032)
		(layer "F.Cu")
		(net "VR_PVNN_VW")
	)
	(segment
		(start 18.051018 -63.375286)
		(end 17.972532 -63.2968)
		(width 0.2032)
		(layer "F.Cu")
		(net "VR_PVNN_VW")
	)
	(segment
		(start 17.145 -62.6872)
		(end 17.145 -62.283848)
		(width 0.2032)
		(layer "F.Cu")
		(net "VR_PVNN_VW")
	)
	(segment
		(start 18.2372 -61.191648)
		(end 18.2372 -60.8076)
		(width 0.2032)
		(layer "F.Cu")
		(net "VR_PVNN_VW")
	)
	(segment
		(start 18.8214 -65.0748)
		(end 18.669 -65.0748)
		(width 0.2032)
		(layer "F.Cu")
		(net "VR_PVNN_VW")
	)
	(via
		(at 18.8214 -65.0748)
		(size 0.7112)
		(drill 0.3556)
		(layers "F.Cu" "B.Cu")
		(net "VR_PVNN_VW")
	)
	(segment
		(start 187.749942 -2.99212)
		(end 187.8838 -3.125978)
		(width 0.1778)
		(layer "F.Cu")
		(net "M_B_DQ62")
	)
	(segment
		(start 105.766108 -36.982654)
		(end 106.1466 -37.3126)
		(width 0.1016)
		(layer "F.Cu")
		(net "M_B_DQ62")
	)
	(segment
		(start 187.8838 -3.125978)
		(end 187.8838 -3.481578)
		(width 0.1778)
		(layer "F.Cu")
		(net "M_B_DQ62")
	)
	(segment
		(start 187.749942 -1.68402)
		(end 187.749942 -2.99212)
		(width 0.1778)
		(layer "F.Cu")
		(net "M_B_DQ62")
	)
	(segment
		(start 187.8838 -3.481578)
		(end 187.706 -3.659378)
		(width 0.1778)
		(layer "F.Cu")
		(net "M_B_DQ62")
	)
	(via
		(at 106.1466 -37.3126)
		(size 0.4318)
		(drill 0.2032)
		(layers "F.Cu" "B.Cu")
		(net "M_B_DQ62")
	)
	(via
		(at 187.706 -3.659378)
		(size 0.4318)
		(drill 0.2032)
		(layers "F.Cu" "B.Cu")
		(net "M_B_DQ62")
	)
	(segment
		(start 188.049916 -1.690624)
		(end 188.049916 -3.315462)
		(width 0.1778)
		(layer "B.Cu")
		(net "M_B_DQ62")
	)
	(segment
		(start 188.049916 -3.315462)
		(end 187.706 -3.659378)
		(width 0.1778)
		(layer "B.Cu")
		(net "M_B_DQ62")
	)
	(segment
		(start 187.2996 -3.659378)
		(end 187.706 -3.659378)
		(width 0.1524)
		(layer "In2.Cu")
		(net "M_B_DQ62")
	)
	(segment
		(start 187.650374 -4.871974)
		(end 187.1472 -4.3688)
		(width 0.1524)
		(layer "In2.Cu")
		(net "M_B_DQ62")
	)
	(segment
		(start 154.9654 -37.323014)
		(end 157.92323 -36.816284)
		(width 0.1524)
		(layer "In2.Cu")
		(net "M_B_DQ62")
	)
	(segment
		(start 106.7054 -38.4302)
		(end 109.254036 -38.4302)
		(width 0.1016)
		(layer "In2.Cu")
		(net "M_B_DQ62")
	)
	(segment
		(start 157.92323 -36.816284)
		(end 182.80253 -11.936984)
		(width 0.1524)
		(layer "In2.Cu")
		(net "M_B_DQ62")
	)
	(segment
		(start 186.69 -8.6868)
		(end 186.8424 -8.155178)
		(width 0.1524)
		(layer "In2.Cu")
		(net "M_B_DQ62")
	)
	(segment
		(start 187.1472 -3.811778)
		(end 187.2996 -3.659378)
		(width 0.1524)
		(layer "In2.Cu")
		(net "M_B_DQ62")
	)
	(segment
		(start 106.3752 -38.1)
		(end 106.7054 -38.4302)
		(width 0.1016)
		(layer "In2.Cu")
		(net "M_B_DQ62")
	)
	(segment
		(start 182.80253 -11.936984)
		(end 185.6613 -9.7155)
		(width 0.1524)
		(layer "In2.Cu")
		(net "M_B_DQ62")
	)
	(segment
		(start 186.8424 -8.155178)
		(end 187.235592 -7.284212)
		(width 0.1524)
		(layer "In2.Cu")
		(net "M_B_DQ62")
	)
	(segment
		(start 185.6613 -9.7155)
		(end 186.69 -8.6868)
		(width 0.1524)
		(layer "In2.Cu")
		(net "M_B_DQ62")
	)
	(segment
		(start 112.130586 -37.323014)
		(end 154.9654 -37.323014)
		(width 0.1524)
		(layer "In2.Cu")
		(net "M_B_DQ62")
	)
	(segment
		(start 110.821724 -38.0492)
		(end 111.075724 -37.7952)
		(width 0.1016)
		(layer "In2.Cu")
		(net "M_B_DQ62")
	)
	(segment
		(start 106.1466 -37.3126)
		(end 106.3752 -38.1)
		(width 0.1016)
		(layer "In2.Cu")
		(net "M_B_DQ62")
	)
	(segment
		(start 109.254036 -38.4302)
		(end 110.821724 -38.0492)
		(width 0.1016)
		(layer "In2.Cu")
		(net "M_B_DQ62")
	)
	(segment
		(start 111.228124 -37.6428)
		(end 111.8108 -37.6428)
		(width 0.1524)
		(layer "In2.Cu")
		(net "M_B_DQ62")
	)
	(segment
		(start 187.1472 -4.3688)
		(end 187.1472 -3.811778)
		(width 0.1524)
		(layer "In2.Cu")
		(net "M_B_DQ62")
	)
	(segment
		(start 111.075724 -37.7952)
		(end 111.228124 -37.6428)
		(width 0.1524)
		(layer "In2.Cu")
		(net "M_B_DQ62")
	)
	(segment
		(start 187.235592 -7.284212)
		(end 187.650374 -5.643372)
		(width 0.1524)
		(layer "In2.Cu")
		(net "M_B_DQ62")
	)
	(segment
		(start 111.8108 -37.6428)
		(end 112.130586 -37.323014)
		(width 0.1524)
		(layer "In2.Cu")
		(net "M_B_DQ62")
	)
	(segment
		(start 187.650374 -5.643372)
		(end 187.650374 -4.871974)
		(width 0.1524)
		(layer "In2.Cu")
		(net "M_B_DQ62")
	)
	(segment
		(start 97.061528 -40.800274)
		(end 97.4598 -41.198546)
		(width 0.127)
		(layer "F.Cu")
		(net "VCCCORE7VIDSI0GT_1P03")
	)
	(segment
		(start 97.048828 -40.800274)
		(end 97.061528 -40.800274)
		(width 0.127)
		(layer "F.Cu")
		(net "VCCCORE7VIDSI0GT_1P03")
	)
	(via
		(at 97.4598 -41.198546)
		(size 0.4318)
		(drill 0.2032)
		(layers "F.Cu" "B.Cu")
		(net "VCCCORE7VIDSI0GT_1P03")
	)
	(segment
		(start 96.4438 -40.182546)
		(end 97.4598 -41.198546)
		(width 0.127)
		(layer "B.Cu")
		(net "VCCCORE7VIDSI0GT_1P03")
	)
	(segment
		(start 96.4438 -39.9923)
		(end 96.4438 -40.182546)
		(width 0.127)
		(layer "B.Cu")
		(net "VCCCORE7VIDSI0GT_1P03")
	)
	(segment
		(start 82.769202 -35.95624)
		(end 83.266788 -35.458654)
		(width 0.127)
		(layer "F.Cu")
		(net "TP_CPU_RSVD13")
	)
	(segment
		(start 82.769202 -36.031932)
		(end 82.769202 -35.95624)
		(width 0.127)
		(layer "F.Cu")
		(net "TP_CPU_RSVD13")
	)
	(segment
		(start 82.743802 -36.057332)
		(end 82.769202 -36.031932)
		(width 0.127)
		(layer "F.Cu")
		(net "TP_CPU_RSVD13")
	)
	(via
		(at 82.743802 -36.057332)
		(size 0.4318)
		(drill 0.2032)
		(layers "F.Cu" "B.Cu")
		(net "TP_CPU_RSVD13")
	)
	(segment
		(start 82.743802 -36.057332)
		(end 82.7405 -36.05403)
		(width 0.127)
		(layer "B.Cu")
		(net "TP_CPU_RSVD13")
	)
	(segment
		(start 82.373216 -35.713416)
		(end 81.541366 -35.713416)
		(width 0.127)
		(layer "B.Cu")
		(net "TP_CPU_RSVD13")
	)
	(segment
		(start 81.247996 -35.420046)
		(end 80.556354 -35.420046)
		(width 0.127)
		(layer "B.Cu")
		(net "TP_CPU_RSVD13")
	)
	(segment
		(start 82.71383 -36.05403)
		(end 82.373216 -35.713416)
		(width 0.127)
		(layer "B.Cu")
		(net "TP_CPU_RSVD13")
	)
	(segment
		(start 81.541366 -35.713416)
		(end 81.247996 -35.420046)
		(width 0.127)
		(layer "B.Cu")
		(net "TP_CPU_RSVD13")
	)
	(segment
		(start 80.556354 -35.420046)
		(end 80.518 -35.4584)
		(width 0.127)
		(layer "B.Cu")
		(net "TP_CPU_RSVD13")
	)
	(segment
		(start 82.7405 -36.05403)
		(end 82.71383 -36.05403)
		(width 0.127)
		(layer "B.Cu")
		(net "TP_CPU_RSVD13")
	)
	(segment
		(start 17.872202 -59.419998)
		(end 18.590006 -59.419998)
		(width 0.1143)
		(layer "F.Cu")
		(net "VR_95831_SDA")
	)
	(segment
		(start 16.637 -60.6552)
		(end 17.872202 -59.419998)
		(width 0.1143)
		(layer "F.Cu")
		(net "VR_95831_SDA")
	)
	(segment
		(start 16.2814 -60.6552)
		(end 16.637 -60.6552)
		(width 0.1143)
		(layer "F.Cu")
		(net "VR_95831_SDA")
	)
	(segment
		(start 97.851468 -35.199574)
		(end 97.851468 -35.199066)
		(width 0.254)
		(layer "F.Cu")
		(net "VCCCLKDDR1")
	)
	(segment
		(start 97.851468 -34.455608)
		(end 98.223832 -34.827972)
		(width 0.254)
		(layer "F.Cu")
		(net "VCCCLKDDR1")
	)
	(segment
		(start 97.851468 -34.399474)
		(end 97.851468 -34.455608)
		(width 0.254)
		(layer "F.Cu")
		(net "VCCCLKDDR1")
	)
	(segment
		(start 97.851468 -35.199066)
		(end 98.222562 -34.827972)
		(width 0.254)
		(layer "F.Cu")
		(net "VCCCLKDDR1")
	)
	(segment
		(start 98.222562 -34.827972)
		(end 98.223832 -34.827972)
		(width 0.254)
		(layer "F.Cu")
		(net "VCCCLKDDR1")
	)
	(via
		(at 98.223832 -34.827972)
		(size 0.4318)
		(drill 0.2032)
		(layers "F.Cu" "B.Cu")
		(net "VCCCLKDDR1")
	)
	(via
		(at 101.675184 -19.8882)
		(size 0.7112)
		(drill 0.3556)
		(layers "F.Cu" "B.Cu")
		(net "VCCCLKDDR1")
	)
	(segment
		(start 101.675184 -19.8882)
		(end 102.080568 -19.482816)
		(width 0.3048)
		(layer "B.Cu")
		(net "VCCCLKDDR1")
	)
	(segment
		(start 100.457 -19.8882)
		(end 101.675184 -19.8882)
		(width 0.3048)
		(layer "B.Cu")
		(net "VCCCLKDDR1")
	)
	(segment
		(start 97.508822 -33.323022)
		(end 97.508822 -32.682688)
		(width 0.3048)
		(layer "B.Cu")
		(net "VCCCLKDDR1")
	)
	(segment
		(start 97.108518 -29.3497)
		(end 96.7105 -29.3497)
		(width 0.3048)
		(layer "B.Cu")
		(net "VCCCLKDDR1")
	)
	(segment
		(start 95.9104 -26.030682)
		(end 96.901 -25.040082)
		(width 0.3048)
		(layer "B.Cu")
		(net "VCCCLKDDR1")
	)
	(segment
		(start 105.2576 -19.939)
		(end 105.156 -19.8374)
		(width 0.508)
		(layer "B.Cu")
		(net "VCCCLKDDR1")
	)
	(segment
		(start 96.901 -25.040082)
		(end 96.901 -20.574)
		(width 0.3048)
		(layer "B.Cu")
		(net "VCCCLKDDR1")
	)
	(segment
		(start 104.801416 -19.482816)
		(end 105.156 -19.8374)
		(width 0.3048)
		(layer "B.Cu")
		(net "VCCCLKDDR1")
	)
	(segment
		(start 97.409 -32.582866)
		(end 97.409 -29.650182)
		(width 0.3048)
		(layer "B.Cu")
		(net "VCCCLKDDR1")
	)
	(segment
		(start 97.508822 -32.682688)
		(end 97.409 -32.582866)
		(width 0.3048)
		(layer "B.Cu")
		(net "VCCCLKDDR1")
	)
	(segment
		(start 96.7105 -29.3497)
		(end 96.435672 -29.074872)
		(width 0.3048)
		(layer "B.Cu")
		(net "VCCCLKDDR1")
	)
	(segment
		(start 95.9104 -27.6098)
		(end 95.9104 -26.030682)
		(width 0.3048)
		(layer "B.Cu")
		(net "VCCCLKDDR1")
	)
	(segment
		(start 98.223832 -34.038032)
		(end 97.508822 -33.323022)
		(width 0.3048)
		(layer "B.Cu")
		(net "VCCCLKDDR1")
	)
	(segment
		(start 96.901 -20.574)
		(end 97.4598 -20.0152)
		(width 0.3048)
		(layer "B.Cu")
		(net "VCCCLKDDR1")
	)
	(segment
		(start 102.080568 -19.482816)
		(end 104.801416 -19.482816)
		(width 0.3048)
		(layer "B.Cu")
		(net "VCCCLKDDR1")
	)
	(segment
		(start 97.4598 -20.0152)
		(end 99.441 -20.0152)
		(width 0.3048)
		(layer "B.Cu")
		(net "VCCCLKDDR1")
	)
	(segment
		(start 99.568 -19.8882)
		(end 100.457 -19.8882)
		(width 0.3048)
		(layer "B.Cu")
		(net "VCCCLKDDR1")
	)
	(segment
		(start 97.409 -29.650182)
		(end 97.108518 -29.3497)
		(width 0.3048)
		(layer "B.Cu")
		(net "VCCCLKDDR1")
	)
	(segment
		(start 98.223832 -34.827972)
		(end 98.223832 -34.038032)
		(width 0.3048)
		(layer "B.Cu")
		(net "VCCCLKDDR1")
	)
	(segment
		(start 96.435672 -28.135072)
		(end 95.9104 -27.6098)
		(width 0.3048)
		(layer "B.Cu")
		(net "VCCCLKDDR1")
	)
	(segment
		(start 96.435672 -29.074872)
		(end 96.435672 -28.135072)
		(width 0.3048)
		(layer "B.Cu")
		(net "VCCCLKDDR1")
	)
	(segment
		(start 107.0356 -19.939)
		(end 105.2576 -19.939)
		(width 0.508)
		(layer "B.Cu")
		(net "VCCCLKDDR1")
	)
	(segment
		(start 99.441 -20.0152)
		(end 99.568 -19.8882)
		(width 0.3048)
		(layer "B.Cu")
		(net "VCCCLKDDR1")
	)
	(segment
		(start 108.714794 -8.8265)
		(end 108.714794 -7.967472)
		(width 0.1143)
		(layer "F.Cu")
		(net "CPU_ERR_N1")
	)
	(segment
		(start 111.872014 -10.136886)
		(end 110.02518 -10.136886)
		(width 0.1143)
		(layer "F.Cu")
		(net "CPU_ERR_N1")
	)
	(segment
		(start 81.302606 -41.352216)
		(end 81.204816 -41.352216)
		(width 0.1143)
		(layer "F.Cu")
		(net "CPU_ERR_N1")
	)
	(segment
		(start 125.657356 -27.0637)
		(end 122.884946 -27.0637)
		(width 0.1143)
		(layer "F.Cu")
		(net "CPU_ERR_N1")
	)
	(segment
		(start 110.02518 -10.136886)
		(end 108.714794 -8.8265)
		(width 0.1143)
		(layer "F.Cu")
		(net "CPU_ERR_N1")
	)
	(segment
		(start 118.020846 -22.1996)
		(end 118.020846 -16.285718)
		(width 0.1143)
		(layer "F.Cu")
		(net "CPU_ERR_N1")
	)
	(segment
		(start 122.884946 -27.0637)
		(end 118.020846 -22.1996)
		(width 0.1143)
		(layer "F.Cu")
		(net "CPU_ERR_N1")
	)
	(segment
		(start 81.646268 -41.008554)
		(end 81.302606 -41.352216)
		(width 0.1143)
		(layer "F.Cu")
		(net "CPU_ERR_N1")
	)
	(segment
		(start 108.714794 -7.967472)
		(end 107.833922 -7.0866)
		(width 0.1143)
		(layer "F.Cu")
		(net "CPU_ERR_N1")
	)
	(segment
		(start 128.387856 -29.7942)
		(end 125.657356 -27.0637)
		(width 0.1143)
		(layer "F.Cu")
		(net "CPU_ERR_N1")
	)
	(segment
		(start 132.1308 -29.7942)
		(end 128.387856 -29.7942)
		(width 0.1143)
		(layer "F.Cu")
		(net "CPU_ERR_N1")
	)
	(segment
		(start 118.020846 -16.285718)
		(end 111.872014 -10.136886)
		(width 0.1143)
		(layer "F.Cu")
		(net "CPU_ERR_N1")
	)
	(via
		(at 80.329786 -41.597834)
		(size 0.7112)
		(drill 0.3556)
		(layers "F.Cu" "B.Cu")
		(net "CPU_ERR_N1")
	)
	(via
		(at 81.204816 -41.352216)
		(size 0.4318)
		(drill 0.2032)
		(layers "F.Cu" "B.Cu")
		(net "CPU_ERR_N1")
	)
	(via
		(at 107.833922 -7.0866)
		(size 0.508)
		(drill 0.254)
		(layers "F.Cu" "B.Cu")
		(net "CPU_ERR_N1")
	)
	(segment
		(start 74.5998 -43.434)
		(end 75.6158 -43.434)
		(width 0.1143)
		(layer "B.Cu")
		(net "CPU_ERR_N1")
	)
	(segment
		(start 76.454 -42.5958)
		(end 79.33182 -42.5958)
		(width 0.1143)
		(layer "B.Cu")
		(net "CPU_ERR_N1")
	)
	(segment
		(start 75.6158 -43.434)
		(end 76.454 -42.5958)
		(width 0.1143)
		(layer "B.Cu")
		(net "CPU_ERR_N1")
	)
	(segment
		(start 81.204816 -41.352216)
		(end 80.575404 -41.352216)
		(width 0.1143)
		(layer "B.Cu")
		(net "CPU_ERR_N1")
	)
	(segment
		(start 79.33182 -42.5958)
		(end 80.329786 -41.597834)
		(width 0.1143)
		(layer "B.Cu")
		(net "CPU_ERR_N1")
	)
	(segment
		(start 80.575404 -41.352216)
		(end 80.329786 -41.597834)
		(width 0.1143)
		(layer "B.Cu")
		(net "CPU_ERR_N1")
	)
	(segment
		(start 106.593894 -8.326628)
		(end 107.833922 -7.0866)
		(width 0.0889)
		(layer "In2.Cu")
		(net "CPU_ERR_N1")
	)
	(segment
		(start 81.204816 -41.352216)
		(end 81.897982 -40.65905)
		(width 0.0889)
		(layer "In2.Cu")
		(net "CPU_ERR_N1")
	)
	(segment
		(start 86.301834 -39.900098)
		(end 86.565486 -40.16375)
		(width 0.0889)
		(layer "In2.Cu")
		(net "CPU_ERR_N1")
	)
	(segment
		(start 90.306906 -15.5321)
		(end 92.8624 -12.976606)
		(width 0.0889)
		(layer "In2.Cu")
		(net "CPU_ERR_N1")
	)
	(segment
		(start 86.59495 -23.19655)
		(end 84.75345 -21.35505)
		(width 0.0889)
		(layer "In2.Cu")
		(net "CPU_ERR_N1")
	)
	(segment
		(start 84.9503 -40.351964)
		(end 84.9503 -40.13454)
		(width 0.0889)
		(layer "In2.Cu")
		(net "CPU_ERR_N1")
	)
	(segment
		(start 81.897982 -40.65905)
		(end 84.643214 -40.65905)
		(width 0.0889)
		(layer "In2.Cu")
		(net "CPU_ERR_N1")
	)
	(segment
		(start 84.75345 -17.229328)
		(end 86.450678 -15.5321)
		(width 0.0889)
		(layer "In2.Cu")
		(net "CPU_ERR_N1")
	)
	(segment
		(start 84.9503 -40.13454)
		(end 85.184742 -39.900098)
		(width 0.0889)
		(layer "In2.Cu")
		(net "CPU_ERR_N1")
	)
	(segment
		(start 87.76081 -39.949374)
		(end 87.76081 -39.268908)
		(width 0.0889)
		(layer "In2.Cu")
		(net "CPU_ERR_N1")
	)
	(segment
		(start 87.64778 -28.313126)
		(end 86.59495 -27.260296)
		(width 0.0889)
		(layer "In2.Cu")
		(net "CPU_ERR_N1")
	)
	(segment
		(start 92.8624 -12.976606)
		(end 104.942894 -12.976606)
		(width 0.0889)
		(layer "In2.Cu")
		(net "CPU_ERR_N1")
	)
	(segment
		(start 106.593894 -11.325606)
		(end 106.593894 -8.326628)
		(width 0.0889)
		(layer "In2.Cu")
		(net "CPU_ERR_N1")
	)
	(segment
		(start 86.450678 -15.5321)
		(end 90.306906 -15.5321)
		(width 0.0889)
		(layer "In2.Cu")
		(net "CPU_ERR_N1")
	)
	(segment
		(start 84.643214 -40.65905)
		(end 84.9503 -40.351964)
		(width 0.0889)
		(layer "In2.Cu")
		(net "CPU_ERR_N1")
	)
	(segment
		(start 85.184742 -39.900098)
		(end 86.301834 -39.900098)
		(width 0.0889)
		(layer "In2.Cu")
		(net "CPU_ERR_N1")
	)
	(segment
		(start 86.565486 -40.16375)
		(end 87.546434 -40.16375)
		(width 0.0889)
		(layer "In2.Cu")
		(net "CPU_ERR_N1")
	)
	(segment
		(start 88.942672 -38.087046)
		(end 88.942672 -36.260532)
		(width 0.0889)
		(layer "In2.Cu")
		(net "CPU_ERR_N1")
	)
	(segment
		(start 86.59495 -27.260296)
		(end 86.59495 -23.19655)
		(width 0.0889)
		(layer "In2.Cu")
		(net "CPU_ERR_N1")
	)
	(segment
		(start 104.942894 -12.976606)
		(end 106.593894 -11.325606)
		(width 0.0889)
		(layer "In2.Cu")
		(net "CPU_ERR_N1")
	)
	(segment
		(start 87.76081 -39.268908)
		(end 88.942672 -38.087046)
		(width 0.0889)
		(layer "In2.Cu")
		(net "CPU_ERR_N1")
	)
	(segment
		(start 87.64778 -34.96564)
		(end 87.64778 -28.313126)
		(width 0.0889)
		(layer "In2.Cu")
		(net "CPU_ERR_N1")
	)
	(segment
		(start 87.546434 -40.16375)
		(end 87.76081 -39.949374)
		(width 0.0889)
		(layer "In2.Cu")
		(net "CPU_ERR_N1")
	)
	(segment
		(start 84.75345 -21.35505)
		(end 84.75345 -17.229328)
		(width 0.0889)
		(layer "In2.Cu")
		(net "CPU_ERR_N1")
	)
	(segment
		(start 88.942672 -36.260532)
		(end 87.64778 -34.96564)
		(width 0.0889)
		(layer "In2.Cu")
		(net "CPU_ERR_N1")
	)
	(segment
		(start 97.409 -40.357552)
		(end 97.409 -40.386)
		(width 0.127)
		(layer "F.Cu")
		(net "VCCRAMCPUSI0GT_MOD3_1P03")
	)
	(segment
		(start 97.048828 -40.000174)
		(end 97.051622 -40.000174)
		(width 0.127)
		(layer "F.Cu")
		(net "VCCRAMCPUSI0GT_MOD3_1P03")
	)
	(segment
		(start 97.051622 -40.000174)
		(end 97.409 -40.357552)
		(width 0.127)
		(layer "F.Cu")
		(net "VCCRAMCPUSI0GT_MOD3_1P03")
	)
	(via
		(at 97.409 -40.386)
		(size 0.4318)
		(drill 0.2032)
		(layers "F.Cu" "B.Cu")
		(net "VCCRAMCPUSI0GT_MOD3_1P03")
	)
	(segment
		(start 97.6376 -40.1574)
		(end 97.409 -40.386)
		(width 0.127)
		(layer "B.Cu")
		(net "VCCRAMCPUSI0GT_MOD3_1P03")
	)
	(segment
		(start 97.6376 -39.7256)
		(end 97.6376 -40.1574)
		(width 0.127)
		(layer "B.Cu")
		(net "VCCRAMCPUSI0GT_MOD3_1P03")
	)
	(segment
		(start 32.893 -64.135)
		(end 33.772094 -64.135)
		(width 0.4064)
		(layer "F.Cu")
		(net "VR_PVNN_GH_R")
	)
	(segment
		(start 25.5778 -66.7512)
		(end 25.2984 -66.4718)
		(width 0.508)
		(layer "F.Cu")
		(net "VR_PVNN_GH_R")
	)
	(segment
		(start 25.5778 -66.7766)
		(end 25.5778 -66.7512)
		(width 0.508)
		(layer "F.Cu")
		(net "VR_PVNN_GH_R")
	)
	(segment
		(start 24.638 -66.4718)
		(end 25.25268 -65.85712)
		(width 0.508)
		(layer "F.Cu")
		(net "VR_PVNN_GH_R")
	)
	(segment
		(start 25.25268 -65.85712)
		(end 25.25268 -65.532)
		(width 0.508)
		(layer "F.Cu")
		(net "VR_PVNN_GH_R")
	)
	(segment
		(start 25.2984 -66.4718)
		(end 24.638 -66.4718)
		(width 0.508)
		(layer "F.Cu")
		(net "VR_PVNN_GH_R")
	)
	(via
		(at 32.893 -64.135)
		(size 0.7112)
		(drill 0.4064)
		(layers "F.Cu" "B.Cu")
		(net "VR_PVNN_GH_R")
	)
	(via
		(at 32.893 -64.9732)
		(size 0.7112)
		(drill 0.3556)
		(layers "F.Cu" "B.Cu")
		(net "VR_PVNN_GH_R")
	)
	(via
		(at 25.5778 -66.7766)
		(size 0.7112)
		(drill 0.4064)
		(layers "F.Cu" "B.Cu")
		(net "VR_PVNN_GH_R")
	)
	(segment
		(start 32.893 -64.135)
		(end 32.893 -64.9732)
		(width 0.508)
		(layer "B.Cu")
		(net "VR_PVNN_GH_R")
	)
	(segment
		(start 32.213804 -69.7738)
		(end 33.577784 -68.40982)
		(width 0.508)
		(layer "In2.Cu")
		(net "VR_PVNN_GH_R")
	)
	(segment
		(start 25.5778 -66.929)
		(end 28.4226 -69.7738)
		(width 0.508)
		(layer "In2.Cu")
		(net "VR_PVNN_GH_R")
	)
	(segment
		(start 33.577784 -68.40982)
		(end 33.577784 -64.819784)
		(width 0.508)
		(layer "In2.Cu")
		(net "VR_PVNN_GH_R")
	)
	(segment
		(start 28.4226 -69.7738)
		(end 32.213804 -69.7738)
		(width 0.508)
		(layer "In2.Cu")
		(net "VR_PVNN_GH_R")
	)
	(segment
		(start 33.577784 -64.819784)
		(end 32.893 -64.135)
		(width 0.508)
		(layer "In2.Cu")
		(net "VR_PVNN_GH_R")
	)
	(segment
		(start 25.5778 -66.7766)
		(end 25.5778 -66.929)
		(width 0.508)
		(layer "In2.Cu")
		(net "VR_PVNN_GH_R")
	)
	(segment
		(start 97.851468 -43.200574)
		(end 97.9932 -43.342306)
		(width 0.254)
		(layer "F.Cu")
		(net "VCCCLKDDR0")
	)
	(segment
		(start 97.851468 -44.000674)
		(end 98.1964 -44.345606)
		(width 0.254)
		(layer "F.Cu")
		(net "VCCCLKDDR0")
	)
	(segment
		(start 98.1964 -44.345606)
		(end 98.1964 -44.4246)
		(width 0.254)
		(layer "F.Cu")
		(net "VCCCLKDDR0")
	)
	(segment
		(start 97.9932 -43.342306)
		(end 97.9932 -43.858942)
		(width 0.254)
		(layer "F.Cu")
		(net "VCCCLKDDR0")
	)
	(segment
		(start 97.9932 -43.858942)
		(end 97.851468 -44.000674)
		(width 0.254)
		(layer "F.Cu")
		(net "VCCCLKDDR0")
	)
	(via
		(at 98.3996 -46.9138)
		(size 0.7112)
		(drill 0.3556)
		(layers "F.Cu" "B.Cu")
		(net "VCCCLKDDR0")
	)
	(via
		(at 98.1964 -44.4246)
		(size 0.4318)
		(drill 0.2032)
		(layers "F.Cu" "B.Cu")
		(net "VCCCLKDDR0")
	)
	(segment
		(start 97.3074 -51.5366)
		(end 97.917 -50.927)
		(width 0.3048)
		(layer "B.Cu")
		(net "VCCCLKDDR0")
	)
	(segment
		(start 97.917 -50.927)
		(end 97.917 -50.9016)
		(width 0.3048)
		(layer "B.Cu")
		(net "VCCCLKDDR0")
	)
	(segment
		(start 97.917 -50.9016)
		(end 98.179636 -50.638964)
		(width 0.3048)
		(layer "B.Cu")
		(net "VCCCLKDDR0")
	)
	(segment
		(start 99.06 -43.6372)
		(end 98.9838 -43.6372)
		(width 0.3048)
		(layer "B.Cu")
		(net "VCCCLKDDR0")
	)
	(segment
		(start 98.3996 -46.9138)
		(end 98.5266 -46.7868)
		(width 0.3048)
		(layer "B.Cu")
		(net "VCCCLKDDR0")
	)
	(segment
		(start 98.9838 -43.6372)
		(end 98.1964 -44.4246)
		(width 0.3048)
		(layer "B.Cu")
		(net "VCCCLKDDR0")
	)
	(segment
		(start 98.3996 -47.841662)
		(end 98.3996 -46.9138)
		(width 0.3048)
		(layer "B.Cu")
		(net "VCCCLKDDR0")
	)
	(segment
		(start 96.901 -51.5366)
		(end 97.3074 -51.5366)
		(width 0.3048)
		(layer "B.Cu")
		(net "VCCCLKDDR0")
	)
	(segment
		(start 98.5266 -44.7548)
		(end 98.5266 -45.2882)
		(width 0.3048)
		(layer "B.Cu")
		(net "VCCCLKDDR0")
	)
	(segment
		(start 98.1964 -44.4246)
		(end 98.5266 -44.7548)
		(width 0.3048)
		(layer "B.Cu")
		(net "VCCCLKDDR0")
	)
	(segment
		(start 98.179636 -50.638964)
		(end 98.179636 -48.061626)
		(width 0.3048)
		(layer "B.Cu")
		(net "VCCCLKDDR0")
	)
	(segment
		(start 98.179636 -48.061626)
		(end 98.3996 -47.841662)
		(width 0.3048)
		(layer "B.Cu")
		(net "VCCCLKDDR0")
	)
	(segment
		(start 98.5266 -46.7868)
		(end 98.5266 -45.2882)
		(width 0.3048)
		(layer "B.Cu")
		(net "VCCCLKDDR0")
	)
	(segment
		(start 94.333568 -33.045654)
		(end 94.696534 -32.682688)
		(width 0.127)
		(layer "F.Cu")
		(net "TP_CPU_RSVD14")
	)
	(segment
		(start 94.696534 -32.682688)
		(end 94.696534 -31.909512)
		(width 0.127)
		(layer "F.Cu")
		(net "TP_CPU_RSVD14")
	)
	(via
		(at 94.696534 -31.909512)
		(size 0.4318)
		(drill 0.2032)
		(layers "F.Cu" "B.Cu")
		(net "TP_CPU_RSVD14")
	)
	(segment
		(start 95.221044 -31.385002)
		(end 94.696534 -31.909512)
		(width 0.127)
		(layer "B.Cu")
		(net "TP_CPU_RSVD14")
	)
	(segment
		(start 95.25 -31.385002)
		(end 95.221044 -31.385002)
		(width 0.127)
		(layer "B.Cu")
		(net "TP_CPU_RSVD14")
	)
	(segment
		(start 178.970686 -39.753286)
		(end 178.970686 -23.885144)
		(width 0.1778)
		(layer "F.Cu")
		(net "DDR3_M_B_VREF_DQ0")
	)
	(segment
		(start 179.21732 -39.99992)
		(end 178.970686 -39.753286)
		(width 0.1778)
		(layer "F.Cu")
		(net "DDR3_M_B_VREF_DQ0")
	)
	(segment
		(start 178.970686 -23.885144)
		(end 179.10683 -23.749)
		(width 0.1778)
		(layer "F.Cu")
		(net "DDR3_M_B_VREF_DQ0")
	)
	(segment
		(start 184.6072 -43.688)
		(end 184.5056 -43.5864)
		(width 0.1778)
		(layer "F.Cu")
		(net "DDR3_M_B_VREF_DQ0")
	)
	(segment
		(start 184.5056 -43.5864)
		(end 182.8038 -43.5864)
		(width 0.1778)
		(layer "F.Cu")
		(net "DDR3_M_B_VREF_DQ0")
	)
	(segment
		(start 182.8038 -43.5864)
		(end 179.21732 -39.99992)
		(width 0.1778)
		(layer "F.Cu")
		(net "DDR3_M_B_VREF_DQ0")
	)
	(via
		(at 179.21732 -39.99992)
		(size 0.7112)
		(drill 0.3556)
		(layers "F.Cu" "B.Cu")
		(net "DDR3_M_B_VREF_DQ0")
	)
	(via
		(at 179.10683 -23.749)
		(size 0.508)
		(drill 0.254)
		(layers "F.Cu" "B.Cu")
		(net "DDR3_M_B_VREF_DQ0")
	)
	(segment
		(start 129.4638 -12.828778)
		(end 129.4638 -12.015978)
		(width 0.1778)
		(layer "B.Cu")
		(net "DDR3_M_B_VREF_DQ0")
	)
	(segment
		(start 129.4638 -13.311378)
		(end 129.4638 -12.828778)
		(width 0.1778)
		(layer "B.Cu")
		(net "DDR3_M_B_VREF_DQ0")
	)
	(segment
		(start 129.4638 -12.015978)
		(end 129.2606 -11.812778)
		(width 0.1778)
		(layer "B.Cu")
		(net "DDR3_M_B_VREF_DQ0")
	)
	(segment
		(start 128.35001 -10.902188)
		(end 129.2606 -11.812778)
		(width 0.1778)
		(layer "B.Cu")
		(net "DDR3_M_B_VREF_DQ0")
	)
	(segment
		(start 179.10683 -20.112228)
		(end 174.61738 -15.622778)
		(width 0.1778)
		(layer "B.Cu")
		(net "DDR3_M_B_VREF_DQ0")
	)
	(segment
		(start 145.5039 -13.552678)
		(end 129.7051 -13.552678)
		(width 0.1778)
		(layer "B.Cu")
		(net "DDR3_M_B_VREF_DQ0")
	)
	(segment
		(start 147.574 -15.622778)
		(end 145.5039 -13.552678)
		(width 0.1778)
		(layer "B.Cu")
		(net "DDR3_M_B_VREF_DQ0")
	)
	(segment
		(start 129.7051 -13.552678)
		(end 129.4638 -13.311378)
		(width 0.1778)
		(layer "B.Cu")
		(net "DDR3_M_B_VREF_DQ0")
	)
	(segment
		(start 128.35001 -9.89076)
		(end 128.35001 -10.902188)
		(width 0.1778)
		(layer "B.Cu")
		(net "DDR3_M_B_VREF_DQ0")
	)
	(segment
		(start 179.10683 -23.749)
		(end 179.10683 -20.112228)
		(width 0.1778)
		(layer "B.Cu")
		(net "DDR3_M_B_VREF_DQ0")
	)
	(segment
		(start 174.61738 -15.622778)
		(end 147.574 -15.622778)
		(width 0.1778)
		(layer "B.Cu")
		(net "DDR3_M_B_VREF_DQ0")
	)
	(segment
		(start 20.463002 -61.292994)
		(end 20.463002 -61.893704)
		(width 0.2032)
		(layer "F.Cu")
		(net "VR_PVNN_RTN")
	)
	(segment
		(start 20.463002 -61.893704)
		(end 20.066 -62.290706)
		(width 0.2032)
		(layer "F.Cu")
		(net "VR_PVNN_RTN")
	)
	(segment
		(start 20.5232 -63.4492)
		(end 20.5232 -63.1698)
		(width 0.2032)
		(layer "F.Cu")
		(net "VR_PVNN_RTN")
	)
	(segment
		(start 20.5232 -63.1698)
		(end 20.066 -62.7126)
		(width 0.2032)
		(layer "F.Cu")
		(net "VR_PVNN_RTN")
	)
	(segment
		(start 20.066 -62.290706)
		(end 20.066 -62.7126)
		(width 0.2032)
		(layer "F.Cu")
		(net "VR_PVNN_RTN")
	)
	(via
		(at 20.5486 -63.5254)
		(size 0.7112)
		(drill 0.3556)
		(layers "F.Cu" "B.Cu")
		(net "VR_PVNN_RTN")
	)
	(via
		(at 20.066 -62.7126)
		(size 0.508)
		(drill 0.254)
		(layers "F.Cu" "B.Cu")
		(net "VR_PVNN_RTN")
	)
	(segment
		(start 20.5486 -63.7286)
		(end 20.5486 -63.5254)
		(width 0.2032)
		(layer "B.Cu")
		(net "VR_PVNN_RTN")
	)
	(segment
		(start 20.5486 -63.1952)
		(end 20.066 -62.7126)
		(width 0.2032)
		(layer "B.Cu")
		(net "VR_PVNN_RTN")
	)
	(segment
		(start 20.066 -62.7126)
		(end 20.6502 -62.1284)
		(width 0.2032)
		(layer "B.Cu")
		(net "VR_PVNN_RTN")
	)
	(segment
		(start 20.5486 -63.5254)
		(end 20.5486 -63.1952)
		(width 0.2032)
		(layer "B.Cu")
		(net "VR_PVNN_RTN")
	)
	(segment
		(start 20.6502 -62.1284)
		(end 21.0566 -62.1284)
		(width 0.2032)
		(layer "B.Cu")
		(net "VR_PVNN_RTN")
	)
	(segment
		(start 19.939 -64.3382)
		(end 20.5486 -63.7286)
		(width 0.2032)
		(layer "B.Cu")
		(net "VR_PVNN_RTN")
	)
	(segment
		(start 21.0566 -62.1284)
		(end 21.6408 -61.5442)
		(width 0.2032)
		(layer "B.Cu")
		(net "VR_PVNN_RTN")
	)
	(segment
		(start 97.048828 -35.199574)
		(end 97.426018 -34.822384)
		(width 0.254)
		(layer "F.Cu")
		(net "VCCA_PLLDDR1_AVN")
	)
	(via
		(at 94.9452 -20.4724)
		(size 0.7112)
		(drill 0.3556)
		(layers "F.Cu" "B.Cu")
		(net "VCCA_PLLDDR1_AVN")
	)
	(via
		(at 97.426018 -34.822384)
		(size 0.4318)
		(drill 0.2032)
		(layers "F.Cu" "B.Cu")
		(net "VCCA_PLLDDR1_AVN")
	)
	(segment
		(start 95.5548 -19.685)
		(end 95.5548 -19.8628)
		(width 0.3048)
		(layer "B.Cu")
		(net "VCCA_PLLDDR1_AVN")
	)
	(segment
		(start 97.102422 -33.579562)
		(end 97.102422 -32.85109)
		(width 0.3048)
		(layer "B.Cu")
		(net "VCCA_PLLDDR1_AVN")
	)
	(segment
		(start 95.4913 -25.0571)
		(end 94.9452 -24.511)
		(width 0.3048)
		(layer "B.Cu")
		(net "VCCA_PLLDDR1_AVN")
	)
	(segment
		(start 96.4311 -32.3977)
		(end 96.4311 -30.342078)
		(width 0.3048)
		(layer "B.Cu")
		(net "VCCA_PLLDDR1_AVN")
	)
	(segment
		(start 96.4311 -30.342078)
		(end 95.4913 -29.402278)
		(width 0.3048)
		(layer "B.Cu")
		(net "VCCA_PLLDDR1_AVN")
	)
	(segment
		(start 95.5548 -18.7452)
		(end 95.4024 -18.5928)
		(width 0.508)
		(layer "B.Cu")
		(net "VCCA_PLLDDR1_AVN")
	)
	(segment
		(start 96.609408 -32.576008)
		(end 96.4311 -32.3977)
		(width 0.3048)
		(layer "B.Cu")
		(net "VCCA_PLLDDR1_AVN")
	)
	(segment
		(start 97.426018 -34.822384)
		(end 97.426018 -33.903158)
		(width 0.3048)
		(layer "B.Cu")
		(net "VCCA_PLLDDR1_AVN")
	)
	(segment
		(start 97.102422 -32.85109)
		(end 96.82734 -32.576008)
		(width 0.3048)
		(layer "B.Cu")
		(net "VCCA_PLLDDR1_AVN")
	)
	(segment
		(start 95.5548 -19.685)
		(end 95.5548 -18.7452)
		(width 0.508)
		(layer "B.Cu")
		(net "VCCA_PLLDDR1_AVN")
	)
	(segment
		(start 95.4913 -29.402278)
		(end 95.4913 -25.0571)
		(width 0.3048)
		(layer "B.Cu")
		(net "VCCA_PLLDDR1_AVN")
	)
	(segment
		(start 95.5548 -19.8628)
		(end 94.9452 -20.4724)
		(width 0.3048)
		(layer "B.Cu")
		(net "VCCA_PLLDDR1_AVN")
	)
	(segment
		(start 96.82734 -32.576008)
		(end 96.609408 -32.576008)
		(width 0.3048)
		(layer "B.Cu")
		(net "VCCA_PLLDDR1_AVN")
	)
	(segment
		(start 94.9452 -24.511)
		(end 94.9452 -20.4724)
		(width 0.3048)
		(layer "B.Cu")
		(net "VCCA_PLLDDR1_AVN")
	)
	(segment
		(start 97.426018 -33.903158)
		(end 97.102422 -33.579562)
		(width 0.3048)
		(layer "B.Cu")
		(net "VCCA_PLLDDR1_AVN")
	)
	(segment
		(start 22.733 -65.6082)
		(end 22.733 -66.3448)
		(width 0.2032)
		(layer "F.Cu")
		(net "VR_PVNN_ISUMN_RC")
	)
	(segment
		(start 22.8092 -66.421)
		(end 22.8092 -66.9798)
		(width 0.2032)
		(layer "F.Cu")
		(net "VR_PVNN_ISUMN_RC")
	)
	(segment
		(start 22.8092 -66.9798)
		(end 22.479 -67.31)
		(width 0.2032)
		(layer "F.Cu")
		(net "VR_PVNN_ISUMN_RC")
	)
	(segment
		(start 22.733 -66.3448)
		(end 22.8092 -66.421)
		(width 0.2032)
		(layer "F.Cu")
		(net "VR_PVNN_ISUMN_RC")
	)
	(via
		(at 22.479 -67.31)
		(size 0.7112)
		(drill 0.3556)
		(layers "F.Cu" "B.Cu")
		(net "VR_PVNN_ISUMN_RC")
	)
	(segment
		(start 111.491268 -32.085534)
		(end 112.33023 -32.085534)
		(width 0.1778)
		(layer "F.Cu")
		(net "M_B_ODT1")
	)
	(segment
		(start 112.33023 -32.085534)
		(end 112.837468 -31.578296)
		(width 0.1778)
		(layer "F.Cu")
		(net "M_B_ODT1")
	)
	(via
		(at 168.196768 -3.777996)
		(size 0.4318)
		(drill 0.2032)
		(layers "F.Cu" "B.Cu")
		(net "M_B_ODT1")
	)
	(via
		(at 112.837468 -31.578296)
		(size 0.4318)
		(drill 0.2032)
		(layers "F.Cu" "B.Cu")
		(net "M_B_ODT1")
	)
	(segment
		(start 168.694354 -2.941828)
		(end 168.694354 -3.316224)
		(width 0.1778)
		(layer "B.Cu")
		(net "M_B_ODT1")
	)
	(segment
		(start 168.232582 -3.777996)
		(end 168.196768 -3.777996)
		(width 0.1778)
		(layer "B.Cu")
		(net "M_B_ODT1")
	)
	(segment
		(start 168.694354 -3.316224)
		(end 168.232582 -3.777996)
		(width 0.1778)
		(layer "B.Cu")
		(net "M_B_ODT1")
	)
	(segment
		(start 168.850056 -1.690624)
		(end 168.850056 -2.786126)
		(width 0.1778)
		(layer "B.Cu")
		(net "M_B_ODT1")
	)
	(segment
		(start 168.850056 -2.786126)
		(end 168.694354 -2.941828)
		(width 0.1778)
		(layer "B.Cu")
		(net "M_B_ODT1")
	)
	(segment
		(start 168.2242 -3.805428)
		(end 168.2242 -4.331462)
		(width 0.1524)
		(layer "In9.Cu")
		(net "M_B_ODT1")
	)
	(segment
		(start 169.2402 -5.056378)
		(end 169.2402 -7.00786)
		(width 0.1524)
		(layer "In9.Cu")
		(net "M_B_ODT1")
	)
	(segment
		(start 162.4838 -22.325076)
		(end 156.259276 -28.5496)
		(width 0.1524)
		(layer "In9.Cu")
		(net "M_B_ODT1")
	)
	(segment
		(start 168.773856 -4.590034)
		(end 169.2402 -5.056378)
		(width 0.1524)
		(layer "In9.Cu")
		(net "M_B_ODT1")
	)
	(segment
		(start 162.4838 -21.0058)
		(end 162.4838 -22.325076)
		(width 0.1524)
		(layer "In9.Cu")
		(net "M_B_ODT1")
	)
	(segment
		(start 162.6743 -20.8153)
		(end 162.4838 -21.0058)
		(width 0.1524)
		(layer "In9.Cu")
		(net "M_B_ODT1")
	)
	(segment
		(start 115.5192 -28.5496)
		(end 112.837468 -31.231332)
		(width 0.1524)
		(layer "In9.Cu")
		(net "M_B_ODT1")
	)
	(segment
		(start 168.196768 -3.777996)
		(end 168.2242 -3.805428)
		(width 0.1524)
		(layer "In9.Cu")
		(net "M_B_ODT1")
	)
	(segment
		(start 171.170854 -11.431778)
		(end 171.755054 -12.015978)
		(width 0.1524)
		(layer "In9.Cu")
		(net "M_B_ODT1")
	)
	(segment
		(start 170.340274 -11.431778)
		(end 171.170854 -11.431778)
		(width 0.1524)
		(layer "In9.Cu")
		(net "M_B_ODT1")
	)
	(segment
		(start 171.755054 -14.812518)
		(end 165.752272 -20.8153)
		(width 0.1524)
		(layer "In9.Cu")
		(net "M_B_ODT1")
	)
	(segment
		(start 169.501312 -7.268972)
		(end 169.501312 -10.592816)
		(width 0.1524)
		(layer "In9.Cu")
		(net "M_B_ODT1")
	)
	(segment
		(start 156.259276 -28.5496)
		(end 115.5192 -28.5496)
		(width 0.1524)
		(layer "In9.Cu")
		(net "M_B_ODT1")
	)
	(segment
		(start 168.2242 -4.331462)
		(end 168.482772 -4.590034)
		(width 0.1524)
		(layer "In9.Cu")
		(net "M_B_ODT1")
	)
	(segment
		(start 169.501312 -10.592816)
		(end 170.340274 -11.431778)
		(width 0.1524)
		(layer "In9.Cu")
		(net "M_B_ODT1")
	)
	(segment
		(start 112.837468 -31.231332)
		(end 112.837468 -31.578296)
		(width 0.1524)
		(layer "In9.Cu")
		(net "M_B_ODT1")
	)
	(segment
		(start 165.752272 -20.8153)
		(end 162.6743 -20.8153)
		(width 0.1524)
		(layer "In9.Cu")
		(net "M_B_ODT1")
	)
	(segment
		(start 168.482772 -4.590034)
		(end 168.773856 -4.590034)
		(width 0.1524)
		(layer "In9.Cu")
		(net "M_B_ODT1")
	)
	(segment
		(start 169.2402 -7.00786)
		(end 169.501312 -7.268972)
		(width 0.1524)
		(layer "In9.Cu")
		(net "M_B_ODT1")
	)
	(segment
		(start 171.755054 -12.015978)
		(end 171.755054 -14.812518)
		(width 0.1524)
		(layer "In9.Cu")
		(net "M_B_ODT1")
	)
	(segment
		(start 95.448628 -38.399974)
		(end 95.0468 -37.998146)
		(width 0.1143)
		(layer "F.Cu")
		(net "VSSRAMCPUSI1_SENSE")
	)
	(segment
		(start 95.0468 -37.998146)
		(end 95.0468 -37.971476)
		(width 0.1143)
		(layer "F.Cu")
		(net "VSSRAMCPUSI1_SENSE")
	)
	(via
		(at 94.615 -38.5318)
		(size 0.7112)
		(drill 0.3556)
		(layers "F.Cu" "B.Cu")
		(net "VSSRAMCPUSI1_SENSE")
	)
	(via
		(at 95.0468 -37.971476)
		(size 0.4318)
		(drill 0.2032)
		(layers "F.Cu" "B.Cu")
		(net "VSSRAMCPUSI1_SENSE")
	)
	(segment
		(start 95.8596 -37.2618)
		(end 95.885 -37.2618)
		(width 0.1143)
		(layer "B.Cu")
		(net "VSSRAMCPUSI1_SENSE")
	)
	(segment
		(start 94.615 -38.5318)
		(end 94.615 -38.403276)
		(width 0.1143)
		(layer "B.Cu")
		(net "VSSRAMCPUSI1_SENSE")
	)
	(segment
		(start 95.0468 -37.971476)
		(end 95.149924 -37.971476)
		(width 0.1143)
		(layer "B.Cu")
		(net "VSSRAMCPUSI1_SENSE")
	)
	(segment
		(start 95.149924 -37.971476)
		(end 95.8596 -37.2618)
		(width 0.1143)
		(layer "B.Cu")
		(net "VSSRAMCPUSI1_SENSE")
	)
	(segment
		(start 94.615 -38.403276)
		(end 95.0468 -37.971476)
		(width 0.1143)
		(layer "B.Cu")
		(net "VSSRAMCPUSI1_SENSE")
	)
	(segment
		(start 76.270104 -41.17086)
		(end 76.48702 -41.17086)
		(width 0.1143)
		(layer "F.Cu")
		(net "CPU_ERR_N2")
	)
	(segment
		(start 79.764636 -40.821864)
		(end 78.97114 -40.821864)
		(width 0.1143)
		(layer "F.Cu")
		(net "CPU_ERR_N2")
	)
	(segment
		(start 74.5998 -42.418)
		(end 75.438 -42.418)
		(width 0.1143)
		(layer "F.Cu")
		(net "CPU_ERR_N2")
	)
	(segment
		(start 118.439946 -22.025864)
		(end 118.439946 -16.111982)
		(width 0.1143)
		(layer "F.Cu")
		(net "CPU_ERR_N2")
	)
	(segment
		(start 76.48702 -41.17086)
		(end 77.74559 -39.91229)
		(width 0.1143)
		(layer "F.Cu")
		(net "CPU_ERR_N2")
	)
	(segment
		(start 128.480312 -29.29382)
		(end 125.831092 -26.6446)
		(width 0.1143)
		(layer "F.Cu")
		(net "CPU_ERR_N2")
	)
	(segment
		(start 75.946 -41.91)
		(end 75.946 -41.494964)
		(width 0.1143)
		(layer "F.Cu")
		(net "CPU_ERR_N2")
	)
	(segment
		(start 78.97114 -40.821864)
		(end 78.486 -40.336724)
		(width 0.1143)
		(layer "F.Cu")
		(net "CPU_ERR_N2")
	)
	(segment
		(start 78.056232 -39.91229)
		(end 78.480666 -40.336724)
		(width 0.1143)
		(layer "F.Cu")
		(net "CPU_ERR_N2")
	)
	(segment
		(start 77.74559 -39.91229)
		(end 78.056232 -39.91229)
		(width 0.1143)
		(layer "F.Cu")
		(net "CPU_ERR_N2")
	)
	(segment
		(start 123.058682 -26.6446)
		(end 118.439946 -22.025864)
		(width 0.1143)
		(layer "F.Cu")
		(net "CPU_ERR_N2")
	)
	(segment
		(start 132.1308 -29.29382)
		(end 128.480312 -29.29382)
		(width 0.1143)
		(layer "F.Cu")
		(net "CPU_ERR_N2")
	)
	(segment
		(start 80.3402 -40.572944)
		(end 80.013556 -40.572944)
		(width 0.1143)
		(layer "F.Cu")
		(net "CPU_ERR_N2")
	)
	(segment
		(start 78.480666 -40.336724)
		(end 78.486 -40.336724)
		(width 0.1143)
		(layer "F.Cu")
		(net "CPU_ERR_N2")
	)
	(segment
		(start 75.946 -41.494964)
		(end 76.270104 -41.17086)
		(width 0.1143)
		(layer "F.Cu")
		(net "CPU_ERR_N2")
	)
	(segment
		(start 112.04575 -9.717786)
		(end 110.261654 -9.717786)
		(width 0.1143)
		(layer "F.Cu")
		(net "CPU_ERR_N2")
	)
	(segment
		(start 80.013556 -40.572944)
		(end 79.764636 -40.821864)
		(width 0.1143)
		(layer "F.Cu")
		(net "CPU_ERR_N2")
	)
	(segment
		(start 80.950308 -40.917114)
		(end 80.68437 -40.917114)
		(width 0.1143)
		(layer "F.Cu")
		(net "CPU_ERR_N2")
	)
	(segment
		(start 118.439946 -16.111982)
		(end 112.04575 -9.717786)
		(width 0.1143)
		(layer "F.Cu")
		(net "CPU_ERR_N2")
	)
	(segment
		(start 125.831092 -26.6446)
		(end 123.058682 -26.6446)
		(width 0.1143)
		(layer "F.Cu")
		(net "CPU_ERR_N2")
	)
	(segment
		(start 80.68437 -40.917114)
		(end 80.3402 -40.572944)
		(width 0.1143)
		(layer "F.Cu")
		(net "CPU_ERR_N2")
	)
	(segment
		(start 110.261654 -9.717786)
		(end 109.22 -8.676132)
		(width 0.1143)
		(layer "F.Cu")
		(net "CPU_ERR_N2")
	)
	(segment
		(start 75.438 -42.418)
		(end 75.946 -41.91)
		(width 0.1143)
		(layer "F.Cu")
		(net "CPU_ERR_N2")
	)
	(via
		(at 109.22 -8.676132)
		(size 0.508)
		(drill 0.254)
		(layers "F.Cu" "B.Cu")
		(net "CPU_ERR_N2")
	)
	(via
		(at 76.270104 -41.17086)
		(size 0.7112)
		(drill 0.3556)
		(layers "F.Cu" "B.Cu")
		(net "CPU_ERR_N2")
	)
	(via
		(at 78.486 -40.336724)
		(size 0.4318)
		(drill 0.2032)
		(layers "F.Cu" "B.Cu")
		(net "CPU_ERR_N2")
	)
	(segment
		(start 109.27715 -12.092178)
		(end 105.954322 -15.415006)
		(width 0.0889)
		(layer "In9.Cu")
		(net "CPU_ERR_N2")
	)
	(segment
		(start 95.202248 -15.01775)
		(end 84.807806 -15.01775)
		(width 0.0889)
		(layer "In9.Cu")
		(net "CPU_ERR_N2")
	)
	(segment
		(start 84.807806 -15.01775)
		(end 81.446878 -18.378678)
		(width 0.0889)
		(layer "In9.Cu")
		(net "CPU_ERR_N2")
	)
	(segment
		(start 79.461868 -38.775386)
		(end 79.461868 -39.360856)
		(width 0.0889)
		(layer "In9.Cu")
		(net "CPU_ERR_N2")
	)
	(segment
		(start 77.47889 -25.626822)
		(end 77.47889 -28.293314)
		(width 0.0889)
		(layer "In9.Cu")
		(net "CPU_ERR_N2")
	)
	(segment
		(start 81.446878 -19.097244)
		(end 78.1812 -22.362922)
		(width 0.0889)
		(layer "In9.Cu")
		(net "CPU_ERR_N2")
	)
	(segment
		(start 76.891896 -36.205414)
		(end 79.461868 -38.775386)
		(width 0.0889)
		(layer "In9.Cu")
		(net "CPU_ERR_N2")
	)
	(segment
		(start 95.599504 -15.415006)
		(end 95.202248 -15.01775)
		(width 0.0889)
		(layer "In9.Cu")
		(net "CPU_ERR_N2")
	)
	(segment
		(start 81.446878 -18.378678)
		(end 81.446878 -19.097244)
		(width 0.0889)
		(layer "In9.Cu")
		(net "CPU_ERR_N2")
	)
	(segment
		(start 77.47889 -28.293314)
		(end 76.891896 -28.880308)
		(width 0.0889)
		(layer "In9.Cu")
		(net "CPU_ERR_N2")
	)
	(segment
		(start 78.1812 -24.924512)
		(end 77.47889 -25.626822)
		(width 0.0889)
		(layer "In9.Cu")
		(net "CPU_ERR_N2")
	)
	(segment
		(start 79.461868 -39.360856)
		(end 78.486 -40.336724)
		(width 0.0889)
		(layer "In9.Cu")
		(net "CPU_ERR_N2")
	)
	(segment
		(start 76.891896 -28.880308)
		(end 76.891896 -36.205414)
		(width 0.0889)
		(layer "In9.Cu")
		(net "CPU_ERR_N2")
	)
	(segment
		(start 109.27715 -8.733282)
		(end 109.27715 -12.092178)
		(width 0.0889)
		(layer "In9.Cu")
		(net "CPU_ERR_N2")
	)
	(segment
		(start 105.954322 -15.415006)
		(end 95.599504 -15.415006)
		(width 0.0889)
		(layer "In9.Cu")
		(net "CPU_ERR_N2")
	)
	(segment
		(start 109.22 -8.676132)
		(end 109.27715 -8.733282)
		(width 0.0889)
		(layer "In9.Cu")
		(net "CPU_ERR_N2")
	)
	(segment
		(start 78.1812 -22.362922)
		(end 78.1812 -24.924512)
		(width 0.0889)
		(layer "In9.Cu")
		(net "CPU_ERR_N2")
	)
	(segment
		(start 100.7618 -32.512)
		(end 100.7618 -32.4612)
		(width 0.1016)
		(layer "F.Cu")
		(net "M_B_CKE1")
	)
	(segment
		(start 100.292408 -31.991808)
		(end 100.292408 -31.902654)
		(width 0.1016)
		(layer "F.Cu")
		(net "M_B_CKE1")
	)
	(segment
		(start 100.7618 -32.4612)
		(end 100.292408 -31.991808)
		(width 0.1016)
		(layer "F.Cu")
		(net "M_B_CKE1")
	)
	(via
		(at 157.2006 -8.45566)
		(size 0.4318)
		(drill 0.2032)
		(layers "F.Cu" "B.Cu")
		(net "M_B_CKE1")
	)
	(via
		(at 100.7618 -32.512)
		(size 0.4318)
		(drill 0.2032)
		(layers "F.Cu" "B.Cu")
		(net "M_B_CKE1")
	)
	(segment
		(start 157.150054 -9.89076)
		(end 157.150054 -8.561324)
		(width 0.1778)
		(layer "B.Cu")
		(net "M_B_CKE1")
	)
	(segment
		(start 157.150054 -8.561324)
		(end 157.2006 -8.510778)
		(width 0.1778)
		(layer "B.Cu")
		(net "M_B_CKE1")
	)
	(segment
		(start 157.2006 -8.510778)
		(end 157.2006 -8.45566)
		(width 0.1778)
		(layer "B.Cu")
		(net "M_B_CKE1")
	)
	(segment
		(start 128.1303 -16.0528)
		(end 127.8255 -16.0528)
		(width 0.1524)
		(layer "In9.Cu")
		(net "M_B_CKE1")
	)
	(segment
		(start 154.939238 -13.0556)
		(end 138.0998 -13.0556)
		(width 0.1524)
		(layer "In9.Cu")
		(net "M_B_CKE1")
	)
	(segment
		(start 100.7618 -32.4612)
		(end 100.3427 -32.0421)
		(width 0.1016)
		(layer "In9.Cu")
		(net "M_B_CKE1")
	)
	(segment
		(start 127.2159 -16.67129)
		(end 127.0635 -16.51889)
		(width 0.1524)
		(layer "In9.Cu")
		(net "M_B_CKE1")
	)
	(segment
		(start 128.8034 -16.67129)
		(end 128.4351 -16.67129)
		(width 0.1524)
		(layer "In9.Cu")
		(net "M_B_CKE1")
	)
	(segment
		(start 109.204506 -20.701)
		(end 103.3272 -20.701)
		(width 0.1524)
		(layer "In9.Cu")
		(net "M_B_CKE1")
	)
	(segment
		(start 128.2827 -16.2052)
		(end 128.1303 -16.0528)
		(width 0.1524)
		(layer "In9.Cu")
		(net "M_B_CKE1")
	)
	(segment
		(start 126.3015 -16.67129)
		(end 125.9967 -16.67129)
		(width 0.1524)
		(layer "In9.Cu")
		(net "M_B_CKE1")
	)
	(segment
		(start 125.2347 -16.51889)
		(end 125.0823 -16.67129)
		(width 0.1524)
		(layer "In9.Cu")
		(net "M_B_CKE1")
	)
	(segment
		(start 125.2347 -16.2052)
		(end 125.2347 -16.51889)
		(width 0.1524)
		(layer "In9.Cu")
		(net "M_B_CKE1")
	)
	(segment
		(start 102.437184 -26.061416)
		(end 102.565962 -26.061416)
		(width 0.1016)
		(layer "In9.Cu")
		(net "M_B_CKE1")
	)
	(segment
		(start 125.3871 -16.0528)
		(end 125.2347 -16.2052)
		(width 0.1524)
		(layer "In9.Cu")
		(net "M_B_CKE1")
	)
	(segment
		(start 157.2006 -8.45566)
		(end 157.2006 -10.794238)
		(width 0.1524)
		(layer "In9.Cu")
		(net "M_B_CKE1")
	)
	(segment
		(start 129.667 -16.51889)
		(end 129.667 -16.256)
		(width 0.1524)
		(layer "In9.Cu")
		(net "M_B_CKE1")
	)
	(segment
		(start 127.8255 -16.0528)
		(end 127.6731 -16.2052)
		(width 0.1524)
		(layer "In9.Cu")
		(net "M_B_CKE1")
	)
	(segment
		(start 99.416362 -29.082238)
		(end 102.437184 -26.061416)
		(width 0.1016)
		(layer "In9.Cu")
		(net "M_B_CKE1")
	)
	(segment
		(start 127.0635 -16.2052)
		(end 126.9111 -16.0528)
		(width 0.1524)
		(layer "In9.Cu")
		(net "M_B_CKE1")
	)
	(segment
		(start 126.9111 -16.0528)
		(end 126.6063 -16.0528)
		(width 0.1524)
		(layer "In9.Cu")
		(net "M_B_CKE1")
	)
	(segment
		(start 129.667 -16.256)
		(end 129.5146 -16.1036)
		(width 0.1524)
		(layer "In9.Cu")
		(net "M_B_CKE1")
	)
	(segment
		(start 103.3272 -20.701)
		(end 102.9716 -21.0566)
		(width 0.1524)
		(layer "In9.Cu")
		(net "M_B_CKE1")
	)
	(segment
		(start 128.4351 -16.67129)
		(end 128.2827 -16.51889)
		(width 0.1524)
		(layer "In9.Cu")
		(net "M_B_CKE1")
	)
	(segment
		(start 129.5146 -16.1036)
		(end 129.1082 -16.1036)
		(width 0.1524)
		(layer "In9.Cu")
		(net "M_B_CKE1")
	)
	(segment
		(start 127.6731 -16.2052)
		(end 127.6731 -16.51889)
		(width 0.1524)
		(layer "In9.Cu")
		(net "M_B_CKE1")
	)
	(segment
		(start 128.2827 -16.51889)
		(end 128.2827 -16.2052)
		(width 0.1524)
		(layer "In9.Cu")
		(net "M_B_CKE1")
	)
	(segment
		(start 136.99871 -16.67129)
		(end 129.8194 -16.67129)
		(width 0.1524)
		(layer "In9.Cu")
		(net "M_B_CKE1")
	)
	(segment
		(start 127.5207 -16.67129)
		(end 127.2159 -16.67129)
		(width 0.1524)
		(layer "In9.Cu")
		(net "M_B_CKE1")
	)
	(segment
		(start 127.6731 -16.51889)
		(end 127.5207 -16.67129)
		(width 0.1524)
		(layer "In9.Cu")
		(net "M_B_CKE1")
	)
	(segment
		(start 126.6063 -16.0528)
		(end 126.4539 -16.2052)
		(width 0.1524)
		(layer "In9.Cu")
		(net "M_B_CKE1")
	)
	(segment
		(start 99.48545 -31.669736)
		(end 99.416362 -31.2166)
		(width 0.1016)
		(layer "In9.Cu")
		(net "M_B_CKE1")
	)
	(segment
		(start 129.1082 -16.1036)
		(end 128.9558 -16.256)
		(width 0.1524)
		(layer "In9.Cu")
		(net "M_B_CKE1")
	)
	(segment
		(start 126.4539 -16.2052)
		(end 126.4539 -16.51889)
		(width 0.1524)
		(layer "In9.Cu")
		(net "M_B_CKE1")
	)
	(segment
		(start 124.4981 -16.67129)
		(end 124.3076 -16.48079)
		(width 0.1524)
		(layer "In9.Cu")
		(net "M_B_CKE1")
	)
	(segment
		(start 137.5918 -16.0782)
		(end 136.99871 -16.67129)
		(width 0.1524)
		(layer "In9.Cu")
		(net "M_B_CKE1")
	)
	(segment
		(start 129.8194 -16.67129)
		(end 129.667 -16.51889)
		(width 0.1524)
		(layer "In9.Cu")
		(net "M_B_CKE1")
	)
	(segment
		(start 125.8443 -16.2052)
		(end 125.6919 -16.0528)
		(width 0.1524)
		(layer "In9.Cu")
		(net "M_B_CKE1")
	)
	(segment
		(start 127.0635 -16.51889)
		(end 127.0635 -16.2052)
		(width 0.1524)
		(layer "In9.Cu")
		(net "M_B_CKE1")
	)
	(segment
		(start 128.9558 -16.256)
		(end 128.9558 -16.51889)
		(width 0.1524)
		(layer "In9.Cu")
		(net "M_B_CKE1")
	)
	(segment
		(start 138.0998 -13.0556)
		(end 137.5918 -13.5636)
		(width 0.1524)
		(layer "In9.Cu")
		(net "M_B_CKE1")
	)
	(segment
		(start 99.416362 -31.2166)
		(end 99.416362 -29.082238)
		(width 0.1016)
		(layer "In9.Cu")
		(net "M_B_CKE1")
	)
	(segment
		(start 102.9716 -25.655778)
		(end 102.565962 -26.061416)
		(width 0.1524)
		(layer "In9.Cu")
		(net "M_B_CKE1")
	)
	(segment
		(start 126.4539 -16.51889)
		(end 126.3015 -16.67129)
		(width 0.1524)
		(layer "In9.Cu")
		(net "M_B_CKE1")
	)
	(segment
		(start 124.3076 -16.48079)
		(end 124.3076 -16.2687)
		(width 0.1524)
		(layer "In9.Cu")
		(net "M_B_CKE1")
	)
	(segment
		(start 137.5918 -13.5636)
		(end 137.5918 -16.0782)
		(width 0.1524)
		(layer "In9.Cu")
		(net "M_B_CKE1")
	)
	(segment
		(start 102.9716 -21.0566)
		(end 102.9716 -25.655778)
		(width 0.1524)
		(layer "In9.Cu")
		(net "M_B_CKE1")
	)
	(segment
		(start 124.1171 -16.0782)
		(end 113.827306 -16.0782)
		(width 0.1524)
		(layer "In9.Cu")
		(net "M_B_CKE1")
	)
	(segment
		(start 100.7618 -32.512)
		(end 100.7618 -32.4612)
		(width 0.1016)
		(layer "In9.Cu")
		(net "M_B_CKE1")
	)
	(segment
		(start 125.0823 -16.67129)
		(end 124.4981 -16.67129)
		(width 0.1524)
		(layer "In9.Cu")
		(net "M_B_CKE1")
	)
	(segment
		(start 125.9967 -16.67129)
		(end 125.8443 -16.51889)
		(width 0.1524)
		(layer "In9.Cu")
		(net "M_B_CKE1")
	)
	(segment
		(start 125.6919 -16.0528)
		(end 125.3871 -16.0528)
		(width 0.1524)
		(layer "In9.Cu")
		(net "M_B_CKE1")
	)
	(segment
		(start 128.9558 -16.51889)
		(end 128.8034 -16.67129)
		(width 0.1524)
		(layer "In9.Cu")
		(net "M_B_CKE1")
	)
	(segment
		(start 157.2006 -10.794238)
		(end 154.939238 -13.0556)
		(width 0.1524)
		(layer "In9.Cu")
		(net "M_B_CKE1")
	)
	(segment
		(start 113.827306 -16.0782)
		(end 109.204506 -20.701)
		(width 0.1524)
		(layer "In9.Cu")
		(net "M_B_CKE1")
	)
	(segment
		(start 125.8443 -16.51889)
		(end 125.8443 -16.2052)
		(width 0.1524)
		(layer "In9.Cu")
		(net "M_B_CKE1")
	)
	(segment
		(start 124.3076 -16.2687)
		(end 124.1171 -16.0782)
		(width 0.1524)
		(layer "In9.Cu")
		(net "M_B_CKE1")
	)
	(arc
		(start 100.3427 -32.0421)
		(mid 100.132856 -31.939651)
		(end 99.90201 -31.904432)
		(width 0.1016)
		(layer "In9.Cu")
		(net "M_B_CKE1")
	)
	(arc
		(start 99.90201 -31.904432)
		(mid 99.758322 -31.872856)
		(end 99.6188 -31.8262)
		(width 0.1016)
		(layer "In9.Cu")
		(net "M_B_CKE1")
	)
	(arc
		(start 99.6188 -31.8262)
		(mid 99.53258 -31.764631)
		(end 99.48545 -31.669736)
		(width 0.1016)
		(layer "In9.Cu")
		(net "M_B_CKE1")
	)
	(segment
		(start 96.251268 -44.000674)
		(end 96.251268 -43.97756)
		(width 0.254)
		(layer "F.Cu")
		(net "VCCACKDDR0")
	)
	(segment
		(start 96.251268 -43.200574)
		(end 96.254062 -43.200574)
		(width 0.254)
		(layer "F.Cu")
		(net "VCCACKDDR0")
	)
	(segment
		(start 96.254062 -43.200574)
		(end 96.641158 -43.58767)
		(width 0.254)
		(layer "F.Cu")
		(net "VCCACKDDR0")
	)
	(segment
		(start 96.251268 -43.97756)
		(end 96.641158 -43.58767)
		(width 0.254)
		(layer "F.Cu")
		(net "VCCACKDDR0")
	)
	(via
		(at 96.408494 -50.276506)
		(size 0.7112)
		(drill 0.3556)
		(layers "F.Cu" "B.Cu")
		(net "VCCACKDDR0")
	)
	(via
		(at 96.641158 -43.58767)
		(size 0.4318)
		(drill 0.2032)
		(layers "F.Cu" "B.Cu")
		(net "VCCACKDDR0")
	)
	(segment
		(start 96.641158 -43.58767)
		(end 96.641158 -44.347892)
		(width 0.3048)
		(layer "B.Cu")
		(net "VCCACKDDR0")
	)
	(segment
		(start 96.1771 -44.81195)
		(end 96.1771 -48.7934)
		(width 0.3048)
		(layer "B.Cu")
		(net "VCCACKDDR0")
	)
	(segment
		(start 96.1771 -48.7934)
		(end 96.408494 -49.024794)
		(width 0.3048)
		(layer "B.Cu")
		(net "VCCACKDDR0")
	)
	(segment
		(start 96.408494 -49.024794)
		(end 96.408494 -50.276506)
		(width 0.3048)
		(layer "B.Cu")
		(net "VCCACKDDR0")
	)
	(segment
		(start 96.641158 -44.347892)
		(end 96.1771 -44.81195)
		(width 0.3048)
		(layer "B.Cu")
		(net "VCCACKDDR0")
	)
	(segment
		(start 95.631 -51.054)
		(end 95.631 -51.5366)
		(width 0.3048)
		(layer "B.Cu")
		(net "VCCACKDDR0")
	)
	(segment
		(start 96.408494 -50.276506)
		(end 95.631 -51.054)
		(width 0.3048)
		(layer "B.Cu")
		(net "VCCACKDDR0")
	)
	(segment
		(start 95.631 -51.5366)
		(end 94.361 -51.5366)
		(width 0.508)
		(layer "B.Cu")
		(net "VCCACKDDR0")
	)
	(segment
		(start 84.823554 -37.0713)
		(end 84.7725 -37.0713)
		(width 0.1143)
		(layer "F.Cu")
		(net "RTC_EXTPAD")
	)
	(segment
		(start 85.171788 -37.444934)
		(end 85.171788 -37.419534)
		(width 0.1143)
		(layer "F.Cu")
		(net "RTC_EXTPAD")
	)
	(segment
		(start 85.171788 -37.419534)
		(end 84.823554 -37.0713)
		(width 0.1143)
		(layer "F.Cu")
		(net "RTC_EXTPAD")
	)
	(via
		(at 80.01 -36.7157)
		(size 0.7112)
		(drill 0.3556)
		(layers "F.Cu" "B.Cu")
		(net "RTC_EXTPAD")
	)
	(via
		(at 84.7725 -37.0713)
		(size 0.4318)
		(drill 0.2032)
		(layers "F.Cu" "B.Cu")
		(net "RTC_EXTPAD")
	)
	(segment
		(start 84.70138 -37.0713)
		(end 84.7725 -37.0713)
		(width 0.1143)
		(layer "B.Cu")
		(net "RTC_EXTPAD")
	)
	(segment
		(start 80.01 -36.7157)
		(end 81.605628 -36.7157)
		(width 0.1143)
		(layer "B.Cu")
		(net "RTC_EXTPAD")
	)
	(segment
		(start 82.481928 -36.913566)
		(end 83.054444 -37.486082)
		(width 0.1143)
		(layer "B.Cu")
		(net "RTC_EXTPAD")
	)
	(segment
		(start 83.054444 -37.486082)
		(end 83.300316 -37.486082)
		(width 0.1143)
		(layer "B.Cu")
		(net "RTC_EXTPAD")
	)
	(segment
		(start 79.0702 -36.6268)
		(end 79.1591 -36.7157)
		(width 0.1143)
		(layer "B.Cu")
		(net "RTC_EXTPAD")
	)
	(segment
		(start 81.803494 -36.913566)
		(end 82.481928 -36.913566)
		(width 0.1143)
		(layer "B.Cu")
		(net "RTC_EXTPAD")
	)
	(segment
		(start 83.329018 -37.514784)
		(end 84.257896 -37.514784)
		(width 0.1143)
		(layer "B.Cu")
		(net "RTC_EXTPAD")
	)
	(segment
		(start 81.605628 -36.7157)
		(end 81.803494 -36.913566)
		(width 0.1143)
		(layer "B.Cu")
		(net "RTC_EXTPAD")
	)
	(segment
		(start 84.257896 -37.514784)
		(end 84.70138 -37.0713)
		(width 0.1143)
		(layer "B.Cu")
		(net "RTC_EXTPAD")
	)
	(segment
		(start 79.1591 -36.7157)
		(end 80.01 -36.7157)
		(width 0.1143)
		(layer "B.Cu")
		(net "RTC_EXTPAD")
	)
	(segment
		(start 83.300316 -37.486082)
		(end 83.329018 -37.514784)
		(width 0.1143)
		(layer "B.Cu")
		(net "RTC_EXTPAD")
	)
	(segment
		(start 25.9842 -50.8)
		(end 25.9842 -51.5366)
		(width 0.2032)
		(layer "F.Cu")
		(net "VR_PVCCP_ISUMN")
	)
	(segment
		(start 53.0352 -54.864)
		(end 53.0352 -55.753)
		(width 0.2032)
		(layer "F.Cu")
		(net "VR_PVCCP_ISUMN")
	)
	(segment
		(start 25.1206 -50.9016)
		(end 25.8826 -50.9016)
		(width 0.2032)
		(layer "F.Cu")
		(net "VR_PVCCP_ISUMN")
	)
	(segment
		(start 25.8826 -50.9016)
		(end 25.9842 -50.8)
		(width 0.2032)
		(layer "F.Cu")
		(net "VR_PVCCP_ISUMN")
	)
	(segment
		(start 25.9588 -50.038)
		(end 25.9588 -49.276)
		(width 0.2032)
		(layer "F.Cu")
		(net "VR_PVCCP_ISUMN")
	)
	(segment
		(start 25.9842 -50.8)
		(end 25.9588 -50.7746)
		(width 0.2032)
		(layer "F.Cu")
		(net "VR_PVCCP_ISUMN")
	)
	(segment
		(start 24.384 -50.9016)
		(end 25.1206 -50.9016)
		(width 0.2032)
		(layer "F.Cu")
		(net "VR_PVCCP_ISUMN")
	)
	(segment
		(start 25.9842 -51.5366)
		(end 25.908 -51.6128)
		(width 0.2032)
		(layer "F.Cu")
		(net "VR_PVCCP_ISUMN")
	)
	(segment
		(start 21.9456 -51.0794)
		(end 21.818092 -50.951892)
		(width 0.2032)
		(layer "F.Cu")
		(net "VR_PVCCP_ISUMN")
	)
	(segment
		(start 25.9588 -49.276)
		(end 25.5016 -48.8188)
		(width 0.2032)
		(layer "F.Cu")
		(net "VR_PVCCP_ISUMN")
	)
	(segment
		(start 24.9428 -48.895)
		(end 25.019 -48.8188)
		(width 0.2032)
		(layer "F.Cu")
		(net "VR_PVCCP_ISUMN")
	)
	(segment
		(start 24.1808 -48.895)
		(end 24.9428 -48.895)
		(width 0.2032)
		(layer "F.Cu")
		(net "VR_PVCCP_ISUMN")
	)
	(segment
		(start 21.9456 -51.6382)
		(end 21.9456 -51.0794)
		(width 0.2032)
		(layer "F.Cu")
		(net "VR_PVCCP_ISUMN")
	)
	(segment
		(start 25.5016 -48.8188)
		(end 25.019 -48.8188)
		(width 0.2032)
		(layer "F.Cu")
		(net "VR_PVCCP_ISUMN")
	)
	(segment
		(start 25.9588 -50.7746)
		(end 25.9588 -50.038)
		(width 0.2032)
		(layer "F.Cu")
		(net "VR_PVCCP_ISUMN")
	)
	(segment
		(start 24.3586 -50.927)
		(end 24.384 -50.9016)
		(width 0.2032)
		(layer "F.Cu")
		(net "VR_PVCCP_ISUMN")
	)
	(via
		(at 53.0352 -55.753)
		(size 0.508)
		(drill 0.254)
		(layers "F.Cu" "B.Cu")
		(net "VR_PVCCP_ISUMN")
	)
	(via
		(at 20.828 -51.308)
		(size 0.7112)
		(drill 0.3556)
		(layers "F.Cu" "B.Cu")
		(net "VR_PVCCP_ISUMN")
	)
	(via
		(at 21.818092 -50.951892)
		(size 0.508)
		(drill 0.254)
		(layers "F.Cu" "B.Cu")
		(net "VR_PVCCP_ISUMN")
	)
	(via
		(at 25.908 -51.6128)
		(size 0.508)
		(drill 0.254)
		(layers "F.Cu" "B.Cu")
		(net "VR_PVCCP_ISUMN")
	)
	(segment
		(start 21.461984 -51.308)
		(end 21.818092 -50.951892)
		(width 0.2032)
		(layer "B.Cu")
		(net "VR_PVCCP_ISUMN")
	)
	(segment
		(start 20.828 -51.308)
		(end 21.461984 -51.308)
		(width 0.2032)
		(layer "B.Cu")
		(net "VR_PVCCP_ISUMN")
	)
	(segment
		(start 52.838604 -55.556404)
		(end 53.0352 -55.753)
		(width 0.2032)
		(layer "In2.Cu")
		(net "VR_PVCCP_ISUMN")
	)
	(segment
		(start 25.908 -51.6128)
		(end 25.908 -52.077366)
		(width 0.2032)
		(layer "In2.Cu")
		(net "VR_PVCCP_ISUMN")
	)
	(segment
		(start 28.284932 -52.451)
		(end 30.42666 -52.451)
		(width 0.2032)
		(layer "In2.Cu")
		(net "VR_PVCCP_ISUMN")
	)
	(segment
		(start 25.908 -51.6128)
		(end 24.1808 -51.6128)
		(width 0.2032)
		(layer "In2.Cu")
		(net "VR_PVCCP_ISUMN")
	)
	(segment
		(start 26.779474 -52.94884)
		(end 27.787092 -52.94884)
		(width 0.2032)
		(layer "In2.Cu")
		(net "VR_PVCCP_ISUMN")
	)
	(segment
		(start 24.1808 -51.6128)
		(end 23.519892 -50.951892)
		(width 0.2032)
		(layer "In2.Cu")
		(net "VR_PVCCP_ISUMN")
	)
	(segment
		(start 23.519892 -50.951892)
		(end 21.818092 -50.951892)
		(width 0.2032)
		(layer "In2.Cu")
		(net "VR_PVCCP_ISUMN")
	)
	(segment
		(start 25.908 -52.077366)
		(end 26.779474 -52.94884)
		(width 0.2032)
		(layer "In2.Cu")
		(net "VR_PVCCP_ISUMN")
	)
	(segment
		(start 27.787092 -52.94884)
		(end 28.284932 -52.451)
		(width 0.2032)
		(layer "In2.Cu")
		(net "VR_PVCCP_ISUMN")
	)
	(segment
		(start 30.42666 -52.451)
		(end 33.532064 -55.556404)
		(width 0.2032)
		(layer "In2.Cu")
		(net "VR_PVCCP_ISUMN")
	)
	(segment
		(start 33.532064 -55.556404)
		(end 52.838604 -55.556404)
		(width 0.2032)
		(layer "In2.Cu")
		(net "VR_PVCCP_ISUMN")
	)
	(segment
		(start 111.193834 -32.5374)
		(end 110.749588 -32.093154)
		(width 0.1016)
		(layer "F.Cu")
		(net "M_B_CS_N1")
	)
	(segment
		(start 111.2012 -32.5374)
		(end 111.193834 -32.5374)
		(width 0.1016)
		(layer "F.Cu")
		(net "M_B_CS_N1")
	)
	(via
		(at 111.2012 -32.5374)
		(size 0.4318)
		(drill 0.2032)
		(layers "F.Cu" "B.Cu")
		(net "M_B_CS_N1")
	)
	(via
		(at 168.828212 -7.697978)
		(size 0.4318)
		(drill 0.2032)
		(layers "F.Cu" "B.Cu")
		(net "M_B_CS_N1")
	)
	(segment
		(start 169.15003 -7.923784)
		(end 168.924224 -7.697978)
		(width 0.1778)
		(layer "B.Cu")
		(net "M_B_CS_N1")
	)
	(segment
		(start 168.924224 -7.697978)
		(end 168.828212 -7.697978)
		(width 0.1778)
		(layer "B.Cu")
		(net "M_B_CS_N1")
	)
	(segment
		(start 169.15003 -9.89076)
		(end 169.15003 -7.923784)
		(width 0.1778)
		(layer "B.Cu")
		(net "M_B_CS_N1")
	)
	(segment
		(start 111.3028 -31.2674)
		(end 111.57585 -30.99435)
		(width 0.1016)
		(layer "In9.Cu")
		(net "M_B_CS_N1")
	)
	(segment
		(start 170.586654 -12.117578)
		(end 170.586654 -14.328394)
		(width 0.1524)
		(layer "In9.Cu")
		(net "M_B_CS_N1")
	)
	(segment
		(start 170.142154 -11.952478)
		(end 170.421554 -11.952478)
		(width 0.1524)
		(layer "In9.Cu")
		(net "M_B_CS_N1")
	)
	(segment
		(start 168.986962 -8.674354)
		(end 168.9354 -8.725916)
		(width 0.1524)
		(layer "In9.Cu")
		(net "M_B_CS_N1")
	)
	(segment
		(start 170.586654 -14.328394)
		(end 165.268148 -19.6469)
		(width 0.1524)
		(layer "In9.Cu")
		(net "M_B_CS_N1")
	)
	(segment
		(start 112.141 -30.353)
		(end 112.543844 -30.070298)
		(width 0.1016)
		(layer "In9.Cu")
		(net "M_B_CS_N1")
	)
	(segment
		(start 161.6075 -19.6469)
		(end 161.0106 -20.2438)
		(width 0.1524)
		(layer "In9.Cu")
		(net "M_B_CS_N1")
	)
	(segment
		(start 111.2012 -32.5374)
		(end 110.945422 -32.5374)
		(width 0.1016)
		(layer "In9.Cu")
		(net "M_B_CS_N1")
	)
	(segment
		(start 168.9354 -8.725916)
		(end 168.9354 -10.745724)
		(width 0.1524)
		(layer "In9.Cu")
		(net "M_B_CS_N1")
	)
	(segment
		(start 110.1598 -31.242)
		(end 110.3376 -31.0642)
		(width 0.1016)
		(layer "In9.Cu")
		(net "M_B_CS_N1")
	)
	(segment
		(start 161.0106 -22.145752)
		(end 155.902406 -27.253946)
		(width 0.1524)
		(layer "In9.Cu")
		(net "M_B_CS_N1")
	)
	(segment
		(start 110.84687 -31.189676)
		(end 110.924594 -31.2674)
		(width 0.1016)
		(layer "In9.Cu")
		(net "M_B_CS_N1")
	)
	(segment
		(start 115.360196 -27.253946)
		(end 112.543844 -30.070298)
		(width 0.1524)
		(layer "In9.Cu")
		(net "M_B_CS_N1")
	)
	(segment
		(start 165.268148 -19.6469)
		(end 161.6075 -19.6469)
		(width 0.1524)
		(layer "In9.Cu")
		(net "M_B_CS_N1")
	)
	(segment
		(start 111.805212 -30.965902)
		(end 112.007142 -30.78353)
		(width 0.1016)
		(layer "In9.Cu")
		(net "M_B_CS_N1")
	)
	(segment
		(start 161.0106 -20.2438)
		(end 161.0106 -22.145752)
		(width 0.1524)
		(layer "In9.Cu")
		(net "M_B_CS_N1")
	)
	(segment
		(start 168.986962 -7.856728)
		(end 168.986962 -8.674354)
		(width 0.1524)
		(layer "In9.Cu")
		(net "M_B_CS_N1")
	)
	(segment
		(start 110.3376 -31.0642)
		(end 110.4646 -31.0642)
		(width 0.1016)
		(layer "In9.Cu")
		(net "M_B_CS_N1")
	)
	(segment
		(start 170.421554 -11.952478)
		(end 170.586654 -12.117578)
		(width 0.1524)
		(layer "In9.Cu")
		(net "M_B_CS_N1")
	)
	(segment
		(start 168.9354 -10.745724)
		(end 170.142154 -11.952478)
		(width 0.1524)
		(layer "In9.Cu")
		(net "M_B_CS_N1")
	)
	(segment
		(start 110.1598 -31.751778)
		(end 110.1598 -31.242)
		(width 0.1016)
		(layer "In9.Cu")
		(net "M_B_CS_N1")
	)
	(segment
		(start 112.007142 -30.78353)
		(end 112.04194 -30.671516)
		(width 0.1016)
		(layer "In9.Cu")
		(net "M_B_CS_N1")
	)
	(segment
		(start 110.945422 -32.5374)
		(end 110.1598 -31.751778)
		(width 0.1016)
		(layer "In9.Cu")
		(net "M_B_CS_N1")
	)
	(segment
		(start 168.828212 -7.697978)
		(end 168.986962 -7.856728)
		(width 0.1524)
		(layer "In9.Cu")
		(net "M_B_CS_N1")
	)
	(segment
		(start 112.04194 -30.671516)
		(end 112.141 -30.353)
		(width 0.1016)
		(layer "In9.Cu")
		(net "M_B_CS_N1")
	)
	(segment
		(start 155.902406 -27.253946)
		(end 115.360196 -27.253946)
		(width 0.1524)
		(layer "In9.Cu")
		(net "M_B_CS_N1")
	)
	(arc
		(start 111.101378 -31.334202)
		(mid 111.207483 -31.317066)
		(end 111.3028 -31.2674)
		(width 0.1016)
		(layer "In9.Cu")
		(net "M_B_CS_N1")
	)
	(arc
		(start 110.924594 -31.2674)
		(mid 111.010042 -31.30859)
		(end 111.101378 -31.334202)
		(width 0.1016)
		(layer "In9.Cu")
		(net "M_B_CS_N1")
	)
	(arc
		(start 111.57585 -30.99435)
		(mid 111.691406 -30.987181)
		(end 111.805212 -30.965902)
		(width 0.1016)
		(layer "In9.Cu")
		(net "M_B_CS_N1")
	)
	(arc
		(start 110.4646 -31.0642)
		(mid 110.665772 -31.096366)
		(end 110.84687 -31.189676)
		(width 0.1016)
		(layer "In9.Cu")
		(net "M_B_CS_N1")
	)
	(segment
		(start 96.410018 -44.58208)
		(end 96.991424 -44.000674)
		(width 0.254)
		(layer "F.Cu")
		(net "VCCA_PLLDDR0_AVN")
	)
	(segment
		(start 95.71482 -44.61256)
		(end 95.7453 -44.58208)
		(width 0.254)
		(layer "F.Cu")
		(net "VCCA_PLLDDR0_AVN")
	)
	(segment
		(start 96.991424 -44.000674)
		(end 97.048828 -44.000674)
		(width 0.254)
		(layer "F.Cu")
		(net "VCCA_PLLDDR0_AVN")
	)
	(segment
		(start 95.7453 -44.58208)
		(end 96.410018 -44.58208)
		(width 0.254)
		(layer "F.Cu")
		(net "VCCA_PLLDDR0_AVN")
	)
	(via
		(at 95.71482 -44.61256)
		(size 0.4318)
		(drill 0.2032)
		(layers "F.Cu" "B.Cu")
		(net "VCCA_PLLDDR0_AVN")
	)
	(via
		(at 94.9198 -43.4594)
		(size 0.7112)
		(drill 0.3556)
		(layers "F.Cu" "B.Cu")
		(net "VCCA_PLLDDR0_AVN")
	)
	(segment
		(start 95.71228 -44.6151)
		(end 94.8944 -44.6151)
		(width 0.3048)
		(layer "B.Cu")
		(net "VCCA_PLLDDR0_AVN")
	)
	(segment
		(start 96.06788 -44.15536)
		(end 95.71482 -44.50842)
		(width 0.3048)
		(layer "B.Cu")
		(net "VCCA_PLLDDR0_AVN")
	)
	(segment
		(start 95.71482 -44.61256)
		(end 95.71228 -44.6151)
		(width 0.3048)
		(layer "B.Cu")
		(net "VCCA_PLLDDR0_AVN")
	)
	(segment
		(start 94.8944 -44.6151)
		(end 94.8944 -43.4848)
		(width 0.3048)
		(layer "B.Cu")
		(net "VCCA_PLLDDR0_AVN")
	)
	(segment
		(start 95.71482 -44.50842)
		(end 95.71482 -44.61256)
		(width 0.3048)
		(layer "B.Cu")
		(net "VCCA_PLLDDR0_AVN")
	)
	(segment
		(start 94.8944 -43.4848)
		(end 94.9198 -43.4594)
		(width 0.3048)
		(layer "B.Cu")
		(net "VCCA_PLLDDR0_AVN")
	)
	(segment
		(start 94.010734 -31.905448)
		(end 94.010734 -31.884112)
		(width 0.127)
		(layer "F.Cu")
		(net "TP_CPU_RSVD15")
	)
	(segment
		(start 93.632528 -32.283654)
		(end 94.010734 -31.905448)
		(width 0.127)
		(layer "F.Cu")
		(net "TP_CPU_RSVD15")
	)
	(via
		(at 94.010734 -31.884112)
		(size 0.4318)
		(drill 0.2032)
		(layers "F.Cu" "B.Cu")
		(net "TP_CPU_RSVD15")
	)
	(segment
		(start 95.2754 -30.619446)
		(end 94.010734 -31.884112)
		(width 0.127)
		(layer "B.Cu")
		(net "TP_CPU_RSVD15")
	)
	(segment
		(start 95.2754 -30.1498)
		(end 95.2754 -30.619446)
		(width 0.127)
		(layer "B.Cu")
		(net "TP_CPU_RSVD15")
	)
	(via
		(at 200.787 -3.683)
		(size 0.7112)
		(drill 0.3556)
		(layers "F.Cu" "B.Cu")
		(net "SMB_M_B0_R_DATA")
	)
	(via
		(at 200.787 -2.794)
		(size 0.5588)
		(drill 0.3048)
		(layers "F.Cu" "B.Cu")
		(net "SMB_M_B0_R_DATA")
	)
	(via
		(at 189.2046 -5.207)
		(size 0.4318)
		(drill 0.2032)
		(layers "F.Cu" "B.Cu")
		(net "SMB_M_B0_R_DATA")
	)
	(segment
		(start 190.449962 -2.88925)
		(end 190.449962 -1.690624)
		(width 0.1143)
		(layer "B.Cu")
		(net "SMB_M_B0_R_DATA")
	)
	(segment
		(start 198.8566 -5.3086)
		(end 199.7964 -5.3086)
		(width 0.1143)
		(layer "B.Cu")
		(net "SMB_M_B0_R_DATA")
	)
	(segment
		(start 200.787 -3.683)
		(end 200.787 -2.794)
		(width 0.1143)
		(layer "B.Cu")
		(net "SMB_M_B0_R_DATA")
	)
	(segment
		(start 189.2046 -5.207)
		(end 189.2046 -4.134612)
		(width 0.1143)
		(layer "B.Cu")
		(net "SMB_M_B0_R_DATA")
	)
	(segment
		(start 197.612 -4.2418)
		(end 197.7898 -4.2418)
		(width 0.1143)
		(layer "B.Cu")
		(net "SMB_M_B0_R_DATA")
	)
	(segment
		(start 199.7964 -5.3086)
		(end 200.787 -4.318)
		(width 0.1143)
		(layer "B.Cu")
		(net "SMB_M_B0_R_DATA")
	)
	(segment
		(start 197.7898 -4.2418)
		(end 198.8566 -5.3086)
		(width 0.1143)
		(layer "B.Cu")
		(net "SMB_M_B0_R_DATA")
	)
	(segment
		(start 189.2046 -4.134612)
		(end 190.449962 -2.88925)
		(width 0.1143)
		(layer "B.Cu")
		(net "SMB_M_B0_R_DATA")
	)
	(segment
		(start 200.787 -4.318)
		(end 200.787 -3.683)
		(width 0.1143)
		(layer "B.Cu")
		(net "SMB_M_B0_R_DATA")
	)
	(segment
		(start 200.787 -2.794)
		(end 199.491854 -2.794)
		(width 0.0889)
		(layer "In7.Cu")
		(net "SMB_M_B0_R_DATA")
	)
	(segment
		(start 198.090282 -1.392428)
		(end 191.647572 -1.392428)
		(width 0.0889)
		(layer "In7.Cu")
		(net "SMB_M_B0_R_DATA")
	)
	(segment
		(start 189.2046 -3.8354)
		(end 189.2046 -5.207)
		(width 0.0889)
		(layer "In7.Cu")
		(net "SMB_M_B0_R_DATA")
	)
	(segment
		(start 199.491854 -2.794)
		(end 198.090282 -1.392428)
		(width 0.0889)
		(layer "In7.Cu")
		(net "SMB_M_B0_R_DATA")
	)
	(segment
		(start 191.647572 -1.392428)
		(end 189.2046 -3.8354)
		(width 0.0889)
		(layer "In7.Cu")
		(net "SMB_M_B0_R_DATA")
	)
	(segment
		(start 16.2814 -59.8932)
		(end 16.582136 -59.8932)
		(width 0.1143)
		(layer "F.Cu")
		(net "VR_95831_ALERT_N")
	)
	(segment
		(start 18.590006 -59.019948)
		(end 17.455388 -59.019948)
		(width 0.1143)
		(layer "F.Cu")
		(net "VR_95831_ALERT_N")
	)
	(segment
		(start 16.582136 -59.8932)
		(end 17.244568 -59.230768)
		(width 0.1143)
		(layer "F.Cu")
		(net "VR_95831_ALERT_N")
	)
	(segment
		(start 17.455388 -59.019948)
		(end 17.244568 -59.230768)
		(width 0.1143)
		(layer "F.Cu")
		(net "VR_95831_ALERT_N")
	)
	(via
		(at 17.244568 -59.230768)
		(size 0.7112)
		(drill 0.3556)
		(layers "F.Cu" "B.Cu")
		(net "VR_95831_ALERT_N")
	)
	(segment
		(start 98.649028 -34.455608)
		(end 99.021392 -34.827972)
		(width 0.254)
		(layer "F.Cu")
		(net "VCCACKDDR1")
	)
	(segment
		(start 98.649028 -35.199066)
		(end 99.020122 -34.827972)
		(width 0.254)
		(layer "F.Cu")
		(net "VCCACKDDR1")
	)
	(segment
		(start 98.649028 -34.399474)
		(end 98.649028 -34.455608)
		(width 0.254)
		(layer "F.Cu")
		(net "VCCACKDDR1")
	)
	(segment
		(start 99.020122 -34.827972)
		(end 99.021392 -34.827972)
		(width 0.254)
		(layer "F.Cu")
		(net "VCCACKDDR1")
	)
	(segment
		(start 98.649028 -35.199574)
		(end 98.649028 -35.199066)
		(width 0.254)
		(layer "F.Cu")
		(net "VCCACKDDR1")
	)
	(via
		(at 95.9739 -16.129)
		(size 0.7112)
		(drill 0.3556)
		(layers "F.Cu" "B.Cu")
		(net "VCCACKDDR1")
	)
	(via
		(at 99.021392 -34.827972)
		(size 0.4318)
		(drill 0.2032)
		(layers "F.Cu" "B.Cu")
		(net "VCCACKDDR1")
	)
	(via
		(at 98.552 -18.532602)
		(size 0.508)
		(drill 0.254)
		(layers "F.Cu" "B.Cu")
		(net "VCCACKDDR1")
	)
	(segment
		(start 96.647 -17.389602)
		(end 95.502984 -17.389602)
		(width 0.508)
		(layer "B.Cu")
		(net "VCCACKDDR1")
	)
	(segment
		(start 96.647 -17.389602)
		(end 97.409 -17.389602)
		(width 0.508)
		(layer "B.Cu")
		(net "VCCACKDDR1")
	)
	(segment
		(start 95.885 -16.129)
		(end 95.9739 -16.129)
		(width 0.508)
		(layer "B.Cu")
		(net "VCCACKDDR1")
	)
	(segment
		(start 95.401384 -16.612616)
		(end 95.885 -16.129)
		(width 0.508)
		(layer "B.Cu")
		(net "VCCACKDDR1")
	)
	(segment
		(start 95.401384 -17.288002)
		(end 95.401384 -16.612616)
		(width 0.508)
		(layer "B.Cu")
		(net "VCCACKDDR1")
	)
	(segment
		(start 95.502984 -17.389602)
		(end 95.401384 -17.288002)
		(width 0.508)
		(layer "B.Cu")
		(net "VCCACKDDR1")
	)
	(segment
		(start 97.409 -17.389602)
		(end 98.552 -18.532602)
		(width 0.508)
		(layer "B.Cu")
		(net "VCCACKDDR1")
	)
	(segment
		(start 96.52508 -24.12492)
		(end 96.52508 -26.04008)
		(width 0.3048)
		(layer "In9.Cu")
		(net "VCCACKDDR1")
	)
	(segment
		(start 98.43262 -34.15792)
		(end 99.021392 -34.746692)
		(width 0.3048)
		(layer "In9.Cu")
		(net "VCCACKDDR1")
	)
	(segment
		(start 98.43262 -32.855916)
		(end 98.43262 -34.15792)
		(width 0.3048)
		(layer "In9.Cu")
		(net "VCCACKDDR1")
	)
	(segment
		(start 98.4504 -28.566872)
		(end 98.4504 -32.838136)
		(width 0.3048)
		(layer "In9.Cu")
		(net "VCCACKDDR1")
	)
	(segment
		(start 97.716594 -27.231594)
		(end 97.716594 -27.833066)
		(width 0.3048)
		(layer "In9.Cu")
		(net "VCCACKDDR1")
	)
	(segment
		(start 99.021392 -34.746692)
		(end 99.021392 -34.827972)
		(width 0.3048)
		(layer "In9.Cu")
		(net "VCCACKDDR1")
	)
	(segment
		(start 96.901 -23.749)
		(end 96.52508 -24.12492)
		(width 0.3048)
		(layer "In9.Cu")
		(net "VCCACKDDR1")
	)
	(segment
		(start 97.716594 -27.833066)
		(end 98.4504 -28.566872)
		(width 0.3048)
		(layer "In9.Cu")
		(net "VCCACKDDR1")
	)
	(segment
		(start 96.52508 -26.04008)
		(end 97.716594 -27.231594)
		(width 0.3048)
		(layer "In9.Cu")
		(net "VCCACKDDR1")
	)
	(segment
		(start 96.901 -20.183602)
		(end 96.901 -23.749)
		(width 0.3048)
		(layer "In9.Cu")
		(net "VCCACKDDR1")
	)
	(segment
		(start 98.4504 -32.838136)
		(end 98.43262 -32.855916)
		(width 0.3048)
		(layer "In9.Cu")
		(net "VCCACKDDR1")
	)
	(segment
		(start 98.552 -18.532602)
		(end 96.901 -20.183602)
		(width 0.3048)
		(layer "In9.Cu")
		(net "VCCACKDDR1")
	)
	(via
		(at 199.229726 -4.694936)
		(size 0.7112)
		(drill 0.3556)
		(layers "F.Cu" "B.Cu")
		(net "SMB_M_B0_R_CLK")
	)
	(via
		(at 199.771 -3.429)
		(size 0.5588)
		(drill 0.3048)
		(layers "F.Cu" "B.Cu")
		(net "SMB_M_B0_R_CLK")
	)
	(via
		(at 189.23 -5.842)
		(size 0.4318)
		(drill 0.2032)
		(layers "F.Cu" "B.Cu")
		(net "SMB_M_B0_R_CLK")
	)
	(segment
		(start 196.85 -4.064)
		(end 197.13575 -3.77825)
		(width 0.1143)
		(layer "B.Cu")
		(net "SMB_M_B0_R_CLK")
	)
	(segment
		(start 199.771 -3.429)
		(end 199.771 -4.153662)
		(width 0.1143)
		(layer "B.Cu")
		(net "SMB_M_B0_R_CLK")
	)
	(segment
		(start 189.738 -5.334)
		(end 189.738 -4.0513)
		(width 0.1143)
		(layer "B.Cu")
		(net "SMB_M_B0_R_CLK")
	)
	(segment
		(start 196.85 -4.2418)
		(end 196.85 -4.064)
		(width 0.1143)
		(layer "B.Cu")
		(net "SMB_M_B0_R_CLK")
	)
	(segment
		(start 191.04991 -2.73939)
		(end 191.04991 -1.690624)
		(width 0.1143)
		(layer "B.Cu")
		(net "SMB_M_B0_R_CLK")
	)
	(segment
		(start 189.23 -5.842)
		(end 189.738 -5.334)
		(width 0.1143)
		(layer "B.Cu")
		(net "SMB_M_B0_R_CLK")
	)
	(segment
		(start 199.771 -4.153662)
		(end 199.229726 -4.694936)
		(width 0.1143)
		(layer "B.Cu")
		(net "SMB_M_B0_R_CLK")
	)
	(segment
		(start 198.31304 -3.77825)
		(end 199.229726 -4.694936)
		(width 0.1143)
		(layer "B.Cu")
		(net "SMB_M_B0_R_CLK")
	)
	(segment
		(start 197.13575 -3.77825)
		(end 198.31304 -3.77825)
		(width 0.1143)
		(layer "B.Cu")
		(net "SMB_M_B0_R_CLK")
	)
	(segment
		(start 189.738 -4.0513)
		(end 191.04991 -2.73939)
		(width 0.1143)
		(layer "B.Cu")
		(net "SMB_M_B0_R_CLK")
	)
	(segment
		(start 199.462136 -3.429)
		(end 197.895464 -1.862328)
		(width 0.0889)
		(layer "In7.Cu")
		(net "SMB_M_B0_R_CLK")
	)
	(segment
		(start 197.895464 -1.862328)
		(end 191.812672 -1.862328)
		(width 0.0889)
		(layer "In7.Cu")
		(net "SMB_M_B0_R_CLK")
	)
	(segment
		(start 189.653164 -5.418836)
		(end 189.23 -5.842)
		(width 0.0889)
		(layer "In7.Cu")
		(net "SMB_M_B0_R_CLK")
	)
	(segment
		(start 189.653164 -4.021836)
		(end 189.653164 -5.418836)
		(width 0.0889)
		(layer "In7.Cu")
		(net "SMB_M_B0_R_CLK")
	)
	(segment
		(start 199.771 -3.429)
		(end 199.462136 -3.429)
		(width 0.0889)
		(layer "In7.Cu")
		(net "SMB_M_B0_R_CLK")
	)
	(segment
		(start 191.812672 -1.862328)
		(end 189.653164 -4.021836)
		(width 0.0889)
		(layer "In7.Cu")
		(net "SMB_M_B0_R_CLK")
	)
	(segment
		(start 25.428448 -55.6006)
		(end 26.3652 -55.6006)
		(width 0.2032)
		(layer "F.Cu")
		(net "VR_PVCCP_GH")
	)
	(segment
		(start 25.0444 -56.317642)
		(end 25.0444 -55.984648)
		(width 0.2032)
		(layer "F.Cu")
		(net "VR_PVCCP_GH")
	)
	(segment
		(start 24.74214 -56.619902)
		(end 25.0444 -56.317642)
		(width 0.2032)
		(layer "F.Cu")
		(net "VR_PVCCP_GH")
	)
	(segment
		(start 24.335994 -56.619902)
		(end 24.74214 -56.619902)
		(width 0.2032)
		(layer "F.Cu")
		(net "VR_PVCCP_GH")
	)
	(segment
		(start 26.3652 -55.6006)
		(end 26.416 -55.6514)
		(width 0.2032)
		(layer "F.Cu")
		(net "VR_PVCCP_GH")
	)
	(segment
		(start 25.0444 -55.984648)
		(end 25.428448 -55.6006)
		(width 0.2032)
		(layer "F.Cu")
		(net "VR_PVCCP_GH")
	)
	(segment
		(start 99.308666 -31.902654)
		(end 99.038156 -31.632144)
		(width 0.1016)
		(layer "F.Cu")
		(net "M_B_CKE0")
	)
	(segment
		(start 99.591368 -31.902654)
		(end 99.308666 -31.902654)
		(width 0.1016)
		(layer "F.Cu")
		(net "M_B_CKE0")
	)
	(via
		(at 99.038156 -31.632144)
		(size 0.4318)
		(drill 0.2032)
		(layers "F.Cu" "B.Cu")
		(net "M_B_CKE0")
	)
	(via
		(at 156.236162 -7.79526)
		(size 0.4318)
		(drill 0.2032)
		(layers "F.Cu" "B.Cu")
		(net "M_B_CKE0")
	)
	(segment
		(start 156.691076 -8.625078)
		(end 156.691076 -8.235442)
		(width 0.1778)
		(layer "B.Cu")
		(net "M_B_CKE0")
	)
	(segment
		(start 156.549852 -8.766302)
		(end 156.691076 -8.625078)
		(width 0.1778)
		(layer "B.Cu")
		(net "M_B_CKE0")
	)
	(segment
		(start 156.261562 -7.82066)
		(end 156.236162 -7.79526)
		(width 0.1778)
		(layer "B.Cu")
		(net "M_B_CKE0")
	)
	(segment
		(start 156.549852 -9.89076)
		(end 156.549852 -8.766302)
		(width 0.1778)
		(layer "B.Cu")
		(net "M_B_CKE0")
	)
	(segment
		(start 156.276294 -7.82066)
		(end 156.261562 -7.82066)
		(width 0.1778)
		(layer "B.Cu")
		(net "M_B_CKE0")
	)
	(segment
		(start 156.691076 -8.235442)
		(end 156.276294 -7.82066)
		(width 0.1778)
		(layer "B.Cu")
		(net "M_B_CKE0")
	)
	(segment
		(start 154.69743 -12.471146)
		(end 138.811 -12.471146)
		(width 0.1524)
		(layer "In9.Cu")
		(net "M_B_CKE0")
	)
	(segment
		(start 136.9822 -13.1064)
		(end 136.9822 -14.1478)
		(width 0.1524)
		(layer "In9.Cu")
		(net "M_B_CKE0")
	)
	(segment
		(start 102.1207 -25.924256)
		(end 99.038156 -29.0068)
		(width 0.1016)
		(layer "In9.Cu")
		(net "M_B_CKE0")
	)
	(segment
		(start 99.038156 -29.0068)
		(end 99.038156 -31.632144)
		(width 0.1016)
		(layer "In9.Cu")
		(net "M_B_CKE0")
	)
	(segment
		(start 156.236162 -7.798562)
		(end 156.678376 -8.240776)
		(width 0.1524)
		(layer "In9.Cu")
		(net "M_B_CKE0")
	)
	(segment
		(start 102.1207 -20.6629)
		(end 102.1207 -25.924256)
		(width 0.1524)
		(layer "In9.Cu")
		(net "M_B_CKE0")
	)
	(segment
		(start 113.610644 -15.4686)
		(end 108.886244 -20.193)
		(width 0.1524)
		(layer "In9.Cu")
		(net "M_B_CKE0")
	)
	(segment
		(start 136.9822 -14.1478)
		(end 135.6614 -15.4686)
		(width 0.1524)
		(layer "In9.Cu")
		(net "M_B_CKE0")
	)
	(segment
		(start 137.6172 -12.4714)
		(end 136.9822 -13.1064)
		(width 0.1524)
		(layer "In9.Cu")
		(net "M_B_CKE0")
	)
	(segment
		(start 130.81254 -15.621)
		(end 130.81254 -15.851886)
		(width 0.1524)
		(layer "In9.Cu")
		(net "M_B_CKE0")
	)
	(segment
		(start 135.6614 -15.4686)
		(end 134.62254 -15.4686)
		(width 0.1524)
		(layer "In9.Cu")
		(net "M_B_CKE0")
	)
	(segment
		(start 138.811 -12.471146)
		(end 138.810746 -12.4714)
		(width 0.1524)
		(layer "In9.Cu")
		(net "M_B_CKE0")
	)
	(segment
		(start 130.20294 -15.621)
		(end 130.05054 -15.4686)
		(width 0.1524)
		(layer "In9.Cu")
		(net "M_B_CKE0")
	)
	(segment
		(start 131.42214 -15.621)
		(end 131.26974 -15.4686)
		(width 0.1524)
		(layer "In9.Cu")
		(net "M_B_CKE0")
	)
	(segment
		(start 131.87934 -16.004286)
		(end 131.57454 -16.004286)
		(width 0.1524)
		(layer "In9.Cu")
		(net "M_B_CKE0")
	)
	(segment
		(start 132.03174 -15.851886)
		(end 131.87934 -16.004286)
		(width 0.1524)
		(layer "In9.Cu")
		(net "M_B_CKE0")
	)
	(segment
		(start 132.03174 -15.621)
		(end 132.03174 -15.851886)
		(width 0.1524)
		(layer "In9.Cu")
		(net "M_B_CKE0")
	)
	(segment
		(start 130.05054 -15.4686)
		(end 113.610644 -15.4686)
		(width 0.1524)
		(layer "In9.Cu")
		(net "M_B_CKE0")
	)
	(segment
		(start 132.18414 -15.4686)
		(end 132.03174 -15.621)
		(width 0.1524)
		(layer "In9.Cu")
		(net "M_B_CKE0")
	)
	(segment
		(start 138.810746 -12.4714)
		(end 137.6172 -12.4714)
		(width 0.1524)
		(layer "In9.Cu")
		(net "M_B_CKE0")
	)
	(segment
		(start 133.25094 -15.851886)
		(end 133.09854 -16.004286)
		(width 0.1524)
		(layer "In9.Cu")
		(net "M_B_CKE0")
	)
	(segment
		(start 133.70814 -15.4686)
		(end 133.40334 -15.4686)
		(width 0.1524)
		(layer "In9.Cu")
		(net "M_B_CKE0")
	)
	(segment
		(start 130.81254 -15.851886)
		(end 130.66014 -16.004286)
		(width 0.1524)
		(layer "In9.Cu")
		(net "M_B_CKE0")
	)
	(segment
		(start 156.236162 -7.79526)
		(end 156.236162 -7.798562)
		(width 0.1524)
		(layer "In9.Cu")
		(net "M_B_CKE0")
	)
	(segment
		(start 131.26974 -15.4686)
		(end 130.96494 -15.4686)
		(width 0.1524)
		(layer "In9.Cu")
		(net "M_B_CKE0")
	)
	(segment
		(start 102.5906 -20.193)
		(end 102.1207 -20.6629)
		(width 0.1524)
		(layer "In9.Cu")
		(net "M_B_CKE0")
	)
	(segment
		(start 132.79374 -16.004286)
		(end 132.64134 -15.851886)
		(width 0.1524)
		(layer "In9.Cu")
		(net "M_B_CKE0")
	)
	(segment
		(start 134.47014 -15.621)
		(end 134.47014 -15.851886)
		(width 0.1524)
		(layer "In9.Cu")
		(net "M_B_CKE0")
	)
	(segment
		(start 134.47014 -15.851886)
		(end 134.31774 -16.004286)
		(width 0.1524)
		(layer "In9.Cu")
		(net "M_B_CKE0")
	)
	(segment
		(start 130.66014 -16.004286)
		(end 130.35534 -16.004286)
		(width 0.1524)
		(layer "In9.Cu")
		(net "M_B_CKE0")
	)
	(segment
		(start 108.886244 -20.193)
		(end 102.5906 -20.193)
		(width 0.1524)
		(layer "In9.Cu")
		(net "M_B_CKE0")
	)
	(segment
		(start 133.40334 -15.4686)
		(end 133.25094 -15.621)
		(width 0.1524)
		(layer "In9.Cu")
		(net "M_B_CKE0")
	)
	(segment
		(start 134.01294 -16.004286)
		(end 133.86054 -15.851886)
		(width 0.1524)
		(layer "In9.Cu")
		(net "M_B_CKE0")
	)
	(segment
		(start 130.96494 -15.4686)
		(end 130.81254 -15.621)
		(width 0.1524)
		(layer "In9.Cu")
		(net "M_B_CKE0")
	)
	(segment
		(start 134.62254 -15.4686)
		(end 134.47014 -15.621)
		(width 0.1524)
		(layer "In9.Cu")
		(net "M_B_CKE0")
	)
	(segment
		(start 131.57454 -16.004286)
		(end 131.42214 -15.851886)
		(width 0.1524)
		(layer "In9.Cu")
		(net "M_B_CKE0")
	)
	(segment
		(start 133.86054 -15.621)
		(end 133.70814 -15.4686)
		(width 0.1524)
		(layer "In9.Cu")
		(net "M_B_CKE0")
	)
	(segment
		(start 156.678376 -8.240776)
		(end 156.678376 -10.4902)
		(width 0.1524)
		(layer "In9.Cu")
		(net "M_B_CKE0")
	)
	(segment
		(start 133.86054 -15.851886)
		(end 133.86054 -15.621)
		(width 0.1524)
		(layer "In9.Cu")
		(net "M_B_CKE0")
	)
	(segment
		(start 131.42214 -15.851886)
		(end 131.42214 -15.621)
		(width 0.1524)
		(layer "In9.Cu")
		(net "M_B_CKE0")
	)
	(segment
		(start 130.35534 -16.004286)
		(end 130.20294 -15.851886)
		(width 0.1524)
		(layer "In9.Cu")
		(net "M_B_CKE0")
	)
	(segment
		(start 156.678376 -10.4902)
		(end 154.69743 -12.471146)
		(width 0.1524)
		(layer "In9.Cu")
		(net "M_B_CKE0")
	)
	(segment
		(start 133.09854 -16.004286)
		(end 132.79374 -16.004286)
		(width 0.1524)
		(layer "In9.Cu")
		(net "M_B_CKE0")
	)
	(segment
		(start 134.31774 -16.004286)
		(end 134.01294 -16.004286)
		(width 0.1524)
		(layer "In9.Cu")
		(net "M_B_CKE0")
	)
	(segment
		(start 132.64134 -15.851886)
		(end 132.64134 -15.621)
		(width 0.1524)
		(layer "In9.Cu")
		(net "M_B_CKE0")
	)
	(segment
		(start 132.64134 -15.621)
		(end 132.48894 -15.4686)
		(width 0.1524)
		(layer "In9.Cu")
		(net "M_B_CKE0")
	)
	(segment
		(start 133.25094 -15.621)
		(end 133.25094 -15.851886)
		(width 0.1524)
		(layer "In9.Cu")
		(net "M_B_CKE0")
	)
	(segment
		(start 132.48894 -15.4686)
		(end 132.18414 -15.4686)
		(width 0.1524)
		(layer "In9.Cu")
		(net "M_B_CKE0")
	)
	(segment
		(start 130.20294 -15.851886)
		(end 130.20294 -15.621)
		(width 0.1524)
		(layer "In9.Cu")
		(net "M_B_CKE0")
	)
	(segment
		(start 93.632528 -30.759654)
		(end 93.632528 -30.789118)
		(width 0.127)
		(layer "F.Cu")
		(net "TP_CPU_RSVD16")
	)
	(segment
		(start 93.632528 -30.789118)
		(end 93.299534 -31.122112)
		(width 0.127)
		(layer "F.Cu")
		(net "TP_CPU_RSVD16")
	)
	(via
		(at 93.299534 -31.122112)
		(size 0.4318)
		(drill 0.2032)
		(layers "F.Cu" "B.Cu")
		(net "TP_CPU_RSVD16")
	)
	(segment
		(start 93.598238 -30.823408)
		(end 93.299534 -31.122112)
		(width 0.127)
		(layer "B.Cu")
		(net "TP_CPU_RSVD16")
	)
	(segment
		(start 93.598238 -28.723336)
		(end 93.598238 -30.823408)
		(width 0.127)
		(layer "B.Cu")
		(net "TP_CPU_RSVD16")
	)
	(segment
		(start 94.869 -27.702002)
		(end 94.619572 -27.702002)
		(width 0.127)
		(layer "B.Cu")
		(net "TP_CPU_RSVD16")
	)
	(segment
		(start 94.619572 -27.702002)
		(end 93.598238 -28.723336)
		(width 0.127)
		(layer "B.Cu")
		(net "TP_CPU_RSVD16")
	)
	(segment
		(start 16.2052 -53.0098)
		(end 16.4338 -53.0098)
		(width 0.2032)
		(layer "F.Cu")
		(net "VR_PVCCP_VW")
	)
	(segment
		(start 18.590006 -55.623206)
		(end 17.437608 -54.470808)
		(width 0.2032)
		(layer "F.Cu")
		(net "VR_PVCCP_VW")
	)
	(segment
		(start 17.437608 -54.013608)
		(end 17.437608 -54.063392)
		(width 0.2032)
		(layer "F.Cu")
		(net "VR_PVCCP_VW")
	)
	(segment
		(start 17.437608 -54.470808)
		(end 17.437608 -54.063392)
		(width 0.2032)
		(layer "F.Cu")
		(net "VR_PVCCP_VW")
	)
	(segment
		(start 16.1798 -53.0352)
		(end 16.2052 -53.0098)
		(width 0.2032)
		(layer "F.Cu")
		(net "VR_PVCCP_VW")
	)
	(segment
		(start 18.590006 -56.220106)
		(end 18.590006 -55.623206)
		(width 0.2032)
		(layer "F.Cu")
		(net "VR_PVCCP_VW")
	)
	(segment
		(start 16.4338 -53.0098)
		(end 17.437608 -54.013608)
		(width 0.2032)
		(layer "F.Cu")
		(net "VR_PVCCP_VW")
	)
	(segment
		(start 15.3924 -53.0352)
		(end 16.1798 -53.0352)
		(width 0.2032)
		(layer "F.Cu")
		(net "VR_PVCCP_VW")
	)
	(via
		(at 17.437608 -54.063392)
		(size 0.7112)
		(drill 0.3556)
		(layers "F.Cu" "B.Cu")
		(net "VR_PVCCP_VW")
	)
	(segment
		(start 111.302546 -30.246574)
		(end 111.153448 -30.246574)
		(width 0.1778)
		(layer "F.Cu")
		(net "M_B_CS_N0")
	)
	(segment
		(start 111.561372 -30.5054)
		(end 111.302546 -30.246574)
		(width 0.1778)
		(layer "F.Cu")
		(net "M_B_CS_N0")
	)
	(segment
		(start 111.6076 -30.5054)
		(end 111.561372 -30.5054)
		(width 0.1778)
		(layer "F.Cu")
		(net "M_B_CS_N0")
	)
	(via
		(at 168.073832 -7.797546)
		(size 0.4318)
		(drill 0.2032)
		(layers "F.Cu" "B.Cu")
		(net "M_B_CS_N0")
	)
	(via
		(at 111.6076 -30.5054)
		(size 0.4318)
		(drill 0.2032)
		(layers "F.Cu" "B.Cu")
		(net "M_B_CS_N0")
	)
	(segment
		(start 168.549828 -9.89076)
		(end 168.549828 -9.089136)
		(width 0.1778)
		(layer "B.Cu")
		(net "M_B_CS_N0")
	)
	(segment
		(start 168.549828 -9.089136)
		(end 168.679368 -8.790686)
		(width 0.1778)
		(layer "B.Cu")
		(net "M_B_CS_N0")
	)
	(segment
		(start 168.712134 -8.61441)
		(end 168.745662 -8.434578)
		(width 0.1778)
		(layer "B.Cu")
		(net "M_B_CS_N0")
	)
	(segment
		(start 168.745662 -8.434578)
		(end 168.614344 -8.095234)
		(width 0.1778)
		(layer "B.Cu")
		(net "M_B_CS_N0")
	)
	(segment
		(start 168.614344 -8.095234)
		(end 168.424606 -7.905496)
		(width 0.1778)
		(layer "B.Cu")
		(net "M_B_CS_N0")
	)
	(segment
		(start 168.679368 -8.790686)
		(end 168.712134 -8.61441)
		(width 0.1778)
		(layer "B.Cu")
		(net "M_B_CS_N0")
	)
	(segment
		(start 168.424606 -7.905496)
		(end 168.073832 -7.797546)
		(width 0.1778)
		(layer "B.Cu")
		(net "M_B_CS_N0")
	)
	(segment
		(start 156.678122 -25.275286)
		(end 156.678122 -25.490678)
		(width 0.1524)
		(layer "In9.Cu")
		(net "M_B_CS_N0")
	)
	(segment
		(start 157.227016 -24.099012)
		(end 157.642306 -24.514302)
		(width 0.1524)
		(layer "In9.Cu")
		(net "M_B_CS_N0")
	)
	(segment
		(start 156.795724 -24.530304)
		(end 156.580332 -24.530304)
		(width 0.1524)
		(layer "In9.Cu")
		(net "M_B_CS_N0")
	)
	(segment
		(start 160.4264 -21.90369)
		(end 158.56839 -23.7617)
		(width 0.1524)
		(layer "In9.Cu")
		(net "M_B_CS_N0")
	)
	(segment
		(start 165.026086 -19.0627)
		(end 160.8963 -19.0627)
		(width 0.1524)
		(layer "In9.Cu")
		(net "M_B_CS_N0")
	)
	(segment
		(start 157.227016 -23.88362)
		(end 157.227016 -24.099012)
		(width 0.1524)
		(layer "In9.Cu")
		(net "M_B_CS_N0")
	)
	(segment
		(start 156.364432 -24.746204)
		(end 156.364432 -24.961596)
		(width 0.1524)
		(layer "In9.Cu")
		(net "M_B_CS_N0")
	)
	(segment
		(start 155.501848 -25.82418)
		(end 155.815538 -26.13787)
		(width 0.1524)
		(layer "In9.Cu")
		(net "M_B_CS_N0")
	)
	(segment
		(start 156.24683 -25.706578)
		(end 155.93314 -25.392888)
		(width 0.1524)
		(layer "In9.Cu")
		(net "M_B_CS_N0")
	)
	(segment
		(start 168.6814 -8.620506)
		(end 168.6814 -10.872724)
		(width 0.1524)
		(layer "In9.Cu")
		(net "M_B_CS_N0")
	)
	(segment
		(start 155.070556 -26.255472)
		(end 154.855164 -26.255472)
		(width 0.1524)
		(layer "In9.Cu")
		(net "M_B_CS_N0")
	)
	(segment
		(start 157.7848 -23.495)
		(end 157.615636 -23.495)
		(width 0.1524)
		(layer "In9.Cu")
		(net "M_B_CS_N0")
	)
	(segment
		(start 170.002454 -12.193778)
		(end 170.002454 -14.086332)
		(width 0.1524)
		(layer "In9.Cu")
		(net "M_B_CS_N0")
	)
	(segment
		(start 168.732962 -8.195818)
		(end 168.732962 -8.568944)
		(width 0.1524)
		(layer "In9.Cu")
		(net "M_B_CS_N0")
	)
	(segment
		(start 160.4264 -19.5326)
		(end 160.4264 -21.90369)
		(width 0.1524)
		(layer "In9.Cu")
		(net "M_B_CS_N0")
	)
	(segment
		(start 157.211014 -24.945594)
		(end 156.795724 -24.530304)
		(width 0.1524)
		(layer "In9.Cu")
		(net "M_B_CS_N0")
	)
	(segment
		(start 115.296442 -26.669746)
		(end 111.6076 -30.358588)
		(width 0.1524)
		(layer "In9.Cu")
		(net "M_B_CS_N0")
	)
	(segment
		(start 155.815538 -26.353262)
		(end 155.599638 -26.569162)
		(width 0.1524)
		(layer "In9.Cu")
		(net "M_B_CS_N0")
	)
	(segment
		(start 168.336722 -7.799578)
		(end 168.732962 -8.195818)
		(width 0.1524)
		(layer "In9.Cu")
		(net "M_B_CS_N0")
	)
	(segment
		(start 158.56839 -23.7617)
		(end 158.0515 -23.7617)
		(width 0.1524)
		(layer "In9.Cu")
		(net "M_B_CS_N0")
	)
	(segment
		(start 157.642306 -24.514302)
		(end 157.642306 -24.687784)
		(width 0.1524)
		(layer "In9.Cu")
		(net "M_B_CS_N0")
	)
	(segment
		(start 155.501848 -25.608788)
		(end 155.501848 -25.82418)
		(width 0.1524)
		(layer "In9.Cu")
		(net "M_B_CS_N0")
	)
	(segment
		(start 154.855164 -26.255472)
		(end 154.44089 -26.669746)
		(width 0.1524)
		(layer "In9.Cu")
		(net "M_B_CS_N0")
	)
	(segment
		(start 156.580332 -24.530304)
		(end 156.364432 -24.746204)
		(width 0.1524)
		(layer "In9.Cu")
		(net "M_B_CS_N0")
	)
	(segment
		(start 155.815538 -26.13787)
		(end 155.815538 -26.353262)
		(width 0.1524)
		(layer "In9.Cu")
		(net "M_B_CS_N0")
	)
	(segment
		(start 155.384246 -26.569162)
		(end 155.070556 -26.255472)
		(width 0.1524)
		(layer "In9.Cu")
		(net "M_B_CS_N0")
	)
	(segment
		(start 154.44089 -26.669746)
		(end 115.296442 -26.669746)
		(width 0.1524)
		(layer "In9.Cu")
		(net "M_B_CS_N0")
	)
	(segment
		(start 157.615636 -23.495)
		(end 157.227016 -23.88362)
		(width 0.1524)
		(layer "In9.Cu")
		(net "M_B_CS_N0")
	)
	(segment
		(start 155.93314 -25.392888)
		(end 155.717748 -25.392888)
		(width 0.1524)
		(layer "In9.Cu")
		(net "M_B_CS_N0")
	)
	(segment
		(start 168.6814 -10.872724)
		(end 170.002454 -12.193778)
		(width 0.1524)
		(layer "In9.Cu")
		(net "M_B_CS_N0")
	)
	(segment
		(start 111.6076 -30.358588)
		(end 111.6076 -30.5054)
		(width 0.1524)
		(layer "In9.Cu")
		(net "M_B_CS_N0")
	)
	(segment
		(start 168.073832 -7.797546)
		(end 168.075864 -7.799578)
		(width 0.1524)
		(layer "In9.Cu")
		(net "M_B_CS_N0")
	)
	(segment
		(start 157.384496 -24.945594)
		(end 157.211014 -24.945594)
		(width 0.1524)
		(layer "In9.Cu")
		(net "M_B_CS_N0")
	)
	(segment
		(start 168.075864 -7.799578)
		(end 168.336722 -7.799578)
		(width 0.1524)
		(layer "In9.Cu")
		(net "M_B_CS_N0")
	)
	(segment
		(start 156.678122 -25.490678)
		(end 156.462222 -25.706578)
		(width 0.1524)
		(layer "In9.Cu")
		(net "M_B_CS_N0")
	)
	(segment
		(start 156.364432 -24.961596)
		(end 156.678122 -25.275286)
		(width 0.1524)
		(layer "In9.Cu")
		(net "M_B_CS_N0")
	)
	(segment
		(start 157.642306 -24.687784)
		(end 157.384496 -24.945594)
		(width 0.1524)
		(layer "In9.Cu")
		(net "M_B_CS_N0")
	)
	(segment
		(start 155.717748 -25.392888)
		(end 155.501848 -25.608788)
		(width 0.1524)
		(layer "In9.Cu")
		(net "M_B_CS_N0")
	)
	(segment
		(start 168.732962 -8.568944)
		(end 168.6814 -8.620506)
		(width 0.1524)
		(layer "In9.Cu")
		(net "M_B_CS_N0")
	)
	(segment
		(start 156.462222 -25.706578)
		(end 156.24683 -25.706578)
		(width 0.1524)
		(layer "In9.Cu")
		(net "M_B_CS_N0")
	)
	(segment
		(start 160.8963 -19.0627)
		(end 160.4264 -19.5326)
		(width 0.1524)
		(layer "In9.Cu")
		(net "M_B_CS_N0")
	)
	(segment
		(start 155.599638 -26.569162)
		(end 155.384246 -26.569162)
		(width 0.1524)
		(layer "In9.Cu")
		(net "M_B_CS_N0")
	)
	(segment
		(start 158.0515 -23.7617)
		(end 157.7848 -23.495)
		(width 0.1524)
		(layer "In9.Cu")
		(net "M_B_CS_N0")
	)
	(segment
		(start 170.002454 -14.086332)
		(end 165.026086 -19.0627)
		(width 0.1524)
		(layer "In9.Cu")
		(net "M_B_CS_N0")
	)
	(segment
		(start 99.451668 -40.800274)
		(end 99.451668 -40.791384)
		(width 0.3048)
		(layer "F.Cu")
		(net "PVCCP")
	)
	(segment
		(start 101.051868 -40.799766)
		(end 101.421692 -41.16959)
		(width 0.3048)
		(layer "F.Cu")
		(net "PVCCP")
	)
	(segment
		(start 103.861616 -38.968934)
		(end 104.209088 -39.316406)
		(width 0.3048)
		(layer "F.Cu")
		(net "PVCCP")
	)
	(segment
		(start 102.692708 -40.256206)
		(end 102.399846 -40.256206)
		(width 0.3048)
		(layer "F.Cu")
		(net "PVCCP")
	)
	(segment
		(start 99.451668 -38.398196)
		(end 99.821492 -38.028372)
		(width 0.3048)
		(layer "F.Cu")
		(net "PVCCP")
	)
	(segment
		(start 102.692708 -38.531292)
		(end 102.381812 -38.842188)
		(width 0.3048)
		(layer "F.Cu")
		(net "PVCCP")
	)
	(segment
		(start 101.051868 -37.599366)
		(end 101.396292 -37.254942)
		(width 0.3048)
		(layer "F.Cu")
		(net "PVCCP")
	)
	(segment
		(start 118.237 -35.652202)
		(end 118.144798 -35.56)
		(width 0.381)
		(layer "F.Cu")
		(net "PVCCP")
	)
	(segment
		(start 118.144798 -35.56)
		(end 116.297202 -35.56)
		(width 0.381)
		(layer "F.Cu")
		(net "PVCCP")
	)
	(segment
		(start 101.051868 -39.999666)
		(end 101.421692 -40.36949)
		(width 0.3048)
		(layer "F.Cu")
		(net "PVCCP")
	)
	(segment
		(start 101.849428 -39.999666)
		(end 102.202742 -39.646352)
		(width 0.3048)
		(layer "F.Cu")
		(net "PVCCP")
	)
	(segment
		(start 101.051868 -40.000174)
		(end 101.051868 -39.999666)
		(width 0.3048)
		(layer "F.Cu")
		(net "PVCCP")
	)
	(segment
		(start 100.249228 -37.580316)
		(end 100.632768 -37.196776)
		(width 0.3048)
		(layer "F.Cu")
		(net "PVCCP")
	)
	(segment
		(start 101.421692 -40.36949)
		(end 101.421692 -40.37076)
		(width 0.3048)
		(layer "F.Cu")
		(net "PVCCP")
	)
	(segment
		(start 114.91214 -35.56)
		(end 116.297202 -35.56)
		(width 0.381)
		(layer "F.Cu")
		(net "PVCCP")
	)
	(segment
		(start 101.792786 -40.799766)
		(end 101.421692 -41.17086)
		(width 0.3048)
		(layer "F.Cu")
		(net "PVCCP")
	)
	(segment
		(start 101.051868 -37.599874)
		(end 101.051868 -37.599366)
		(width 0.3048)
		(layer "F.Cu")
		(net "PVCCP")
	)
	(segment
		(start 112.5982 -37.7952)
		(end 112.6236 -37.8206)
		(width 0.254)
		(layer "F.Cu")
		(net "PVCCP")
	)
	(segment
		(start 99.451668 -37.658548)
		(end 99.821492 -38.028372)
		(width 0.3048)
		(layer "F.Cu")
		(net "PVCCP")
	)
	(segment
		(start 112.6236 -37.8206)
		(end 112.7887 -37.6555)
		(width 0.381)
		(layer "F.Cu")
		(net "PVCCP")
	)
	(segment
		(start 100.249228 -38.399974)
		(end 100.249228 -38.398196)
		(width 0.3048)
		(layer "F.Cu")
		(net "PVCCP")
	)
	(segment
		(start 112.7887 -37.6555)
		(end 112.81664 -37.6555)
		(width 0.381)
		(layer "F.Cu")
		(net "PVCCP")
	)
	(segment
		(start 101.051868 -38.347396)
		(end 101.396292 -38.002972)
		(width 0.3048)
		(layer "F.Cu")
		(net "PVCCP")
	)
	(segment
		(start 99.451668 -38.399974)
		(end 99.451668 -38.398196)
		(width 0.3048)
		(layer "F.Cu")
		(net "PVCCP")
	)
	(segment
		(start 101.051868 -38.399974)
		(end 101.051868 -38.347396)
		(width 0.3048)
		(layer "F.Cu")
		(net "PVCCP")
	)
	(segment
		(start 101.849428 -39.199566)
		(end 101.849428 -39.200074)
		(width 0.3048)
		(layer "F.Cu")
		(net "PVCCP")
	)
	(segment
		(start 103.099108 -38.968934)
		(end 103.099108 -38.986714)
		(width 0.3048)
		(layer "F.Cu")
		(net "PVCCP")
	)
	(segment
		(start 77.2922 -66.7766)
		(end 77.724 -66.3448)
		(width 0.3048)
		(layer "F.Cu")
		(net "PVCCP")
	)
	(segment
		(start 101.849428 -38.399466)
		(end 102.29215 -38.842188)
		(width 0.3048)
		(layer "F.Cu")
		(net "PVCCP")
	)
	(segment
		(start 112.167162 -37.7952)
		(end 112.5982 -37.7952)
		(width 0.254)
		(layer "F.Cu")
		(net "PVCCP")
	)
	(segment
		(start 112.098328 -37.864034)
		(end 112.167162 -37.7952)
		(width 0.254)
		(layer "F.Cu")
		(net "PVCCP")
	)
	(segment
		(start 99.886516 -41.162986)
		(end 99.829112 -41.162986)
		(width 0.3048)
		(layer "F.Cu")
		(net "PVCCP")
	)
	(segment
		(start 101.421692 -41.16959)
		(end 101.421692 -41.17086)
		(width 0.3048)
		(layer "F.Cu")
		(net "PVCCP")
	)
	(segment
		(start 102.692708 -38.384734)
		(end 102.692708 -38.384226)
		(width 0.3048)
		(layer "F.Cu")
		(net "PVCCP")
	)
	(segment
		(start 99.451668 -37.599874)
		(end 99.451668 -37.658548)
		(width 0.3048)
		(layer "F.Cu")
		(net "PVCCP")
	)
	(segment
		(start 99.501706 -40.000174)
		(end 99.872292 -40.37076)
		(width 0.3048)
		(layer "F.Cu")
		(net "PVCCP")
	)
	(segment
		(start 102.29215 -38.842188)
		(end 102.381812 -38.842188)
		(width 0.3048)
		(layer "F.Cu")
		(net "PVCCP")
	)
	(segment
		(start 101.396292 -37.254942)
		(end 101.396292 -37.202872)
		(width 0.3048)
		(layer "F.Cu")
		(net "PVCCP")
	)
	(segment
		(start 103.099108 -39.669466)
		(end 102.757732 -39.32809)
		(width 0.3048)
		(layer "F.Cu")
		(net "PVCCP")
	)
	(segment
		(start 100.249228 -37.599874)
		(end 100.249228 -37.580316)
		(width 0.3048)
		(layer "F.Cu")
		(net "PVCCP")
	)
	(segment
		(start 101.849428 -40.799766)
		(end 101.792786 -40.799766)
		(width 0.3048)
		(layer "F.Cu")
		(net "PVCCP")
	)
	(segment
		(start 103.099108 -38.986714)
		(end 102.757732 -39.32809)
		(width 0.3048)
		(layer "F.Cu")
		(net "PVCCP")
	)
	(segment
		(start 99.451668 -40.791384)
		(end 99.872292 -40.37076)
		(width 0.3048)
		(layer "F.Cu")
		(net "PVCCP")
	)
	(segment
		(start 101.849428 -40.000174)
		(end 101.849428 -39.999666)
		(width 0.3048)
		(layer "F.Cu")
		(net "PVCCP")
	)
	(segment
		(start 101.051868 -40.800274)
		(end 101.051868 -40.799766)
		(width 0.3048)
		(layer "F.Cu")
		(net "PVCCP")
	)
	(segment
		(start 54.693566 -59.436)
		(end 52.324 -59.436)
		(width 0.508)
		(layer "F.Cu")
		(net "PVCCP")
	)
	(segment
		(start 101.849428 -39.200074)
		(end 101.849428 -39.258494)
		(width 0.3048)
		(layer "F.Cu")
		(net "PVCCP")
	)
	(segment
		(start 104.209088 -39.316406)
		(end 104.209088 -39.317676)
		(width 0.3048)
		(layer "F.Cu")
		(net "PVCCP")
	)
	(segment
		(start 102.399846 -40.256206)
		(end 102.23627 -40.419782)
		(width 0.3048)
		(layer "F.Cu")
		(net "PVCCP")
	)
	(segment
		(start 77.724 -66.3448)
		(end 78.232 -66.3448)
		(width 0.3048)
		(layer "F.Cu")
		(net "PVCCP")
	)
	(segment
		(start 102.202742 -39.646352)
		(end 102.202742 -39.611808)
		(width 0.3048)
		(layer "F.Cu")
		(net "PVCCP")
	)
	(segment
		(start 100.250498 -39.999666)
		(end 100.621592 -40.37076)
		(width 0.3048)
		(layer "F.Cu")
		(net "PVCCP")
	)
	(segment
		(start 103.861108 -38.968934)
		(end 103.861616 -38.968934)
		(width 0.3048)
		(layer "F.Cu")
		(net "PVCCP")
	)
	(segment
		(start 101.849428 -40.800274)
		(end 101.849428 -40.799766)
		(width 0.3048)
		(layer "F.Cu")
		(net "PVCCP")
	)
	(segment
		(start 100.249228 -40.000174)
		(end 100.249228 -39.999666)
		(width 0.3048)
		(layer "F.Cu")
		(net "PVCCP")
	)
	(segment
		(start 104.209088 -39.317676)
		(end 104.210358 -39.317676)
		(width 0.3048)
		(layer "F.Cu")
		(net "PVCCP")
	)
	(segment
		(start 100.249228 -39.999666)
		(end 100.250498 -39.999666)
		(width 0.3048)
		(layer "F.Cu")
		(net "PVCCP")
	)
	(segment
		(start 102.692708 -38.384734)
		(end 102.692708 -38.531292)
		(width 0.3048)
		(layer "F.Cu")
		(net "PVCCP")
	)
	(segment
		(start 101.849428 -38.399974)
		(end 101.849428 -38.399466)
		(width 0.3048)
		(layer "F.Cu")
		(net "PVCCP")
	)
	(segment
		(start 100.249228 -38.398196)
		(end 100.630228 -38.017196)
		(width 0.3048)
		(layer "F.Cu")
		(net "PVCCP")
	)
	(segment
		(start 103.099108 -39.669974)
		(end 103.099108 -39.669466)
		(width 0.3048)
		(layer "F.Cu")
		(net "PVCCP")
	)
	(segment
		(start 103.099108 -38.968934)
		(end 103.099108 -38.968426)
		(width 0.3048)
		(layer "F.Cu")
		(net "PVCCP")
	)
	(segment
		(start 101.849428 -39.258494)
		(end 102.202742 -39.611808)
		(width 0.3048)
		(layer "F.Cu")
		(net "PVCCP")
	)
	(segment
		(start 112.81664 -37.6555)
		(end 114.91214 -35.56)
		(width 0.381)
		(layer "F.Cu")
		(net "PVCCP")
	)
	(segment
		(start 102.692708 -40.256714)
		(end 102.692708 -40.256206)
		(width 0.3048)
		(layer "F.Cu")
		(net "PVCCP")
	)
	(segment
		(start 99.451668 -40.000174)
		(end 99.501706 -40.000174)
		(width 0.3048)
		(layer "F.Cu")
		(net "PVCCP")
	)
	(segment
		(start 100.249228 -40.800274)
		(end 99.886516 -41.162986)
		(width 0.3048)
		(layer "F.Cu")
		(net "PVCCP")
	)
	(via
		(at 57.2262 -60.7568)
		(size 0.7112)
		(drill 0.4064)
		(layers "F.Cu" "B.Cu")
		(net "PVCCP")
	)
	(via
		(at 100.621592 -40.37076)
		(size 0.4318)
		(drill 0.2032)
		(layers "F.Cu" "B.Cu")
		(net "PVCCP")
	)
	(via
		(at 104.5464 -40.5384)
		(size 0.4318)
		(drill 0.2032)
		(layers "F.Cu" "B.Cu")
		(net "PVCCP")
	)
	(via
		(at 108.8136 -39.303198)
		(size 0.4318)
		(drill 0.2032)
		(layers "F.Cu" "B.Cu")
		(net "PVCCP")
	)
	(via
		(at 62.865 -61.8363)
		(size 0.7112)
		(drill 0.4064)
		(layers "F.Cu" "B.Cu")
		(net "PVCCP")
	)
	(via
		(at 60.6806 -61.8363)
		(size 0.7112)
		(drill 0.4064)
		(layers "F.Cu" "B.Cu")
		(net "PVCCP")
	)
	(via
		(at 103.1494 -40.513)
		(size 0.4318)
		(drill 0.2032)
		(layers "F.Cu" "B.Cu")
		(net "PVCCP")
	)
	(via
		(at 59.56935 -59.6392)
		(size 0.7112)
		(drill 0.4064)
		(layers "F.Cu" "B.Cu")
		(net "PVCCP")
	)
	(via
		(at 61.7982 -59.7027)
		(size 0.7112)
		(drill 0.4064)
		(layers "F.Cu" "B.Cu")
		(net "PVCCP")
	)
	(via
		(at 102.381812 -38.842188)
		(size 0.4318)
		(drill 0.2032)
		(layers "F.Cu" "B.Cu")
		(net "PVCCP")
	)
	(via
		(at 100.6348 -38.801802)
		(size 0.4318)
		(drill 0.2032)
		(layers "F.Cu" "B.Cu")
		(net "PVCCP")
	)
	(via
		(at 100.6602 -41.1734)
		(size 0.4318)
		(drill 0.2032)
		(layers "F.Cu" "B.Cu")
		(net "PVCCP")
	)
	(via
		(at 103.7844 -40.5384)
		(size 0.4318)
		(drill 0.2032)
		(layers "F.Cu" "B.Cu")
		(net "PVCCP")
	)
	(via
		(at 104.8766 -40.0812)
		(size 0.4318)
		(drill 0.2032)
		(layers "F.Cu" "B.Cu")
		(net "PVCCP")
	)
	(via
		(at 102.38232 -37.320474)
		(size 0.4318)
		(drill 0.2032)
		(layers "F.Cu" "B.Cu")
		(net "PVCCP")
	)
	(via
		(at 59.56935 -60.7695)
		(size 0.7112)
		(drill 0.4064)
		(layers "F.Cu" "B.Cu")
		(net "PVCCP")
	)
	(via
		(at 99.829112 -41.162986)
		(size 0.4318)
		(drill 0.2032)
		(layers "F.Cu" "B.Cu")
		(net "PVCCP")
	)
	(via
		(at 110.363 -40.649398)
		(size 0.4318)
		(drill 0.2032)
		(layers "F.Cu" "B.Cu")
		(net "PVCCP")
	)
	(via
		(at 101.396292 -37.202872)
		(size 0.4318)
		(drill 0.2032)
		(layers "F.Cu" "B.Cu")
		(net "PVCCP")
	)
	(via
		(at 93.853 -60.2488)
		(size 0.508)
		(drill 0.254)
		(layers "F.Cu" "B.Cu")
		(net "PVCCP")
	)
	(via
		(at 103.505 -40.0304)
		(size 0.4318)
		(drill 0.2032)
		(layers "F.Cu" "B.Cu")
		(net "PVCCP")
	)
	(via
		(at 105.4354 -40.1574)
		(size 0.4318)
		(drill 0.2032)
		(layers "F.Cu" "B.Cu")
		(net "PVCCP")
	)
	(via
		(at 104.2416 -38.608)
		(size 0.4318)
		(drill 0.2032)
		(layers "F.Cu" "B.Cu")
		(net "PVCCP")
	)
	(via
		(at 100.632768 -37.196776)
		(size 0.4318)
		(drill 0.2032)
		(layers "F.Cu" "B.Cu")
		(net "PVCCP")
	)
	(via
		(at 93.853 -59.5884)
		(size 0.508)
		(drill 0.254)
		(layers "F.Cu" "B.Cu")
		(net "PVCCP")
	)
	(via
		(at 60.1726 -58.7502)
		(size 0.7112)
		(drill 0.3556)
		(layers "F.Cu" "B.Cu")
		(net "PVCCP")
	)
	(via
		(at 103.505 -38.6334)
		(size 0.4318)
		(drill 0.2032)
		(layers "F.Cu" "B.Cu")
		(net "PVCCP")
	)
	(via
		(at 103.4796 -39.335202)
		(size 0.4318)
		(drill 0.2032)
		(layers "F.Cu" "B.Cu")
		(net "PVCCP")
	)
	(via
		(at 111.6584 -39.0652)
		(size 0.4318)
		(drill 0.2032)
		(layers "F.Cu" "B.Cu")
		(net "PVCCP")
	)
	(via
		(at 57.2262 -59.6392)
		(size 0.7112)
		(drill 0.4064)
		(layers "F.Cu" "B.Cu")
		(net "PVCCP")
	)
	(via
		(at 59.56935 -61.8363)
		(size 0.7112)
		(drill 0.4064)
		(layers "F.Cu" "B.Cu")
		(net "PVCCP")
	)
	(via
		(at 93.853 -61.1124)
		(size 0.508)
		(drill 0.254)
		(layers "F.Cu" "B.Cu")
		(net "PVCCP")
	)
	(via
		(at 99.872292 -40.37076)
		(size 0.4318)
		(drill 0.2032)
		(layers "F.Cu" "B.Cu")
		(net "PVCCP")
	)
	(via
		(at 111.117888 -38.735254)
		(size 0.4318)
		(drill 0.2032)
		(layers "F.Cu" "B.Cu")
		(net "PVCCP")
	)
	(via
		(at 52.324 -59.436)
		(size 0.508)
		(drill 0.254)
		(layers "F.Cu" "B.Cu")
		(net "PVCCP")
	)
	(via
		(at 116.297202 -35.56)
		(size 0.7112)
		(drill 0.3556)
		(layers "F.Cu" "B.Cu")
		(net "PVCCP")
	)
	(via
		(at 99.821492 -38.028372)
		(size 0.4318)
		(drill 0.2032)
		(layers "F.Cu" "B.Cu")
		(net "PVCCP")
	)
	(via
		(at 101.421692 -40.37076)
		(size 0.4318)
		(drill 0.2032)
		(layers "F.Cu" "B.Cu")
		(net "PVCCP")
	)
	(via
		(at 63.9318 -60.7695)
		(size 0.7112)
		(drill 0.4064)
		(layers "F.Cu" "B.Cu")
		(net "PVCCP")
	)
	(via
		(at 112.6236 -37.8206)
		(size 0.4318)
		(drill 0.2032)
		(layers "F.Cu" "B.Cu")
		(net "PVCCP")
	)
	(via
		(at 110.617 -39.751)
		(size 0.7112)
		(drill 0.3556)
		(layers "F.Cu" "B.Cu")
		(net "PVCCP")
	)
	(via
		(at 60.68695 -60.7568)
		(size 0.7112)
		(drill 0.4064)
		(layers "F.Cu" "B.Cu")
		(net "PVCCP")
	)
	(via
		(at 93.853 -61.976)
		(size 0.508)
		(drill 0.254)
		(layers "F.Cu" "B.Cu")
		(net "PVCCP")
	)
	(via
		(at 61.7982 -61.8363)
		(size 0.7112)
		(drill 0.4064)
		(layers "F.Cu" "B.Cu")
		(net "PVCCP")
	)
	(via
		(at 102.23627 -40.419782)
		(size 0.4318)
		(drill 0.2032)
		(layers "F.Cu" "B.Cu")
		(net "PVCCP")
	)
	(via
		(at 58.3438 -59.6138)
		(size 0.7112)
		(drill 0.4064)
		(layers "F.Cu" "B.Cu")
		(net "PVCCP")
	)
	(via
		(at 60.68695 -59.69)
		(size 0.7112)
		(drill 0.4064)
		(layers "F.Cu" "B.Cu")
		(net "PVCCP")
	)
	(via
		(at 62.865 -59.7027)
		(size 0.7112)
		(drill 0.4064)
		(layers "F.Cu" "B.Cu")
		(net "PVCCP")
	)
	(via
		(at 101.4222 -39.614602)
		(size 0.4318)
		(drill 0.2032)
		(layers "F.Cu" "B.Cu")
		(net "PVCCP")
	)
	(via
		(at 99.822 -38.776402)
		(size 0.4318)
		(drill 0.2032)
		(layers "F.Cu" "B.Cu")
		(net "PVCCP")
	)
	(via
		(at 102.202742 -39.611808)
		(size 0.4318)
		(drill 0.2032)
		(layers "F.Cu" "B.Cu")
		(net "PVCCP")
	)
	(via
		(at 101.421692 -41.17086)
		(size 0.4318)
		(drill 0.2032)
		(layers "F.Cu" "B.Cu")
		(net "PVCCP")
	)
	(via
		(at 77.2922 -66.7766)
		(size 0.508)
		(drill 0.254)
		(layers "F.Cu" "B.Cu")
		(net "PVCCP")
	)
	(via
		(at 58.33745 -60.706)
		(size 0.7112)
		(drill 0.4064)
		(layers "F.Cu" "B.Cu")
		(net "PVCCP")
	)
	(via
		(at 102.3366 -38.014402)
		(size 0.4318)
		(drill 0.2032)
		(layers "F.Cu" "B.Cu")
		(net "PVCCP")
	)
	(via
		(at 102.757732 -39.32809)
		(size 0.4318)
		(drill 0.2032)
		(layers "F.Cu" "B.Cu")
		(net "PVCCP")
	)
	(via
		(at 100.630228 -38.017196)
		(size 0.4318)
		(drill 0.2032)
		(layers "F.Cu" "B.Cu")
		(net "PVCCP")
	)
	(via
		(at 65.6336 -58.3692)
		(size 0.7112)
		(drill 0.3556)
		(layers "F.Cu" "B.Cu")
		(net "PVCCP")
	)
	(via
		(at 108.077 -39.303198)
		(size 0.4318)
		(drill 0.2032)
		(layers "F.Cu" "B.Cu")
		(net "PVCCP")
	)
	(via
		(at 61.7982 -60.7695)
		(size 0.7112)
		(drill 0.4064)
		(layers "F.Cu" "B.Cu")
		(net "PVCCP")
	)
	(via
		(at 101.4222 -38.827202)
		(size 0.4318)
		(drill 0.2032)
		(layers "F.Cu" "B.Cu")
		(net "PVCCP")
	)
	(via
		(at 63.9318 -61.8363)
		(size 0.7112)
		(drill 0.4064)
		(layers "F.Cu" "B.Cu")
		(net "PVCCP")
	)
	(via
		(at 104.209088 -39.317676)
		(size 0.4318)
		(drill 0.2032)
		(layers "F.Cu" "B.Cu")
		(net "PVCCP")
	)
	(via
		(at 65.278 -61.595)
		(size 0.7112)
		(drill 0.3556)
		(layers "F.Cu" "B.Cu")
		(net "PVCCP")
	)
	(via
		(at 57.2262 -61.8236)
		(size 0.7112)
		(drill 0.4064)
		(layers "F.Cu" "B.Cu")
		(net "PVCCP")
	)
	(via
		(at 62.865 -60.7695)
		(size 0.7112)
		(drill 0.4064)
		(layers "F.Cu" "B.Cu")
		(net "PVCCP")
	)
	(via
		(at 101.396292 -38.002972)
		(size 0.4318)
		(drill 0.2032)
		(layers "F.Cu" "B.Cu")
		(net "PVCCP")
	)
	(via
		(at 58.35015 -61.8363)
		(size 0.7112)
		(drill 0.4064)
		(layers "F.Cu" "B.Cu")
		(net "PVCCP")
	)
	(via
		(at 105.7656 -39.37)
		(size 0.4318)
		(drill 0.2032)
		(layers "F.Cu" "B.Cu")
		(net "PVCCP")
	)
	(via
		(at 103.124 -38.1508)
		(size 0.4318)
		(drill 0.2032)
		(layers "F.Cu" "B.Cu")
		(net "PVCCP")
	)
	(segment
		(start 52.2478 -58.547)
		(end 52.2478 -59.3598)
		(width 0.508)
		(layer "B.Cu")
		(net "PVCCP")
	)
	(segment
		(start 52.2478 -59.3598)
		(end 52.324 -59.436)
		(width 0.508)
		(layer "B.Cu")
		(net "PVCCP")
	)
	(segment
		(start 73.401936 -69.342)
		(end 74.417936 -68.326)
		(width 0.3048)
		(layer "In4.Cu")
		(net "PVCCP")
	)
	(segment
		(start 70.358 -69.342)
		(end 73.401936 -69.342)
		(width 0.3048)
		(layer "In4.Cu")
		(net "PVCCP")
	)
	(segment
		(start 74.417936 -68.326)
		(end 75.9968 -68.326)
		(width 0.3048)
		(layer "In4.Cu")
		(net "PVCCP")
	)
	(segment
		(start 77.2922 -67.0306)
		(end 77.2922 -66.7766)
		(width 0.3048)
		(layer "In4.Cu")
		(net "PVCCP")
	)
	(segment
		(start 75.9968 -68.326)
		(end 77.2922 -67.0306)
		(width 0.3048)
		(layer "In4.Cu")
		(net "PVCCP")
	)
	(segment
		(start 66.294 -62.865)
		(end 66.294 -65.278)
		(width 0.3048)
		(layer "In4.Cu")
		(net "PVCCP")
	)
	(segment
		(start 66.294 -65.278)
		(end 70.358 -69.342)
		(width 0.3048)
		(layer "In4.Cu")
		(net "PVCCP")
	)
	(segment
		(start 108.7374 -29.591)
		(end 108.263182 -29.591)
		(width 0.1016)
		(layer "F.Cu")
		(net "M_B_CK_DN1")
	)
	(segment
		(start 108.263182 -29.591)
		(end 108.237528 -29.616654)
		(width 0.1016)
		(layer "F.Cu")
		(net "M_B_CK_DN1")
	)
	(via
		(at 108.7374 -29.591)
		(size 0.4318)
		(drill 0.2032)
		(layers "F.Cu" "B.Cu")
		(net "M_B_CK_DN1")
	)
	(via
		(at 164.7952 -3.227578)
		(size 0.4318)
		(drill 0.2032)
		(layers "F.Cu" "B.Cu")
		(net "M_B_CK_DN1")
	)
	(segment
		(start 164.494464 -2.975356)
		(end 164.746686 -3.227578)
		(width 0.2159)
		(layer "B.Cu")
		(net "M_B_CK_DN1")
	)
	(segment
		(start 164.649912 -2.442464)
		(end 164.494464 -2.597912)
		(width 0.2159)
		(layer "B.Cu")
		(net "M_B_CK_DN1")
	)
	(segment
		(start 164.746686 -3.227578)
		(end 164.7952 -3.227578)
		(width 0.2159)
		(layer "B.Cu")
		(net "M_B_CK_DN1")
	)
	(segment
		(start 164.494464 -2.597912)
		(end 164.494464 -2.975356)
		(width 0.2159)
		(layer "B.Cu")
		(net "M_B_CK_DN1")
	)
	(segment
		(start 164.649912 -1.690624)
		(end 164.649912 -2.442464)
		(width 0.2159)
		(layer "B.Cu")
		(net "M_B_CK_DN1")
	)
	(segment
		(start 118.188232 -24.059896)
		(end 117.13464 -24.059896)
		(width 0.1905)
		(layer "In9.Cu")
		(net "M_B_CK_DN1")
	)
	(segment
		(start 155.956 -19.1389)
		(end 155.3083 -19.7866)
		(width 0.1905)
		(layer "In9.Cu")
		(net "M_B_CK_DN1")
	)
	(segment
		(start 111.047784 -27.58821)
		(end 111.047784 -27.013662)
		(width 0.1016)
		(layer "In9.Cu")
		(net "M_B_CK_DN1")
	)
	(segment
		(start 114.174016 -24.059896)
		(end 112.202468 -26.031444)
		(width 0.1905)
		(layer "In9.Cu")
		(net "M_B_CK_DN1")
	)
	(segment
		(start 109.280198 -29.12237)
		(end 109.513624 -29.12237)
		(width 0.1016)
		(layer "In9.Cu")
		(net "M_B_CK_DN1")
	)
	(segment
		(start 111.047784 -27.013662)
		(end 112.030002 -26.031444)
		(width 0.1016)
		(layer "In9.Cu")
		(net "M_B_CK_DN1")
	)
	(segment
		(start 166.8018 -13.5128)
		(end 166.1287 -13.5128)
		(width 0.1905)
		(layer "In9.Cu")
		(net "M_B_CK_DN1")
	)
	(segment
		(start 163.6268 -16.2814)
		(end 159.9692 -16.2814)
		(width 0.1905)
		(layer "In9.Cu")
		(net "M_B_CK_DN1")
	)
	(segment
		(start 165.1508 -5.665978)
		(end 166.66845 -7.183628)
		(width 0.1905)
		(layer "In9.Cu")
		(net "M_B_CK_DN1")
	)
	(segment
		(start 116.920518 -23.845774)
		(end 116.651278 -23.845774)
		(width 0.1905)
		(layer "In9.Cu")
		(net "M_B_CK_DN1")
	)
	(segment
		(start 166.66845 -7.183628)
		(end 166.66845 -10.592562)
		(width 0.1905)
		(layer "In9.Cu")
		(net "M_B_CK_DN1")
	)
	(segment
		(start 165.1508 -3.54203)
		(end 165.1508 -5.665978)
		(width 0.1905)
		(layer "In9.Cu")
		(net "M_B_CK_DN1")
	)
	(segment
		(start 109.513624 -29.12237)
		(end 111.047784 -27.58821)
		(width 0.1016)
		(layer "In9.Cu")
		(net "M_B_CK_DN1")
	)
	(segment
		(start 108.811568 -29.591)
		(end 109.280198 -29.12237)
		(width 0.1016)
		(layer "In9.Cu")
		(net "M_B_CK_DN1")
	)
	(segment
		(start 155.3083 -19.7866)
		(end 155.3083 -20.9423)
		(width 0.1905)
		(layer "In9.Cu")
		(net "M_B_CK_DN1")
	)
	(segment
		(start 119.386096 -23.624032)
		(end 118.624096 -23.624032)
		(width 0.1905)
		(layer "In9.Cu")
		(net "M_B_CK_DN1")
	)
	(segment
		(start 166.1287 -13.5128)
		(end 165.6461 -13.9954)
		(width 0.1905)
		(layer "In9.Cu")
		(net "M_B_CK_DN1")
	)
	(segment
		(start 167.3479 -11.272012)
		(end 167.3479 -12.9667)
		(width 0.1905)
		(layer "In9.Cu")
		(net "M_B_CK_DN1")
	)
	(segment
		(start 164.7952 -3.227578)
		(end 164.836348 -3.227578)
		(width 0.1905)
		(layer "In9.Cu")
		(net "M_B_CK_DN1")
	)
	(segment
		(start 117.13464 -24.059896)
		(end 116.920518 -23.845774)
		(width 0.1905)
		(layer "In9.Cu")
		(net "M_B_CK_DN1")
	)
	(segment
		(start 108.7374 -29.591)
		(end 108.811568 -29.591)
		(width 0.1016)
		(layer "In9.Cu")
		(net "M_B_CK_DN1")
	)
	(segment
		(start 157.1117 -19.1389)
		(end 155.956 -19.1389)
		(width 0.1905)
		(layer "In9.Cu")
		(net "M_B_CK_DN1")
	)
	(segment
		(start 166.66845 -10.592562)
		(end 167.3479 -11.272012)
		(width 0.1905)
		(layer "In9.Cu")
		(net "M_B_CK_DN1")
	)
	(segment
		(start 164.836348 -3.227578)
		(end 165.1508 -3.54203)
		(width 0.1905)
		(layer "In9.Cu")
		(net "M_B_CK_DN1")
	)
	(segment
		(start 167.3479 -12.9667)
		(end 166.8018 -13.5128)
		(width 0.1905)
		(layer "In9.Cu")
		(net "M_B_CK_DN1")
	)
	(segment
		(start 119.82196 -24.059896)
		(end 119.386096 -23.624032)
		(width 0.1905)
		(layer "In9.Cu")
		(net "M_B_CK_DN1")
	)
	(segment
		(start 112.030002 -26.031444)
		(end 112.202468 -26.031444)
		(width 0.1016)
		(layer "In9.Cu")
		(net "M_B_CK_DN1")
	)
	(segment
		(start 165.6461 -14.2621)
		(end 163.6268 -16.2814)
		(width 0.1905)
		(layer "In9.Cu")
		(net "M_B_CK_DN1")
	)
	(segment
		(start 116.437156 -24.059896)
		(end 114.174016 -24.059896)
		(width 0.1905)
		(layer "In9.Cu")
		(net "M_B_CK_DN1")
	)
	(segment
		(start 116.651278 -23.845774)
		(end 116.437156 -24.059896)
		(width 0.1905)
		(layer "In9.Cu")
		(net "M_B_CK_DN1")
	)
	(segment
		(start 165.6461 -13.9954)
		(end 165.6461 -14.2621)
		(width 0.1905)
		(layer "In9.Cu")
		(net "M_B_CK_DN1")
	)
	(segment
		(start 152.190704 -24.059896)
		(end 119.82196 -24.059896)
		(width 0.1905)
		(layer "In9.Cu")
		(net "M_B_CK_DN1")
	)
	(segment
		(start 118.624096 -23.624032)
		(end 118.188232 -24.059896)
		(width 0.1905)
		(layer "In9.Cu")
		(net "M_B_CK_DN1")
	)
	(segment
		(start 159.9692 -16.2814)
		(end 157.1117 -19.1389)
		(width 0.1905)
		(layer "In9.Cu")
		(net "M_B_CK_DN1")
	)
	(segment
		(start 155.3083 -20.9423)
		(end 152.190704 -24.059896)
		(width 0.1905)
		(layer "In9.Cu")
		(net "M_B_CK_DN1")
	)
	(segment
		(start 85.933788 -44.689014)
		(end 85.933788 -44.708064)
		(width 0.1143)
		(layer "F.Cu")
		(net "SVID_DATA_R")
	)
	(segment
		(start 85.933788 -44.708064)
		(end 85.57641 -45.065442)
		(width 0.1143)
		(layer "F.Cu")
		(net "SVID_DATA_R")
	)
	(via
		(at 80.53324 -51.435)
		(size 0.7112)
		(drill 0.3556)
		(layers "F.Cu" "B.Cu")
		(net "SVID_DATA_R")
	)
	(via
		(at 85.57641 -45.065442)
		(size 0.4318)
		(drill 0.2032)
		(layers "F.Cu" "B.Cu")
		(net "SVID_DATA_R")
	)
	(segment
		(start 78.07325 -60.560966)
		(end 78.07325 -60.07735)
		(width 0.1143)
		(layer "B.Cu")
		(net "SVID_DATA_R")
	)
	(segment
		(start 80.853026 -49.941988)
		(end 80.853026 -48.255174)
		(width 0.1143)
		(layer "B.Cu")
		(net "SVID_DATA_R")
	)
	(segment
		(start 79.234284 -61.722)
		(end 78.07325 -60.560966)
		(width 0.1143)
		(layer "B.Cu")
		(net "SVID_DATA_R")
	)
	(segment
		(start 80.53324 -50.261774)
		(end 80.853026 -49.941988)
		(width 0.1143)
		(layer "B.Cu")
		(net "SVID_DATA_R")
	)
	(segment
		(start 82.532982 -46.575218)
		(end 82.532982 -46.146974)
		(width 0.1143)
		(layer "B.Cu")
		(net "SVID_DATA_R")
	)
	(segment
		(start 80.53324 -53.12156)
		(end 80.53324 -51.435)
		(width 0.1143)
		(layer "B.Cu")
		(net "SVID_DATA_R")
	)
	(segment
		(start 80.53324 -51.435)
		(end 80.53324 -50.261774)
		(width 0.1143)
		(layer "B.Cu")
		(net "SVID_DATA_R")
	)
	(segment
		(start 81.026 -62.484)
		(end 80.264 -61.722)
		(width 0.1143)
		(layer "B.Cu")
		(net "SVID_DATA_R")
	)
	(segment
		(start 82.532982 -46.146974)
		(end 83.106006 -45.57395)
		(width 0.1143)
		(layer "B.Cu")
		(net "SVID_DATA_R")
	)
	(segment
		(start 85.067648 -45.57395)
		(end 85.57641 -45.065442)
		(width 0.1143)
		(layer "B.Cu")
		(net "SVID_DATA_R")
	)
	(segment
		(start 81.026 -62.8142)
		(end 81.026 -62.484)
		(width 0.1143)
		(layer "B.Cu")
		(net "SVID_DATA_R")
	)
	(segment
		(start 80.264 -61.722)
		(end 79.234284 -61.722)
		(width 0.1143)
		(layer "B.Cu")
		(net "SVID_DATA_R")
	)
	(segment
		(start 80.0862 -53.5686)
		(end 80.53324 -53.12156)
		(width 0.1143)
		(layer "B.Cu")
		(net "SVID_DATA_R")
	)
	(segment
		(start 78.07325 -60.07735)
		(end 80.0862 -58.0644)
		(width 0.1143)
		(layer "B.Cu")
		(net "SVID_DATA_R")
	)
	(segment
		(start 80.0862 -58.0644)
		(end 80.0862 -53.5686)
		(width 0.1143)
		(layer "B.Cu")
		(net "SVID_DATA_R")
	)
	(segment
		(start 80.853026 -48.255174)
		(end 82.532982 -46.575218)
		(width 0.1143)
		(layer "B.Cu")
		(net "SVID_DATA_R")
	)
	(segment
		(start 83.106006 -45.57395)
		(end 85.067648 -45.57395)
		(width 0.1143)
		(layer "B.Cu")
		(net "SVID_DATA_R")
	)
	(segment
		(start 108.6866 -29.0322)
		(end 108.415074 -29.0322)
		(width 0.1016)
		(layer "F.Cu")
		(net "M_B_CK_DP1")
	)
	(segment
		(start 108.415074 -29.0322)
		(end 108.237528 -28.854654)
		(width 0.1016)
		(layer "F.Cu")
		(net "M_B_CK_DP1")
	)
	(via
		(at 108.6866 -29.0322)
		(size 0.4318)
		(drill 0.2032)
		(layers "F.Cu" "B.Cu")
		(net "M_B_CK_DP1")
	)
	(via
		(at 164.6936 -3.93446)
		(size 0.4318)
		(drill 0.2032)
		(layers "F.Cu" "B.Cu")
		(net "M_B_CK_DP1")
	)
	(segment
		(start 164.126164 -2.592578)
		(end 164.126164 -3.367024)
		(width 0.2159)
		(layer "B.Cu")
		(net "M_B_CK_DP1")
	)
	(segment
		(start 164.049964 -2.516378)
		(end 164.126164 -2.592578)
		(width 0.2159)
		(layer "B.Cu")
		(net "M_B_CK_DP1")
	)
	(segment
		(start 164.126164 -3.367024)
		(end 164.6936 -3.93446)
		(width 0.2159)
		(layer "B.Cu")
		(net "M_B_CK_DP1")
	)
	(segment
		(start 164.049964 -1.690624)
		(end 164.049964 -2.516378)
		(width 0.2159)
		(layer "B.Cu")
		(net "M_B_CK_DP1")
	)
	(segment
		(start 116.284756 -23.640796)
		(end 115.713256 -23.640796)
		(width 0.1905)
		(layer "In9.Cu")
		(net "M_B_CK_DP1")
	)
	(segment
		(start 118.014496 -23.640796)
		(end 117.308376 -23.640796)
		(width 0.1905)
		(layer "In9.Cu")
		(net "M_B_CK_DP1")
	)
	(segment
		(start 118.45036 -23.204932)
		(end 118.014496 -23.640796)
		(width 0.1905)
		(layer "In9.Cu")
		(net "M_B_CK_DP1")
	)
	(segment
		(start 109.19587 -28.91917)
		(end 109.02442 -29.09062)
		(width 0.1016)
		(layer "In9.Cu")
		(net "M_B_CK_DP1")
	)
	(segment
		(start 114.00028 -23.640796)
		(end 111.90605 -25.735026)
		(width 0.1905)
		(layer "In9.Cu")
		(net "M_B_CK_DP1")
	)
	(segment
		(start 154.8892 -20.768564)
		(end 152.016968 -23.640796)
		(width 0.1905)
		(layer "In9.Cu")
		(net "M_B_CK_DP1")
	)
	(segment
		(start 166.628064 -13.0937)
		(end 165.954964 -13.0937)
		(width 0.1905)
		(layer "In9.Cu")
		(net "M_B_CK_DP1")
	)
	(segment
		(start 108.74502 -29.09062)
		(end 108.6866 -29.0322)
		(width 0.1016)
		(layer "In9.Cu")
		(net "M_B_CK_DP1")
	)
	(segment
		(start 116.510816 -23.414736)
		(end 116.284756 -23.640796)
		(width 0.1905)
		(layer "In9.Cu")
		(net "M_B_CK_DP1")
	)
	(segment
		(start 114.689636 -23.640796)
		(end 114.00028 -23.640796)
		(width 0.1905)
		(layer "In9.Cu")
		(net "M_B_CK_DP1")
	)
	(segment
		(start 164.6936 -3.93446)
		(end 164.7317 -3.97256)
		(width 0.1905)
		(layer "In9.Cu")
		(net "M_B_CK_DP1")
	)
	(segment
		(start 165.227 -14.088364)
		(end 163.453064 -15.8623)
		(width 0.1905)
		(layer "In9.Cu")
		(net "M_B_CK_DP1")
	)
	(segment
		(start 166.3192 -10.836148)
		(end 166.9288 -11.445748)
		(width 0.1905)
		(layer "In9.Cu")
		(net "M_B_CK_DP1")
	)
	(segment
		(start 111.896906 -25.877012)
		(end 110.844584 -26.929334)
		(width 0.1016)
		(layer "In9.Cu")
		(net "M_B_CK_DP1")
	)
	(segment
		(start 166.3192 -7.427214)
		(end 166.3192 -10.836148)
		(width 0.1905)
		(layer "In9.Cu")
		(net "M_B_CK_DP1")
	)
	(segment
		(start 109.429296 -28.91917)
		(end 109.19587 -28.91917)
		(width 0.1016)
		(layer "In9.Cu")
		(net "M_B_CK_DP1")
	)
	(segment
		(start 152.016968 -23.640796)
		(end 148.924264 -23.640796)
		(width 0.1905)
		(layer "In9.Cu")
		(net "M_B_CK_DP1")
	)
	(segment
		(start 129.266696 -23.414736)
		(end 128.695196 -23.414736)
		(width 0.1905)
		(layer "In9.Cu")
		(net "M_B_CK_DP1")
	)
	(segment
		(start 110.844584 -26.929334)
		(end 110.844584 -27.503882)
		(width 0.1016)
		(layer "In9.Cu")
		(net "M_B_CK_DP1")
	)
	(segment
		(start 128.469136 -23.640796)
		(end 119.995696 -23.640796)
		(width 0.1905)
		(layer "In9.Cu")
		(net "M_B_CK_DP1")
	)
	(segment
		(start 129.492756 -23.640796)
		(end 129.266696 -23.414736)
		(width 0.1905)
		(layer "In9.Cu")
		(net "M_B_CK_DP1")
	)
	(segment
		(start 119.995696 -23.640796)
		(end 119.559832 -23.204932)
		(width 0.1905)
		(layer "In9.Cu")
		(net "M_B_CK_DP1")
	)
	(segment
		(start 164.7317 -3.97256)
		(end 164.7317 -5.839714)
		(width 0.1905)
		(layer "In9.Cu")
		(net "M_B_CK_DP1")
	)
	(segment
		(start 128.695196 -23.414736)
		(end 128.469136 -23.640796)
		(width 0.1905)
		(layer "In9.Cu")
		(net "M_B_CK_DP1")
	)
	(segment
		(start 156.937964 -18.7198)
		(end 155.782264 -18.7198)
		(width 0.1905)
		(layer "In9.Cu")
		(net "M_B_CK_DP1")
	)
	(segment
		(start 115.713256 -23.640796)
		(end 115.487196 -23.414736)
		(width 0.1905)
		(layer "In9.Cu")
		(net "M_B_CK_DP1")
	)
	(segment
		(start 165.954964 -13.0937)
		(end 165.227 -13.821664)
		(width 0.1905)
		(layer "In9.Cu")
		(net "M_B_CK_DP1")
	)
	(segment
		(start 109.02442 -29.09062)
		(end 108.74502 -29.09062)
		(width 0.1016)
		(layer "In9.Cu")
		(net "M_B_CK_DP1")
	)
	(segment
		(start 166.9288 -11.445748)
		(end 166.9288 -12.792964)
		(width 0.1905)
		(layer "In9.Cu")
		(net "M_B_CK_DP1")
	)
	(segment
		(start 164.7317 -5.839714)
		(end 166.3192 -7.427214)
		(width 0.1905)
		(layer "In9.Cu")
		(net "M_B_CK_DP1")
	)
	(segment
		(start 155.782264 -18.7198)
		(end 154.8892 -19.612864)
		(width 0.1905)
		(layer "In9.Cu")
		(net "M_B_CK_DP1")
	)
	(segment
		(start 165.227 -13.821664)
		(end 165.227 -14.088364)
		(width 0.1905)
		(layer "In9.Cu")
		(net "M_B_CK_DP1")
	)
	(segment
		(start 119.559832 -23.204932)
		(end 118.45036 -23.204932)
		(width 0.1905)
		(layer "In9.Cu")
		(net "M_B_CK_DP1")
	)
	(segment
		(start 147.900644 -23.640796)
		(end 129.492756 -23.640796)
		(width 0.1905)
		(layer "In9.Cu")
		(net "M_B_CK_DP1")
	)
	(segment
		(start 111.896906 -25.74417)
		(end 111.896906 -25.877012)
		(width 0.1016)
		(layer "In9.Cu")
		(net "M_B_CK_DP1")
	)
	(segment
		(start 114.915696 -23.414736)
		(end 114.689636 -23.640796)
		(width 0.1905)
		(layer "In9.Cu")
		(net "M_B_CK_DP1")
	)
	(segment
		(start 154.8892 -19.612864)
		(end 154.8892 -20.768564)
		(width 0.1905)
		(layer "In9.Cu")
		(net "M_B_CK_DP1")
	)
	(segment
		(start 148.698204 -23.414736)
		(end 148.126704 -23.414736)
		(width 0.1905)
		(layer "In9.Cu")
		(net "M_B_CK_DP1")
	)
	(segment
		(start 148.126704 -23.414736)
		(end 147.900644 -23.640796)
		(width 0.1905)
		(layer "In9.Cu")
		(net "M_B_CK_DP1")
	)
	(segment
		(start 166.9288 -12.792964)
		(end 166.628064 -13.0937)
		(width 0.1905)
		(layer "In9.Cu")
		(net "M_B_CK_DP1")
	)
	(segment
		(start 111.90605 -25.735026)
		(end 111.896906 -25.74417)
		(width 0.1016)
		(layer "In9.Cu")
		(net "M_B_CK_DP1")
	)
	(segment
		(start 163.453064 -15.8623)
		(end 159.795464 -15.8623)
		(width 0.1905)
		(layer "In9.Cu")
		(net "M_B_CK_DP1")
	)
	(segment
		(start 115.487196 -23.414736)
		(end 114.915696 -23.414736)
		(width 0.1905)
		(layer "In9.Cu")
		(net "M_B_CK_DP1")
	)
	(segment
		(start 117.308376 -23.640796)
		(end 117.082316 -23.414736)
		(width 0.1905)
		(layer "In9.Cu")
		(net "M_B_CK_DP1")
	)
	(segment
		(start 117.082316 -23.414736)
		(end 116.510816 -23.414736)
		(width 0.1905)
		(layer "In9.Cu")
		(net "M_B_CK_DP1")
	)
	(segment
		(start 159.795464 -15.8623)
		(end 156.937964 -18.7198)
		(width 0.1905)
		(layer "In9.Cu")
		(net "M_B_CK_DP1")
	)
	(segment
		(start 110.844584 -27.503882)
		(end 109.429296 -28.91917)
		(width 0.1016)
		(layer "In9.Cu")
		(net "M_B_CK_DP1")
	)
	(segment
		(start 148.924264 -23.640796)
		(end 148.698204 -23.414736)
		(width 0.1905)
		(layer "In9.Cu")
		(net "M_B_CK_DP1")
	)
	(segment
		(start 82.504788 -46.675294)
		(end 82.877914 -46.302168)
		(width 0.1143)
		(layer "F.Cu")
		(net "SVID_CLK_R")
	)
	(segment
		(start 82.877914 -46.302168)
		(end 82.907632 -46.302168)
		(width 0.1143)
		(layer "F.Cu")
		(net "SVID_CLK_R")
	)
	(via
		(at 81.133442 -58.058558)
		(size 0.7112)
		(drill 0.3556)
		(layers "F.Cu" "B.Cu")
		(net "SVID_CLK_R")
	)
	(via
		(at 82.907632 -46.302168)
		(size 0.4318)
		(drill 0.2032)
		(layers "F.Cu" "B.Cu")
		(net "SVID_CLK_R")
	)
	(segment
		(start 79.22895 -59.96305)
		(end 81.133442 -58.058558)
		(width 0.1143)
		(layer "B.Cu")
		(net "SVID_CLK_R")
	)
	(segment
		(start 81.5848 -57.6072)
		(end 81.5848 -54.3052)
		(width 0.1143)
		(layer "B.Cu")
		(net "SVID_CLK_R")
	)
	(segment
		(start 81.915 -62.8142)
		(end 81.915 -61.1378)
		(width 0.1143)
		(layer "B.Cu")
		(net "SVID_CLK_R")
	)
	(segment
		(start 83.1596 -47.28464)
		(end 83.312 -47.13224)
		(width 0.1143)
		(layer "B.Cu")
		(net "SVID_CLK_R")
	)
	(segment
		(start 82.39125 -49.403)
		(end 81.808574 -49.403)
		(width 0.1143)
		(layer "B.Cu")
		(net "SVID_CLK_R")
	)
	(segment
		(start 82.804 -54.0004)
		(end 82.804 -52.2732)
		(width 0.1143)
		(layer "B.Cu")
		(net "SVID_CLK_R")
	)
	(segment
		(start 81.5848 -54.3052)
		(end 81.7372 -54.1528)
		(width 0.1143)
		(layer "B.Cu")
		(net "SVID_CLK_R")
	)
	(segment
		(start 83.312 -46.454568)
		(end 83.1596 -46.302168)
		(width 0.1143)
		(layer "B.Cu")
		(net "SVID_CLK_R")
	)
	(segment
		(start 82.0674 -51.1302)
		(end 82.54365 -50.65395)
		(width 0.1143)
		(layer "B.Cu")
		(net "SVID_CLK_R")
	)
	(segment
		(start 82.54365 -49.5554)
		(end 82.39125 -49.403)
		(width 0.1143)
		(layer "B.Cu")
		(net "SVID_CLK_R")
	)
	(segment
		(start 83.312 -47.13224)
		(end 83.312 -46.454568)
		(width 0.1143)
		(layer "B.Cu")
		(net "SVID_CLK_R")
	)
	(segment
		(start 81.7372 -54.1528)
		(end 82.6516 -54.1528)
		(width 0.1143)
		(layer "B.Cu")
		(net "SVID_CLK_R")
	)
	(segment
		(start 81.915 -61.1378)
		(end 81.7626 -60.9854)
		(width 0.1143)
		(layer "B.Cu")
		(net "SVID_CLK_R")
	)
	(segment
		(start 81.656174 -47.837852)
		(end 82.209386 -47.28464)
		(width 0.1143)
		(layer "B.Cu")
		(net "SVID_CLK_R")
	)
	(segment
		(start 79.22895 -60.833)
		(end 79.22895 -59.96305)
		(width 0.1143)
		(layer "B.Cu")
		(net "SVID_CLK_R")
	)
	(segment
		(start 82.209386 -47.28464)
		(end 83.1596 -47.28464)
		(width 0.1143)
		(layer "B.Cu")
		(net "SVID_CLK_R")
	)
	(segment
		(start 81.7626 -60.9854)
		(end 79.38135 -60.9854)
		(width 0.1143)
		(layer "B.Cu")
		(net "SVID_CLK_R")
	)
	(segment
		(start 82.54365 -50.65395)
		(end 82.54365 -49.5554)
		(width 0.1143)
		(layer "B.Cu")
		(net "SVID_CLK_R")
	)
	(segment
		(start 83.1596 -46.302168)
		(end 82.907632 -46.302168)
		(width 0.1143)
		(layer "B.Cu")
		(net "SVID_CLK_R")
	)
	(segment
		(start 82.0674 -51.5366)
		(end 82.0674 -51.1302)
		(width 0.1143)
		(layer "B.Cu")
		(net "SVID_CLK_R")
	)
	(segment
		(start 81.808574 -49.403)
		(end 81.656174 -49.2506)
		(width 0.1143)
		(layer "B.Cu")
		(net "SVID_CLK_R")
	)
	(segment
		(start 82.804 -52.2732)
		(end 82.0674 -51.5366)
		(width 0.1143)
		(layer "B.Cu")
		(net "SVID_CLK_R")
	)
	(segment
		(start 81.656174 -49.2506)
		(end 81.656174 -47.837852)
		(width 0.1143)
		(layer "B.Cu")
		(net "SVID_CLK_R")
	)
	(segment
		(start 82.6516 -54.1528)
		(end 82.804 -54.0004)
		(width 0.1143)
		(layer "B.Cu")
		(net "SVID_CLK_R")
	)
	(segment
		(start 79.38135 -60.9854)
		(end 79.22895 -60.833)
		(width 0.1143)
		(layer "B.Cu")
		(net "SVID_CLK_R")
	)
	(segment
		(start 81.133442 -58.058558)
		(end 81.5848 -57.6072)
		(width 0.1143)
		(layer "B.Cu")
		(net "SVID_CLK_R")
	)
	(segment
		(start 189.55004 -10.638282)
		(end 188.375544 -11.812778)
		(width 0.1143)
		(layer "B.Cu")
		(net "CHB_0_SA0")
	)
	(segment
		(start 188.375544 -11.812778)
		(end 188.341 -11.812778)
		(width 0.1143)
		(layer "B.Cu")
		(net "CHB_0_SA0")
	)
	(segment
		(start 189.55004 -9.89076)
		(end 189.55004 -10.638282)
		(width 0.1143)
		(layer "B.Cu")
		(net "CHB_0_SA0")
	)
	(segment
		(start 187.5028 -11.812778)
		(end 188.341 -11.812778)
		(width 0.1143)
		(layer "B.Cu")
		(net "CHB_0_SA0")
	)
	(segment
		(start 18.9992 -49.0474)
		(end 18.7706 -49.276)
		(width 0.2032)
		(layer "F.Cu")
		(net "VR_PVCCP_VSEN_R")
	)
	(segment
		(start 18.9992 -48.514)
		(end 18.9992 -49.0474)
		(width 0.2032)
		(layer "F.Cu")
		(net "VR_PVCCP_VSEN_R")
	)
	(segment
		(start 18.7706 -49.911)
		(end 18.3896 -50.292)
		(width 0.2032)
		(layer "F.Cu")
		(net "VR_PVCCP_VSEN_R")
	)
	(segment
		(start 18.7706 -49.276)
		(end 18.7706 -49.911)
		(width 0.2032)
		(layer "F.Cu")
		(net "VR_PVCCP_VSEN_R")
	)
	(segment
		(start 21.5392 -50.0888)
		(end 21.5138 -50.0634)
		(width 0.2032)
		(layer "F.Cu")
		(net "VR_PVCCP_VSEN_R")
	)
	(segment
		(start 22.7584 -50.0888)
		(end 21.5392 -50.0888)
		(width 0.2032)
		(layer "F.Cu")
		(net "VR_PVCCP_VSEN_R")
	)
	(via
		(at 21.5138 -50.0634)
		(size 0.508)
		(drill 0.254)
		(layers "F.Cu" "B.Cu")
		(net "VR_PVCCP_VSEN_R")
	)
	(via
		(at 18.9992 -48.514)
		(size 0.508)
		(drill 0.254)
		(layers "F.Cu" "B.Cu")
		(net "VR_PVCCP_VSEN_R")
	)
	(via
		(at 20.701 -49.403)
		(size 0.7112)
		(drill 0.3556)
		(layers "F.Cu" "B.Cu")
		(net "VR_PVCCP_VSEN_R")
	)
	(segment
		(start 18.9992 -48.514)
		(end 19.812 -48.514)
		(width 0.2032)
		(layer "B.Cu")
		(net "VR_PVCCP_VSEN_R")
	)
	(segment
		(start 20.701 -49.403)
		(end 20.8534 -49.403)
		(width 0.2032)
		(layer "B.Cu")
		(net "VR_PVCCP_VSEN_R")
	)
	(segment
		(start 19.812 -48.514)
		(end 20.701 -49.403)
		(width 0.2032)
		(layer "B.Cu")
		(net "VR_PVCCP_VSEN_R")
	)
	(segment
		(start 20.8534 -49.403)
		(end 21.5138 -50.0634)
		(width 0.2032)
		(layer "B.Cu")
		(net "VR_PVCCP_VSEN_R")
	)
	(segment
		(start 190.0174 -12.701778)
		(end 190.0174 -11.838178)
		(width 0.1143)
		(layer "B.Cu")
		(net "CHB_0_SA1")
	)
	(segment
		(start 190.0428 -11.634978)
		(end 190.0428 -11.812778)
		(width 0.1143)
		(layer "B.Cu")
		(net "CHB_0_SA1")
	)
	(segment
		(start 190.749936 -10.927842)
		(end 190.0428 -11.634978)
		(width 0.1143)
		(layer "B.Cu")
		(net "CHB_0_SA1")
	)
	(segment
		(start 190.749936 -9.89076)
		(end 190.749936 -10.927842)
		(width 0.1143)
		(layer "B.Cu")
		(net "CHB_0_SA1")
	)
	(segment
		(start 190.0174 -11.838178)
		(end 190.0428 -11.812778)
		(width 0.1143)
		(layer "B.Cu")
		(net "CHB_0_SA1")
	)
	(segment
		(start 24.3332 -61.292994)
		(end 23.662894 -61.292994)
		(width 0.2032)
		(layer "F.Cu")
		(net "VR_PVNN_GL")
	)
	(segment
		(start 24.684482 -61.292994)
		(end 24.3332 -61.292994)
		(width 0.508)
		(layer "F.Cu")
		(net "VR_PVNN_GL")
	)
	(segment
		(start 25.3111 -60.8838)
		(end 25.093676 -60.8838)
		(width 0.508)
		(layer "F.Cu")
		(net "VR_PVNN_GL")
	)
	(segment
		(start 25.654 -61.0997)
		(end 25.3746 -60.8203)
		(width 0.508)
		(layer "F.Cu")
		(net "VR_PVNN_GL")
	)
	(segment
		(start 25.093676 -60.8838)
		(end 24.684482 -61.292994)
		(width 0.508)
		(layer "F.Cu")
		(net "VR_PVNN_GL")
	)
	(segment
		(start 25.3746 -60.8203)
		(end 25.3111 -60.8838)
		(width 0.508)
		(layer "F.Cu")
		(net "VR_PVNN_GL")
	)
	(segment
		(start 25.654 -61.849)
		(end 25.654 -61.0997)
		(width 0.508)
		(layer "F.Cu")
		(net "VR_PVNN_GL")
	)
	(via
		(at 25.3746 -60.8203)
		(size 0.7112)
		(drill 0.3556)
		(layers "F.Cu" "B.Cu")
		(net "VR_PVNN_GL")
	)
	(segment
		(start 18.934176 -53.328824)
		(end 18.934176 -54.161944)
		(width 0.2032)
		(layer "F.Cu")
		(net "VR_PVCCP_FB_RC2")
	)
	(segment
		(start 19.5326 -52.6288)
		(end 18.8468 -52.6288)
		(width 0.2032)
		(layer "F.Cu")
		(net "VR_PVCCP_FB_RC2")
	)
	(segment
		(start 18.8468 -53.241448)
		(end 18.934176 -53.328824)
		(width 0.2032)
		(layer "F.Cu")
		(net "VR_PVCCP_FB_RC2")
	)
	(segment
		(start 18.8468 -52.6288)
		(end 18.8468 -53.241448)
		(width 0.2032)
		(layer "F.Cu")
		(net "VR_PVCCP_FB_RC2")
	)
	(via
		(at 18.934176 -54.161944)
		(size 0.7112)
		(drill 0.3556)
		(layers "F.Cu" "B.Cu")
		(net "VR_PVCCP_FB_RC2")
	)
	(segment
		(start 108.60024 -26.61158)
		(end 108.60024 -26.83256)
		(width 0.1016)
		(layer "F.Cu")
		(net "M_B_CK_DP0")
	)
	(segment
		(start 108.475526 -26.957274)
		(end 108.252768 -26.957274)
		(width 0.1016)
		(layer "F.Cu")
		(net "M_B_CK_DP0")
	)
	(segment
		(start 108.60024 -26.83256)
		(end 108.475526 -26.957274)
		(width 0.1016)
		(layer "F.Cu")
		(net "M_B_CK_DP0")
	)
	(via
		(at 163.4998 -8.45566)
		(size 0.4318)
		(drill 0.2032)
		(layers "F.Cu" "B.Cu")
		(net "M_B_CK_DP0")
	)
	(via
		(at 108.60024 -26.61158)
		(size 0.4318)
		(drill 0.2032)
		(layers "F.Cu" "B.Cu")
		(net "M_B_CK_DP0")
	)
	(segment
		(start 163.74999 -8.70585)
		(end 163.4998 -8.45566)
		(width 0.2159)
		(layer "B.Cu")
		(net "M_B_CK_DP0")
	)
	(segment
		(start 163.74999 -9.89076)
		(end 163.74999 -8.70585)
		(width 0.2159)
		(layer "B.Cu")
		(net "M_B_CK_DP0")
	)
	(segment
		(start 146.600164 -15.08125)
		(end 147.328636 -15.08125)
		(width 0.1905)
		(layer "In9.Cu")
		(net "M_B_CK_DP0")
	)
	(segment
		(start 145.5547 -18.2118)
		(end 146.0119 -18.2118)
		(width 0.1905)
		(layer "In9.Cu")
		(net "M_B_CK_DP0")
	)
	(segment
		(start 146.1643 -18.0594)
		(end 146.1643 -15.517114)
		(width 0.1905)
		(layer "In9.Cu")
		(net "M_B_CK_DP0")
	)
	(segment
		(start 113.847372 -18.923)
		(end 123.222004 -18.923)
		(width 0.1905)
		(layer "In9.Cu")
		(net "M_B_CK_DP0")
	)
	(segment
		(start 148.3741 -18.161)
		(end 148.5265 -18.0086)
		(width 0.1905)
		(layer "In9.Cu")
		(net "M_B_CK_DP0")
	)
	(segment
		(start 129.13233 -18.69694)
		(end 129.70383 -18.69694)
		(width 0.1905)
		(layer "In9.Cu")
		(net "M_B_CK_DP0")
	)
	(segment
		(start 132.53085 -18.923)
		(end 132.75691 -18.69694)
		(width 0.1905)
		(layer "In9.Cu")
		(net "M_B_CK_DP0")
	)
	(segment
		(start 143.5227 -15.479014)
		(end 143.920464 -15.08125)
		(width 0.1905)
		(layer "In9.Cu")
		(net "M_B_CK_DP0")
	)
	(segment
		(start 125.94209 -18.69694)
		(end 126.51359 -18.69694)
		(width 0.1905)
		(layer "In9.Cu")
		(net "M_B_CK_DP0")
	)
	(segment
		(start 138.825224 -18.923)
		(end 139.396724 -18.923)
		(width 0.1905)
		(layer "In9.Cu")
		(net "M_B_CK_DP0")
	)
	(segment
		(start 131.95935 -18.923)
		(end 132.53085 -18.923)
		(width 0.1905)
		(layer "In9.Cu")
		(net "M_B_CK_DP0")
	)
	(segment
		(start 148.5265 -15.517114)
		(end 148.962364 -15.08125)
		(width 0.1905)
		(layer "In9.Cu")
		(net "M_B_CK_DP0")
	)
	(segment
		(start 143.5227 -17.987264)
		(end 143.5227 -15.479014)
		(width 0.1905)
		(layer "In9.Cu")
		(net "M_B_CK_DP0")
	)
	(segment
		(start 143.920464 -15.08125)
		(end 144.966436 -15.08125)
		(width 0.1905)
		(layer "In9.Cu")
		(net "M_B_CK_DP0")
	)
	(segment
		(start 160.091374 -10.465308)
		(end 160.41116 -10.465308)
		(width 0.1905)
		(layer "In9.Cu")
		(net "M_B_CK_DP0")
	)
	(segment
		(start 109.857286 -22.913086)
		(end 113.847372 -18.923)
		(width 0.1905)
		(layer "In9.Cu")
		(net "M_B_CK_DP0")
	)
	(segment
		(start 160.41116 -10.465308)
		(end 161.033968 -9.8425)
		(width 0.1905)
		(layer "In9.Cu")
		(net "M_B_CK_DP0")
	)
	(segment
		(start 134.35203 -18.69694)
		(end 134.92353 -18.69694)
		(width 0.1905)
		(layer "In9.Cu")
		(net "M_B_CK_DP0")
	)
	(segment
		(start 128.90627 -18.923)
		(end 129.13233 -18.69694)
		(width 0.1905)
		(layer "In9.Cu")
		(net "M_B_CK_DP0")
	)
	(segment
		(start 133.55447 -18.923)
		(end 134.12597 -18.923)
		(width 0.1905)
		(layer "In9.Cu")
		(net "M_B_CK_DP0")
	)
	(segment
		(start 138.599164 -18.69694)
		(end 138.825224 -18.923)
		(width 0.1905)
		(layer "In9.Cu")
		(net "M_B_CK_DP0")
	)
	(segment
		(start 147.9169 -18.161)
		(end 148.3741 -18.161)
		(width 0.1905)
		(layer "In9.Cu")
		(net "M_B_CK_DP0")
	)
	(segment
		(start 159.68726 -11.189208)
		(end 159.68726 -10.869422)
		(width 0.1905)
		(layer "In9.Cu")
		(net "M_B_CK_DP0")
	)
	(segment
		(start 162.769042 -9.8425)
		(end 163.53155 -9.079992)
		(width 0.1905)
		(layer "In9.Cu")
		(net "M_B_CK_DP0")
	)
	(segment
		(start 161.033968 -9.8425)
		(end 162.769042 -9.8425)
		(width 0.1905)
		(layer "In9.Cu")
		(net "M_B_CK_DP0")
	)
	(segment
		(start 140.991844 -18.923)
		(end 141.217904 -18.69694)
		(width 0.1905)
		(layer "In9.Cu")
		(net "M_B_CK_DP0")
	)
	(segment
		(start 163.4998 -8.48106)
		(end 163.4998 -8.45566)
		(width 0.1905)
		(layer "In9.Cu")
		(net "M_B_CK_DP0")
	)
	(segment
		(start 142.586964 -18.923)
		(end 143.5227 -17.987264)
		(width 0.1905)
		(layer "In9.Cu")
		(net "M_B_CK_DP0")
	)
	(segment
		(start 146.1643 -15.517114)
		(end 146.600164 -15.08125)
		(width 0.1905)
		(layer "In9.Cu")
		(net "M_B_CK_DP0")
	)
	(segment
		(start 140.420344 -18.923)
		(end 140.991844 -18.923)
		(width 0.1905)
		(layer "In9.Cu")
		(net "M_B_CK_DP0")
	)
	(segment
		(start 147.7645 -15.517114)
		(end 147.7645 -18.0086)
		(width 0.1905)
		(layer "In9.Cu")
		(net "M_B_CK_DP0")
	)
	(segment
		(start 126.51359 -18.69694)
		(end 126.73965 -18.923)
		(width 0.1905)
		(layer "In9.Cu")
		(net "M_B_CK_DP0")
	)
	(segment
		(start 148.5265 -18.0086)
		(end 148.5265 -15.517114)
		(width 0.1905)
		(layer "In9.Cu")
		(net "M_B_CK_DP0")
	)
	(segment
		(start 141.789404 -18.69694)
		(end 142.015464 -18.923)
		(width 0.1905)
		(layer "In9.Cu")
		(net "M_B_CK_DP0")
	)
	(segment
		(start 147.328636 -15.08125)
		(end 147.7645 -15.517114)
		(width 0.1905)
		(layer "In9.Cu")
		(net "M_B_CK_DP0")
	)
	(segment
		(start 145.4023 -18.0594)
		(end 145.5547 -18.2118)
		(width 0.1905)
		(layer "In9.Cu")
		(net "M_B_CK_DP0")
	)
	(segment
		(start 131.73329 -18.69694)
		(end 131.95935 -18.923)
		(width 0.1905)
		(layer "In9.Cu")
		(net "M_B_CK_DP0")
	)
	(segment
		(start 108.88726 -26.53792)
		(end 108.8136 -26.61158)
		(width 0.1016)
		(layer "In9.Cu")
		(net "M_B_CK_DP0")
	)
	(segment
		(start 134.12597 -18.923)
		(end 134.35203 -18.69694)
		(width 0.1905)
		(layer "In9.Cu")
		(net "M_B_CK_DP0")
	)
	(segment
		(start 146.0119 -18.2118)
		(end 146.1643 -18.0594)
		(width 0.1905)
		(layer "In9.Cu")
		(net "M_B_CK_DP0")
	)
	(segment
		(start 109.857286 -22.913086)
		(end 109.857286 -23.154386)
		(width 0.1016)
		(layer "In9.Cu")
		(net "M_B_CK_DP0")
	)
	(segment
		(start 108.88726 -24.569928)
		(end 108.88726 -26.53792)
		(width 0.1016)
		(layer "In9.Cu")
		(net "M_B_CK_DP0")
	)
	(segment
		(start 128.33477 -18.923)
		(end 128.90627 -18.923)
		(width 0.1905)
		(layer "In9.Cu")
		(net "M_B_CK_DP0")
	)
	(segment
		(start 124.019564 -18.69694)
		(end 124.245624 -18.923)
		(width 0.1905)
		(layer "In9.Cu")
		(net "M_B_CK_DP0")
	)
	(segment
		(start 139.396724 -18.923)
		(end 139.622784 -18.69694)
		(width 0.1905)
		(layer "In9.Cu")
		(net "M_B_CK_DP0")
	)
	(segment
		(start 124.245624 -18.923)
		(end 125.71603 -18.923)
		(width 0.1905)
		(layer "In9.Cu")
		(net "M_B_CK_DP0")
	)
	(segment
		(start 123.448064 -18.69694)
		(end 124.019564 -18.69694)
		(width 0.1905)
		(layer "In9.Cu")
		(net "M_B_CK_DP0")
	)
	(segment
		(start 133.32841 -18.69694)
		(end 133.55447 -18.923)
		(width 0.1905)
		(layer "In9.Cu")
		(net "M_B_CK_DP0")
	)
	(segment
		(start 159.68726 -10.869422)
		(end 160.091374 -10.465308)
		(width 0.1905)
		(layer "In9.Cu")
		(net "M_B_CK_DP0")
	)
	(segment
		(start 125.71603 -18.923)
		(end 125.94209 -18.69694)
		(width 0.1905)
		(layer "In9.Cu")
		(net "M_B_CK_DP0")
	)
	(segment
		(start 134.92353 -18.69694)
		(end 135.14959 -18.923)
		(width 0.1905)
		(layer "In9.Cu")
		(net "M_B_CK_DP0")
	)
	(segment
		(start 109.857286 -23.154386)
		(end 109.5248 -23.486872)
		(width 0.1016)
		(layer "In9.Cu")
		(net "M_B_CK_DP0")
	)
	(segment
		(start 132.75691 -18.69694)
		(end 133.32841 -18.69694)
		(width 0.1905)
		(layer "In9.Cu")
		(net "M_B_CK_DP0")
	)
	(segment
		(start 163.53155 -8.51281)
		(end 163.4998 -8.48106)
		(width 0.1905)
		(layer "In9.Cu")
		(net "M_B_CK_DP0")
	)
	(segment
		(start 141.217904 -18.69694)
		(end 141.789404 -18.69694)
		(width 0.1905)
		(layer "In9.Cu")
		(net "M_B_CK_DP0")
	)
	(segment
		(start 148.962364 -15.08125)
		(end 155.795218 -15.08125)
		(width 0.1905)
		(layer "In9.Cu")
		(net "M_B_CK_DP0")
	)
	(segment
		(start 131.16179 -18.69694)
		(end 131.73329 -18.69694)
		(width 0.1905)
		(layer "In9.Cu")
		(net "M_B_CK_DP0")
	)
	(segment
		(start 129.92989 -18.923)
		(end 130.93573 -18.923)
		(width 0.1905)
		(layer "In9.Cu")
		(net "M_B_CK_DP0")
	)
	(segment
		(start 126.73965 -18.923)
		(end 127.31115 -18.923)
		(width 0.1905)
		(layer "In9.Cu")
		(net "M_B_CK_DP0")
	)
	(segment
		(start 155.795218 -15.08125)
		(end 159.68726 -11.189208)
		(width 0.1905)
		(layer "In9.Cu")
		(net "M_B_CK_DP0")
	)
	(segment
		(start 144.966436 -15.08125)
		(end 145.4023 -15.517114)
		(width 0.1905)
		(layer "In9.Cu")
		(net "M_B_CK_DP0")
	)
	(segment
		(start 140.194284 -18.69694)
		(end 140.420344 -18.923)
		(width 0.1905)
		(layer "In9.Cu")
		(net "M_B_CK_DP0")
	)
	(segment
		(start 147.7645 -18.0086)
		(end 147.9169 -18.161)
		(width 0.1905)
		(layer "In9.Cu")
		(net "M_B_CK_DP0")
	)
	(segment
		(start 145.4023 -15.517114)
		(end 145.4023 -18.0594)
		(width 0.1905)
		(layer "In9.Cu")
		(net "M_B_CK_DP0")
	)
	(segment
		(start 139.622784 -18.69694)
		(end 140.194284 -18.69694)
		(width 0.1905)
		(layer "In9.Cu")
		(net "M_B_CK_DP0")
	)
	(segment
		(start 130.93573 -18.923)
		(end 131.16179 -18.69694)
		(width 0.1905)
		(layer "In9.Cu")
		(net "M_B_CK_DP0")
	)
	(segment
		(start 123.222004 -18.923)
		(end 123.448064 -18.69694)
		(width 0.1905)
		(layer "In9.Cu")
		(net "M_B_CK_DP0")
	)
	(segment
		(start 128.10871 -18.69694)
		(end 128.33477 -18.923)
		(width 0.1905)
		(layer "In9.Cu")
		(net "M_B_CK_DP0")
	)
	(segment
		(start 137.801604 -18.923)
		(end 138.027664 -18.69694)
		(width 0.1905)
		(layer "In9.Cu")
		(net "M_B_CK_DP0")
	)
	(segment
		(start 108.8136 -26.61158)
		(end 108.60024 -26.61158)
		(width 0.1016)
		(layer "In9.Cu")
		(net "M_B_CK_DP0")
	)
	(segment
		(start 163.53155 -9.079992)
		(end 163.53155 -8.51281)
		(width 0.1905)
		(layer "In9.Cu")
		(net "M_B_CK_DP0")
	)
	(segment
		(start 127.53721 -18.69694)
		(end 128.10871 -18.69694)
		(width 0.1905)
		(layer "In9.Cu")
		(net "M_B_CK_DP0")
	)
	(segment
		(start 135.14959 -18.923)
		(end 137.801604 -18.923)
		(width 0.1905)
		(layer "In9.Cu")
		(net "M_B_CK_DP0")
	)
	(segment
		(start 142.015464 -18.923)
		(end 142.586964 -18.923)
		(width 0.1905)
		(layer "In9.Cu")
		(net "M_B_CK_DP0")
	)
	(segment
		(start 109.5248 -23.486872)
		(end 109.5248 -23.932388)
		(width 0.1016)
		(layer "In9.Cu")
		(net "M_B_CK_DP0")
	)
	(segment
		(start 129.70383 -18.69694)
		(end 129.92989 -18.923)
		(width 0.1905)
		(layer "In9.Cu")
		(net "M_B_CK_DP0")
	)
	(segment
		(start 127.31115 -18.923)
		(end 127.53721 -18.69694)
		(width 0.1905)
		(layer "In9.Cu")
		(net "M_B_CK_DP0")
	)
	(segment
		(start 138.027664 -18.69694)
		(end 138.599164 -18.69694)
		(width 0.1905)
		(layer "In9.Cu")
		(net "M_B_CK_DP0")
	)
	(segment
		(start 109.5248 -23.932388)
		(end 108.88726 -24.569928)
		(width 0.1016)
		(layer "In9.Cu")
		(net "M_B_CK_DP0")
	)
	(segment
		(start 26.416 -54.3814)
		(end 25.9588 -54.3814)
		(width 0.508)
		(layer "F.Cu")
		(net "VR_PVCCP_BOOT")
	)
	(segment
		(start 24.335994 -56.220106)
		(end 24.335994 -55.775606)
		(width 0.2032)
		(layer "F.Cu")
		(net "VR_PVCCP_BOOT")
	)
	(segment
		(start 25.4508 -54.8894)
		(end 25.3746 -54.8894)
		(width 0.508)
		(layer "F.Cu")
		(net "VR_PVCCP_BOOT")
	)
	(segment
		(start 24.687276 -55.424324)
		(end 25.2222 -54.8894)
		(width 0.508)
		(layer "F.Cu")
		(net "VR_PVCCP_BOOT")
	)
	(segment
		(start 25.9588 -54.3814)
		(end 25.4508 -54.8894)
		(width 0.508)
		(layer "F.Cu")
		(net "VR_PVCCP_BOOT")
	)
	(segment
		(start 25.2222 -54.8894)
		(end 25.3746 -54.8894)
		(width 0.508)
		(layer "F.Cu")
		(net "VR_PVCCP_BOOT")
	)
	(segment
		(start 24.335994 -55.775606)
		(end 24.687276 -55.424324)
		(width 0.2032)
		(layer "F.Cu")
		(net "VR_PVCCP_BOOT")
	)
	(via
		(at 25.3746 -54.8894)
		(size 0.7112)
		(drill 0.3556)
		(layers "F.Cu" "B.Cu")
		(net "VR_PVCCP_BOOT")
	)
	(segment
		(start 108.786676 -27.215592)
		(end 108.783628 -27.215592)
		(width 0.1016)
		(layer "F.Cu")
		(net "M_B_CK_DN0")
	)
	(segment
		(start 108.99267 -27.009598)
		(end 108.786676 -27.215592)
		(width 0.1016)
		(layer "F.Cu")
		(net "M_B_CK_DN0")
	)
	(segment
		(start 108.783628 -27.215592)
		(end 108.783628 -27.447494)
		(width 0.1016)
		(layer "F.Cu")
		(net "M_B_CK_DN0")
	)
	(via
		(at 108.99267 -27.009598)
		(size 0.4318)
		(drill 0.2032)
		(layers "F.Cu" "B.Cu")
		(net "M_B_CK_DN0")
	)
	(via
		(at 163.6014 -7.697978)
		(size 0.4318)
		(drill 0.2032)
		(layers "F.Cu" "B.Cu")
		(net "M_B_CK_DN0")
	)
	(segment
		(start 163.95065 -8.047228)
		(end 163.6014 -7.697978)
		(width 0.2159)
		(layer "B.Cu")
		(net "M_B_CK_DN0")
	)
	(segment
		(start 164.349938 -9.189974)
		(end 164.11829 -8.958326)
		(width 0.2159)
		(layer "B.Cu")
		(net "M_B_CK_DN0")
	)
	(segment
		(start 164.349938 -9.89076)
		(end 164.349938 -9.189974)
		(width 0.2159)
		(layer "B.Cu")
		(net "M_B_CK_DN0")
	)
	(segment
		(start 163.95065 -8.385556)
		(end 163.95065 -8.047228)
		(width 0.2159)
		(layer "B.Cu")
		(net "M_B_CK_DN0")
	)
	(segment
		(start 164.11829 -8.958326)
		(end 164.11829 -8.553196)
		(width 0.2159)
		(layer "B.Cu")
		(net "M_B_CK_DN0")
	)
	(segment
		(start 164.11829 -8.553196)
		(end 163.95065 -8.385556)
		(width 0.2159)
		(layer "B.Cu")
		(net "M_B_CK_DN0")
	)
	(segment
		(start 109.09046 -24.654256)
		(end 109.728 -24.016716)
		(width 0.1016)
		(layer "In9.Cu")
		(net "M_B_CK_DN0")
	)
	(segment
		(start 146.185636 -18.6309)
		(end 146.5834 -18.233136)
		(width 0.1905)
		(layer "In9.Cu")
		(net "M_B_CK_DN0")
	)
	(segment
		(start 144.9832 -15.69085)
		(end 144.9832 -18.233136)
		(width 0.1905)
		(layer "In9.Cu")
		(net "M_B_CK_DN0")
	)
	(segment
		(start 147.1549 -15.50035)
		(end 147.3454 -15.69085)
		(width 0.1905)
		(layer "In9.Cu")
		(net "M_B_CK_DN0")
	)
	(segment
		(start 148.547836 -18.5801)
		(end 148.9456 -18.182336)
		(width 0.1905)
		(layer "In9.Cu")
		(net "M_B_CK_DN0")
	)
	(segment
		(start 109.09046 -26.911808)
		(end 109.09046 -24.654256)
		(width 0.1016)
		(layer "In9.Cu")
		(net "M_B_CK_DN0")
	)
	(segment
		(start 142.7607 -19.3421)
		(end 143.9418 -18.161)
		(width 0.1905)
		(layer "In9.Cu")
		(net "M_B_CK_DN0")
	)
	(segment
		(start 114.021108 -19.3421)
		(end 142.7607 -19.3421)
		(width 0.1905)
		(layer "In9.Cu")
		(net "M_B_CK_DN0")
	)
	(segment
		(start 146.7739 -15.50035)
		(end 147.1549 -15.50035)
		(width 0.1905)
		(layer "In9.Cu")
		(net "M_B_CK_DN0")
	)
	(segment
		(start 143.9418 -18.161)
		(end 143.9418 -15.65275)
		(width 0.1905)
		(layer "In9.Cu")
		(net "M_B_CK_DN0")
	)
	(segment
		(start 149.1361 -15.50035)
		(end 155.968954 -15.50035)
		(width 0.1905)
		(layer "In9.Cu")
		(net "M_B_CK_DN0")
	)
	(segment
		(start 146.5834 -15.69085)
		(end 146.7739 -15.50035)
		(width 0.1905)
		(layer "In9.Cu")
		(net "M_B_CK_DN0")
	)
	(segment
		(start 109.728 -23.5712)
		(end 110.089696 -23.209504)
		(width 0.1016)
		(layer "In9.Cu")
		(net "M_B_CK_DN0")
	)
	(segment
		(start 110.153704 -23.209504)
		(end 114.021108 -19.3421)
		(width 0.1905)
		(layer "In9.Cu")
		(net "M_B_CK_DN0")
	)
	(segment
		(start 147.3454 -15.69085)
		(end 147.3454 -18.182336)
		(width 0.1905)
		(layer "In9.Cu")
		(net "M_B_CK_DN0")
	)
	(segment
		(start 163.95065 -8.047228)
		(end 163.6014 -7.697978)
		(width 0.1905)
		(layer "In9.Cu")
		(net "M_B_CK_DN0")
	)
	(segment
		(start 143.9418 -15.65275)
		(end 144.0942 -15.50035)
		(width 0.1905)
		(layer "In9.Cu")
		(net "M_B_CK_DN0")
	)
	(segment
		(start 163.95065 -9.253728)
		(end 163.95065 -8.047228)
		(width 0.1905)
		(layer "In9.Cu")
		(net "M_B_CK_DN0")
	)
	(segment
		(start 148.9456 -18.182336)
		(end 148.9456 -15.69085)
		(width 0.1905)
		(layer "In9.Cu")
		(net "M_B_CK_DN0")
	)
	(segment
		(start 109.728 -24.016716)
		(end 109.728 -23.5712)
		(width 0.1016)
		(layer "In9.Cu")
		(net "M_B_CK_DN0")
	)
	(segment
		(start 147.743164 -18.5801)
		(end 148.547836 -18.5801)
		(width 0.1905)
		(layer "In9.Cu")
		(net "M_B_CK_DN0")
	)
	(segment
		(start 108.99267 -27.009598)
		(end 109.09046 -26.911808)
		(width 0.1016)
		(layer "In9.Cu")
		(net "M_B_CK_DN0")
	)
	(segment
		(start 110.089696 -23.209504)
		(end 110.153704 -23.209504)
		(width 0.1016)
		(layer "In9.Cu")
		(net "M_B_CK_DN0")
	)
	(segment
		(start 147.3454 -18.182336)
		(end 147.743164 -18.5801)
		(width 0.1905)
		(layer "In9.Cu")
		(net "M_B_CK_DN0")
	)
	(segment
		(start 144.9832 -18.233136)
		(end 145.380964 -18.6309)
		(width 0.1905)
		(layer "In9.Cu")
		(net "M_B_CK_DN0")
	)
	(segment
		(start 155.968954 -15.50035)
		(end 161.207704 -10.2616)
		(width 0.1905)
		(layer "In9.Cu")
		(net "M_B_CK_DN0")
	)
	(segment
		(start 148.9456 -15.69085)
		(end 149.1361 -15.50035)
		(width 0.1905)
		(layer "In9.Cu")
		(net "M_B_CK_DN0")
	)
	(segment
		(start 162.942778 -10.2616)
		(end 163.95065 -9.253728)
		(width 0.1905)
		(layer "In9.Cu")
		(net "M_B_CK_DN0")
	)
	(segment
		(start 144.7927 -15.50035)
		(end 144.9832 -15.69085)
		(width 0.1905)
		(layer "In9.Cu")
		(net "M_B_CK_DN0")
	)
	(segment
		(start 146.5834 -18.233136)
		(end 146.5834 -15.69085)
		(width 0.1905)
		(layer "In9.Cu")
		(net "M_B_CK_DN0")
	)
	(segment
		(start 145.380964 -18.6309)
		(end 146.185636 -18.6309)
		(width 0.1905)
		(layer "In9.Cu")
		(net "M_B_CK_DN0")
	)
	(segment
		(start 161.207704 -10.2616)
		(end 162.942778 -10.2616)
		(width 0.1905)
		(layer "In9.Cu")
		(net "M_B_CK_DN0")
	)
	(segment
		(start 144.0942 -15.50035)
		(end 144.7927 -15.50035)
		(width 0.1905)
		(layer "In9.Cu")
		(net "M_B_CK_DN0")
	)
	(segment
		(start 112.11433 -31.056834)
		(end 112.481868 -30.689296)
		(width 0.1778)
		(layer "F.Cu")
		(net "M_B_ODT0")
	)
	(segment
		(start 111.656368 -31.056834)
		(end 112.11433 -31.056834)
		(width 0.1778)
		(layer "F.Cu")
		(net "M_B_ODT0")
	)
	(via
		(at 112.481868 -30.689296)
		(size 0.4318)
		(drill 0.2032)
		(layers "F.Cu" "B.Cu")
		(net "M_B_ODT0")
	)
	(via
		(at 168.239186 -3.144266)
		(size 0.4318)
		(drill 0.2032)
		(layers "F.Cu" "B.Cu")
		(net "M_B_ODT0")
	)
	(segment
		(start 168.249854 -3.133598)
		(end 168.239186 -3.144266)
		(width 0.1778)
		(layer "B.Cu")
		(net "M_B_ODT0")
	)
	(segment
		(start 168.249854 -1.690624)
		(end 168.249854 -3.133598)
		(width 0.1778)
		(layer "B.Cu")
		(net "M_B_ODT0")
	)
	(segment
		(start 168.239186 -3.144266)
		(end 168.204134 -3.144266)
		(width 0.1524)
		(layer "In9.Cu")
		(net "M_B_ODT0")
	)
	(segment
		(start 165.51021 -20.2311)
		(end 162.0012 -20.2311)
		(width 0.1524)
		(layer "In9.Cu")
		(net "M_B_ODT0")
	)
	(segment
		(start 155.660598 -27.8384)
		(end 155.660344 -27.838146)
		(width 0.1524)
		(layer "In9.Cu")
		(net "M_B_ODT0")
	)
	(segment
		(start 168.602152 -4.878578)
		(end 168.91 -5.186426)
		(width 0.1524)
		(layer "In9.Cu")
		(net "M_B_ODT0")
	)
	(segment
		(start 171.170854 -12.041378)
		(end 171.170854 -14.570456)
		(width 0.1524)
		(layer "In9.Cu")
		(net "M_B_ODT0")
	)
	(segment
		(start 155.660344 -27.838146)
		(end 115.417854 -27.838146)
		(width 0.1524)
		(layer "In9.Cu")
		(net "M_B_ODT0")
	)
	(segment
		(start 167.758872 -3.589528)
		(end 167.758872 -4.36245)
		(width 0.1524)
		(layer "In9.Cu")
		(net "M_B_ODT0")
	)
	(segment
		(start 167.758872 -4.36245)
		(end 168.275 -4.878578)
		(width 0.1524)
		(layer "In9.Cu")
		(net "M_B_ODT0")
	)
	(segment
		(start 156.144214 -27.8384)
		(end 155.660598 -27.8384)
		(width 0.1524)
		(layer "In9.Cu")
		(net "M_B_ODT0")
	)
	(segment
		(start 170.815254 -11.685778)
		(end 171.170854 -12.041378)
		(width 0.1524)
		(layer "In9.Cu")
		(net "M_B_ODT0")
	)
	(segment
		(start 169.247312 -8.773414)
		(end 169.1894 -8.831326)
		(width 0.1524)
		(layer "In9.Cu")
		(net "M_B_ODT0")
	)
	(segment
		(start 112.566704 -30.689296)
		(end 112.481868 -30.689296)
		(width 0.1524)
		(layer "In9.Cu")
		(net "M_B_ODT0")
	)
	(segment
		(start 168.204134 -3.144266)
		(end 167.758872 -3.589528)
		(width 0.1524)
		(layer "In9.Cu")
		(net "M_B_ODT0")
	)
	(segment
		(start 168.91 -7.03707)
		(end 169.247312 -7.374382)
		(width 0.1524)
		(layer "In9.Cu")
		(net "M_B_ODT0")
	)
	(segment
		(start 162.0012 -20.2311)
		(end 161.5948 -20.6375)
		(width 0.1524)
		(layer "In9.Cu")
		(net "M_B_ODT0")
	)
	(segment
		(start 168.275 -4.878578)
		(end 168.602152 -4.878578)
		(width 0.1524)
		(layer "In9.Cu")
		(net "M_B_ODT0")
	)
	(segment
		(start 168.91 -5.186426)
		(end 168.91 -7.03707)
		(width 0.1524)
		(layer "In9.Cu")
		(net "M_B_ODT0")
	)
	(segment
		(start 170.234864 -11.685778)
		(end 170.815254 -11.685778)
		(width 0.1524)
		(layer "In9.Cu")
		(net "M_B_ODT0")
	)
	(segment
		(start 161.5948 -22.387814)
		(end 156.144214 -27.8384)
		(width 0.1524)
		(layer "In9.Cu")
		(net "M_B_ODT0")
	)
	(segment
		(start 169.1894 -10.640314)
		(end 170.234864 -11.685778)
		(width 0.1524)
		(layer "In9.Cu")
		(net "M_B_ODT0")
	)
	(segment
		(start 115.417854 -27.838146)
		(end 112.566704 -30.689296)
		(width 0.1524)
		(layer "In9.Cu")
		(net "M_B_ODT0")
	)
	(segment
		(start 161.5948 -20.6375)
		(end 161.5948 -22.387814)
		(width 0.1524)
		(layer "In9.Cu")
		(net "M_B_ODT0")
	)
	(segment
		(start 171.170854 -14.570456)
		(end 165.51021 -20.2311)
		(width 0.1524)
		(layer "In9.Cu")
		(net "M_B_ODT0")
	)
	(segment
		(start 169.1894 -8.831326)
		(end 169.1894 -10.640314)
		(width 0.1524)
		(layer "In9.Cu")
		(net "M_B_ODT0")
	)
	(segment
		(start 169.247312 -7.374382)
		(end 169.247312 -8.773414)
		(width 0.1524)
		(layer "In9.Cu")
		(net "M_B_ODT0")
	)
	(segment
		(start 25.1206 -52.578)
		(end 25.146 -52.6034)
		(width 0.2032)
		(layer "F.Cu")
		(net "VR_PVCCP_ISUMN_RC")
	)
	(segment
		(start 26.1366 -52.6288)
		(end 26.2382 -52.5272)
		(width 0.2032)
		(layer "F.Cu")
		(net "VR_PVCCP_ISUMN_RC")
	)
	(segment
		(start 25.1206 -51.816)
		(end 25.1206 -52.578)
		(width 0.2032)
		(layer "F.Cu")
		(net "VR_PVCCP_ISUMN_RC")
	)
	(segment
		(start 25.1714 -52.6288)
		(end 26.1366 -52.6288)
		(width 0.2032)
		(layer "F.Cu")
		(net "VR_PVCCP_ISUMN_RC")
	)
	(segment
		(start 25.146 -52.6034)
		(end 25.1714 -52.6288)
		(width 0.2032)
		(layer "F.Cu")
		(net "VR_PVCCP_ISUMN_RC")
	)
	(via
		(at 26.2382 -52.5272)
		(size 0.7112)
		(drill 0.3556)
		(layers "F.Cu" "B.Cu")
		(net "VR_PVCCP_ISUMN_RC")
	)
	(segment
		(start 105.349294 -41.3004)
		(end 105.3592 -41.3004)
		(width 0.1016)
		(layer "F.Cu")
		(net "M_A_DQ5")
	)
	(segment
		(start 105.004108 -40.955214)
		(end 105.349294 -41.3004)
		(width 0.1016)
		(layer "F.Cu")
		(net "M_A_DQ5")
	)
	(segment
		(start 188.4426 -69.374004)
		(end 188.4426 -68.8848)
		(width 0.1778)
		(layer "F.Cu")
		(net "M_A_DQ5")
	)
	(segment
		(start 188.350144 -69.46646)
		(end 188.4426 -69.374004)
		(width 0.1778)
		(layer "F.Cu")
		(net "M_A_DQ5")
	)
	(segment
		(start 188.4426 -68.8848)
		(end 188.2648 -68.707)
		(width 0.1778)
		(layer "F.Cu")
		(net "M_A_DQ5")
	)
	(segment
		(start 188.350144 -70.806564)
		(end 188.350144 -69.46646)
		(width 0.1778)
		(layer "F.Cu")
		(net "M_A_DQ5")
	)
	(via
		(at 105.3592 -41.3004)
		(size 0.4318)
		(drill 0.2032)
		(layers "F.Cu" "B.Cu")
		(net "M_A_DQ5")
	)
	(via
		(at 188.2648 -68.707)
		(size 0.4318)
		(drill 0.2032)
		(layers "F.Cu" "B.Cu")
		(net "M_A_DQ5")
	)
	(segment
		(start 188.4426 -69.5198)
		(end 188.4426 -68.8848)
		(width 0.1778)
		(layer "B.Cu")
		(net "M_A_DQ5")
	)
	(segment
		(start 188.4426 -68.8848)
		(end 188.2648 -68.707)
		(width 0.1778)
		(layer "B.Cu")
		(net "M_A_DQ5")
	)
	(segment
		(start 188.650118 -69.727318)
		(end 188.4426 -69.5198)
		(width 0.1778)
		(layer "B.Cu")
		(net "M_A_DQ5")
	)
	(segment
		(start 188.650118 -70.79996)
		(end 188.650118 -69.727318)
		(width 0.1778)
		(layer "B.Cu")
		(net "M_A_DQ5")
	)
	(segment
		(start 111.712502 -40.0304)
		(end 111.479076 -40.0304)
		(width 0.1016)
		(layer "In7.Cu")
		(net "M_A_DQ5")
	)
	(segment
		(start 111.479076 -40.0304)
		(end 111.323374 -39.874698)
		(width 0.1016)
		(layer "In7.Cu")
		(net "M_A_DQ5")
	)
	(segment
		(start 188.502798 -66.3194)
		(end 188.502798 -65.827402)
		(width 0.1524)
		(layer "In7.Cu")
		(net "M_A_DQ5")
	)
	(segment
		(start 188.087 -68.5292)
		(end 188.087 -68.132198)
		(width 0.1524)
		(layer "In7.Cu")
		(net "M_A_DQ5")
	)
	(segment
		(start 105.3592 -41.102788)
		(end 105.3592 -41.3004)
		(width 0.1016)
		(layer "In7.Cu")
		(net "M_A_DQ5")
	)
	(segment
		(start 189.518798 -63.876936)
		(end 189.046104 -63.404242)
		(width 0.1524)
		(layer "In7.Cu")
		(net "M_A_DQ5")
	)
	(segment
		(start 188.7474 -66.564002)
		(end 188.502798 -66.3194)
		(width 0.1524)
		(layer "In7.Cu")
		(net "M_A_DQ5")
	)
	(segment
		(start 119.275098 -40.255698)
		(end 119.0498 -40.0304)
		(width 0.1524)
		(layer "In7.Cu")
		(net "M_A_DQ5")
	)
	(segment
		(start 189.046104 -63.404242)
		(end 186.2836 -61.1886)
		(width 0.1524)
		(layer "In7.Cu")
		(net "M_A_DQ5")
	)
	(segment
		(start 153.629106 -40.255444)
		(end 153.628852 -40.255698)
		(width 0.1524)
		(layer "In7.Cu")
		(net "M_A_DQ5")
	)
	(segment
		(start 119.0498 -40.0304)
		(end 111.712502 -40.0304)
		(width 0.1524)
		(layer "In7.Cu")
		(net "M_A_DQ5")
	)
	(segment
		(start 106.58729 -39.874698)
		(end 105.3592 -41.102788)
		(width 0.1016)
		(layer "In7.Cu")
		(net "M_A_DQ5")
	)
	(segment
		(start 189.485778 -64.636142)
		(end 189.518798 -64.503808)
		(width 0.1524)
		(layer "In7.Cu")
		(net "M_A_DQ5")
	)
	(segment
		(start 188.502798 -67.7164)
		(end 188.502798 -67.249802)
		(width 0.1524)
		(layer "In7.Cu")
		(net "M_A_DQ5")
	)
	(segment
		(start 186.2836 -61.1886)
		(end 171.28363 -50.109628)
		(width 0.1524)
		(layer "In7.Cu")
		(net "M_A_DQ5")
	)
	(segment
		(start 171.28363 -50.109628)
		(end 158.806896 -43.145456)
		(width 0.1524)
		(layer "In7.Cu")
		(net "M_A_DQ5")
	)
	(segment
		(start 156.448252 -41.828974)
		(end 153.629106 -40.255444)
		(width 0.1524)
		(layer "In7.Cu")
		(net "M_A_DQ5")
	)
	(segment
		(start 189.518798 -64.503808)
		(end 189.518798 -63.876936)
		(width 0.1524)
		(layer "In7.Cu")
		(net "M_A_DQ5")
	)
	(segment
		(start 188.2648 -68.707)
		(end 188.087 -68.5292)
		(width 0.1524)
		(layer "In7.Cu")
		(net "M_A_DQ5")
	)
	(segment
		(start 153.628852 -40.255698)
		(end 119.275098 -40.255698)
		(width 0.1524)
		(layer "In7.Cu")
		(net "M_A_DQ5")
	)
	(segment
		(start 188.7474 -67.0052)
		(end 188.7474 -66.564002)
		(width 0.1524)
		(layer "In7.Cu")
		(net "M_A_DQ5")
	)
	(segment
		(start 188.502798 -67.249802)
		(end 188.7474 -67.0052)
		(width 0.1524)
		(layer "In7.Cu")
		(net "M_A_DQ5")
	)
	(segment
		(start 188.502798 -65.827402)
		(end 189.416182 -64.914018)
		(width 0.1524)
		(layer "In7.Cu")
		(net "M_A_DQ5")
	)
	(segment
		(start 189.416182 -64.914018)
		(end 189.485778 -64.636142)
		(width 0.1524)
		(layer "In7.Cu")
		(net "M_A_DQ5")
	)
	(segment
		(start 111.323374 -39.874698)
		(end 106.58729 -39.874698)
		(width 0.1016)
		(layer "In7.Cu")
		(net "M_A_DQ5")
	)
	(segment
		(start 188.087 -68.132198)
		(end 188.502798 -67.7164)
		(width 0.1524)
		(layer "In7.Cu")
		(net "M_A_DQ5")
	)
	(segment
		(start 158.806896 -43.145456)
		(end 156.448252 -41.828974)
		(width 0.1524)
		(layer "In7.Cu")
		(net "M_A_DQ5")
	)
	(segment
		(start 102.2858 -57.6326)
		(end 102.2858 -52.087526)
		(width 0.1016)
		(layer "F.Cu")
		(net "M_A_DQ43")
	)
	(segment
		(start 139.450064 -64.596264)
		(end 139.7508 -64.897)
		(width 0.1778)
		(layer "F.Cu")
		(net "M_A_DQ43")
	)
	(segment
		(start 102.2858 -52.087526)
		(end 102.037388 -51.839114)
		(width 0.1016)
		(layer "F.Cu")
		(net "M_A_DQ43")
	)
	(segment
		(start 139.450064 -62.59322)
		(end 139.450064 -64.596264)
		(width 0.1778)
		(layer "F.Cu")
		(net "M_A_DQ43")
	)
	(segment
		(start 102.7176 -58.0644)
		(end 102.2858 -57.6326)
		(width 0.1016)
		(layer "F.Cu")
		(net "M_A_DQ43")
	)
	(via
		(at 102.7176 -58.0644)
		(size 0.4318)
		(drill 0.2032)
		(layers "F.Cu" "B.Cu")
		(net "M_A_DQ43")
	)
	(via
		(at 139.7508 -64.897)
		(size 0.4318)
		(drill 0.2032)
		(layers "F.Cu" "B.Cu")
		(net "M_A_DQ43")
	)
	(segment
		(start 139.750038 -62.599824)
		(end 139.750038 -63.425324)
		(width 0.1778)
		(layer "B.Cu")
		(net "M_A_DQ43")
	)
	(segment
		(start 139.750038 -63.425324)
		(end 139.5222 -63.653162)
		(width 0.1778)
		(layer "B.Cu")
		(net "M_A_DQ43")
	)
	(segment
		(start 139.5222 -63.653162)
		(end 139.5222 -64.6684)
		(width 0.1778)
		(layer "B.Cu")
		(net "M_A_DQ43")
	)
	(segment
		(start 139.5222 -64.6684)
		(end 139.7508 -64.897)
		(width 0.1778)
		(layer "B.Cu")
		(net "M_A_DQ43")
	)
	(segment
		(start 129.735326 -68.1228)
		(end 129.887726 -67.9704)
		(width 0.1524)
		(layer "In2.Cu")
		(net "M_A_DQ43")
	)
	(segment
		(start 134.017004 -67.9704)
		(end 134.169404 -68.1228)
		(width 0.1524)
		(layer "In2.Cu")
		(net "M_A_DQ43")
	)
	(segment
		(start 102.7176 -58.0644)
		(end 102.7176 -59.2328)
		(width 0.1524)
		(layer "In2.Cu")
		(net "M_A_DQ43")
	)
	(segment
		(start 137.7188 -65.8114)
		(end 138.0998 -65.4304)
		(width 0.1524)
		(layer "In2.Cu")
		(net "M_A_DQ43")
	)
	(segment
		(start 133.255004 -68.1228)
		(end 133.407404 -67.9704)
		(width 0.1524)
		(layer "In2.Cu")
		(net "M_A_DQ43")
	)
	(segment
		(start 139.162536 -65.4304)
		(end 139.695936 -64.897)
		(width 0.1524)
		(layer "In2.Cu")
		(net "M_A_DQ43")
	)
	(segment
		(start 104.5718 -61.087)
		(end 120.4214 -61.087)
		(width 0.1524)
		(layer "In2.Cu")
		(net "M_A_DQ43")
	)
	(segment
		(start 133.407404 -66.7512)
		(end 133.559804 -66.5988)
		(width 0.1524)
		(layer "In2.Cu")
		(net "M_A_DQ43")
	)
	(segment
		(start 130.497326 -67.9704)
		(end 130.649726 -68.1228)
		(width 0.1524)
		(layer "In2.Cu")
		(net "M_A_DQ43")
	)
	(segment
		(start 133.559804 -66.5988)
		(end 133.864604 -66.5988)
		(width 0.1524)
		(layer "In2.Cu")
		(net "M_A_DQ43")
	)
	(segment
		(start 135.236204 -67.9704)
		(end 135.388604 -68.1228)
		(width 0.1524)
		(layer "In2.Cu")
		(net "M_A_DQ43")
	)
	(segment
		(start 130.497326 -67.2846)
		(end 130.497326 -67.9704)
		(width 0.1524)
		(layer "In2.Cu")
		(net "M_A_DQ43")
	)
	(segment
		(start 130.040126 -67.1322)
		(end 130.344926 -67.1322)
		(width 0.1524)
		(layer "In2.Cu")
		(net "M_A_DQ43")
	)
	(segment
		(start 120.4214 -61.087)
		(end 124.2695 -64.9351)
		(width 0.1524)
		(layer "In2.Cu")
		(net "M_A_DQ43")
	)
	(segment
		(start 124.2695 -64.9351)
		(end 125.9459 -64.9351)
		(width 0.1524)
		(layer "In2.Cu")
		(net "M_A_DQ43")
	)
	(segment
		(start 138.0998 -65.4304)
		(end 139.162536 -65.4304)
		(width 0.1524)
		(layer "In2.Cu")
		(net "M_A_DQ43")
	)
	(segment
		(start 133.407404 -67.9704)
		(end 133.407404 -66.7512)
		(width 0.1524)
		(layer "In2.Cu")
		(net "M_A_DQ43")
	)
	(segment
		(start 130.344926 -67.1322)
		(end 130.497326 -67.2846)
		(width 0.1524)
		(layer "In2.Cu")
		(net "M_A_DQ43")
	)
	(segment
		(start 129.887726 -67.2846)
		(end 130.040126 -67.1322)
		(width 0.1524)
		(layer "In2.Cu")
		(net "M_A_DQ43")
	)
	(segment
		(start 133.864604 -66.5988)
		(end 134.017004 -66.7512)
		(width 0.1524)
		(layer "In2.Cu")
		(net "M_A_DQ43")
	)
	(segment
		(start 134.169404 -68.1228)
		(end 134.474204 -68.1228)
		(width 0.1524)
		(layer "In2.Cu")
		(net "M_A_DQ43")
	)
	(segment
		(start 134.626604 -66.7512)
		(end 134.779004 -66.5988)
		(width 0.1524)
		(layer "In2.Cu")
		(net "M_A_DQ43")
	)
	(segment
		(start 102.7176 -59.2328)
		(end 104.5718 -61.087)
		(width 0.1524)
		(layer "In2.Cu")
		(net "M_A_DQ43")
	)
	(segment
		(start 137.7188 -67.8434)
		(end 137.7188 -65.8114)
		(width 0.1524)
		(layer "In2.Cu")
		(net "M_A_DQ43")
	)
	(segment
		(start 134.779004 -66.5988)
		(end 135.083804 -66.5988)
		(width 0.1524)
		(layer "In2.Cu")
		(net "M_A_DQ43")
	)
	(segment
		(start 137.4394 -68.1228)
		(end 137.7188 -67.8434)
		(width 0.1524)
		(layer "In2.Cu")
		(net "M_A_DQ43")
	)
	(segment
		(start 135.083804 -66.5988)
		(end 135.236204 -66.7512)
		(width 0.1524)
		(layer "In2.Cu")
		(net "M_A_DQ43")
	)
	(segment
		(start 134.017004 -66.7512)
		(end 134.017004 -67.9704)
		(width 0.1524)
		(layer "In2.Cu")
		(net "M_A_DQ43")
	)
	(segment
		(start 125.9459 -64.9351)
		(end 129.1336 -68.1228)
		(width 0.1524)
		(layer "In2.Cu")
		(net "M_A_DQ43")
	)
	(segment
		(start 135.388604 -68.1228)
		(end 137.4394 -68.1228)
		(width 0.1524)
		(layer "In2.Cu")
		(net "M_A_DQ43")
	)
	(segment
		(start 134.626604 -67.9704)
		(end 134.626604 -66.7512)
		(width 0.1524)
		(layer "In2.Cu")
		(net "M_A_DQ43")
	)
	(segment
		(start 135.236204 -66.7512)
		(end 135.236204 -67.9704)
		(width 0.1524)
		(layer "In2.Cu")
		(net "M_A_DQ43")
	)
	(segment
		(start 139.695936 -64.897)
		(end 139.7508 -64.897)
		(width 0.1524)
		(layer "In2.Cu")
		(net "M_A_DQ43")
	)
	(segment
		(start 129.1336 -68.1228)
		(end 129.735326 -68.1228)
		(width 0.1524)
		(layer "In2.Cu")
		(net "M_A_DQ43")
	)
	(segment
		(start 134.474204 -68.1228)
		(end 134.626604 -67.9704)
		(width 0.1524)
		(layer "In2.Cu")
		(net "M_A_DQ43")
	)
	(segment
		(start 130.649726 -68.1228)
		(end 133.255004 -68.1228)
		(width 0.1524)
		(layer "In2.Cu")
		(net "M_A_DQ43")
	)
	(segment
		(start 129.887726 -67.9704)
		(end 129.887726 -67.2846)
		(width 0.1524)
		(layer "In2.Cu")
		(net "M_A_DQ43")
	)
	(segment
		(start 121.0437 -43.2943)
		(end 121.0437 -48.382936)
		(width 0.127)
		(layer "F.Cu")
		(net "VR_PVCCP_RTN")
	)
	(segment
		(start 21.6408 -54.968902)
		(end 21.662898 -54.991)
		(width 0.127)
		(layer "F.Cu")
		(net "VR_PVCCP_RTN")
	)
	(segment
		(start 101.818694 -61.935106)
		(end 101.457252 -61.935106)
		(width 0.127)
		(layer "F.Cu")
		(net "VR_PVCCP_RTN")
	)
	(segment
		(start 23.2918 -51.181)
		(end 23.5204 -50.9524)
		(width 0.127)
		(layer "F.Cu")
		(net "VR_PVCCP_RTN")
	)
	(segment
		(start 23.3934 -52.4764)
		(end 23.3934 -52.021232)
		(width 0.127)
		(layer "F.Cu")
		(net "VR_PVCCP_RTN")
	)
	(segment
		(start 22.95271 -53.5051)
		(end 22.31771 -53.5051)
		(width 0.127)
		(layer "F.Cu")
		(net "VR_PVCCP_RTN")
	)
	(segment
		(start 23.2918 -51.512978)
		(end 23.2918 -51.181)
		(width 0.127)
		(layer "F.Cu")
		(net "VR_PVCCP_RTN")
	)
	(segment
		(start 21.662898 -54.991)
		(end 21.662898 -55.547006)
		(width 0.127)
		(layer "F.Cu")
		(net "VR_PVCCP_RTN")
	)
	(segment
		(start 118.1608 -37.354002)
		(end 118.237 -37.277802)
		(width 0.127)
		(layer "F.Cu")
		(net "VR_PVCCP_RTN")
	)
	(segment
		(start 118.237 -37.277802)
		(end 118.491 -37.023802)
		(width 0.127)
		(layer "F.Cu")
		(net "VR_PVCCP_RTN")
	)
	(segment
		(start 118.491 -37.023802)
		(end 123.024392 -37.023802)
		(width 0.127)
		(layer "F.Cu")
		(net "VR_PVCCP_RTN")
	)
	(segment
		(start 124.46 -39.878)
		(end 121.0437 -43.2943)
		(width 0.127)
		(layer "F.Cu")
		(net "VR_PVCCP_RTN")
	)
	(segment
		(start 117.3988 -37.354002)
		(end 118.1608 -37.354002)
		(width 0.127)
		(layer "F.Cu")
		(net "VR_PVCCP_RTN")
	)
	(segment
		(start 23.2156 -53.24221)
		(end 22.95271 -53.5051)
		(width 0.127)
		(layer "F.Cu")
		(net "VR_PVCCP_RTN")
	)
	(segment
		(start 23.5204 -52.6034)
		(end 23.5458 -52.6288)
		(width 0.127)
		(layer "F.Cu")
		(net "VR_PVCCP_RTN")
	)
	(segment
		(start 23.3934 -52.021232)
		(end 23.5966 -51.818032)
		(width 0.127)
		(layer "F.Cu")
		(net "VR_PVCCP_RTN")
	)
	(segment
		(start 115.7097 -56.7563)
		(end 112.395 -60.071)
		(width 0.127)
		(layer "F.Cu")
		(net "VR_PVCCP_RTN")
	)
	(segment
		(start 23.5458 -52.6288)
		(end 23.2156 -52.959)
		(width 0.127)
		(layer "F.Cu")
		(net "VR_PVCCP_RTN")
	)
	(segment
		(start 115.7097 -53.716936)
		(end 115.7097 -56.7563)
		(width 0.127)
		(layer "F.Cu")
		(net "VR_PVCCP_RTN")
	)
	(segment
		(start 121.0437 -48.382936)
		(end 115.7097 -53.716936)
		(width 0.127)
		(layer "F.Cu")
		(net "VR_PVCCP_RTN")
	)
	(segment
		(start 123.024392 -37.023802)
		(end 124.46 -38.45941)
		(width 0.127)
		(layer "F.Cu")
		(net "VR_PVCCP_RTN")
	)
	(segment
		(start 112.395 -60.071)
		(end 103.6828 -60.071)
		(width 0.127)
		(layer "F.Cu")
		(net "VR_PVCCP_RTN")
	)
	(segment
		(start 23.5712 -51.792378)
		(end 23.2918 -51.512978)
		(width 0.127)
		(layer "F.Cu")
		(net "VR_PVCCP_RTN")
	)
	(segment
		(start 22.31771 -53.5051)
		(end 21.6408 -54.18201)
		(width 0.127)
		(layer "F.Cu")
		(net "VR_PVCCP_RTN")
	)
	(segment
		(start 23.5204 -52.6034)
		(end 23.3934 -52.4764)
		(width 0.127)
		(layer "F.Cu")
		(net "VR_PVCCP_RTN")
	)
	(segment
		(start 103.6828 -60.071)
		(end 101.818694 -61.935106)
		(width 0.127)
		(layer "F.Cu")
		(net "VR_PVCCP_RTN")
	)
	(segment
		(start 124.46 -38.45941)
		(end 124.46 -39.878)
		(width 0.127)
		(layer "F.Cu")
		(net "VR_PVCCP_RTN")
	)
	(segment
		(start 23.5966 -51.818032)
		(end 23.5712 -51.792632)
		(width 0.127)
		(layer "F.Cu")
		(net "VR_PVCCP_RTN")
	)
	(segment
		(start 23.5712 -51.792632)
		(end 23.5712 -51.792378)
		(width 0.127)
		(layer "F.Cu")
		(net "VR_PVCCP_RTN")
	)
	(segment
		(start 21.6408 -54.18201)
		(end 21.6408 -54.968902)
		(width 0.127)
		(layer "F.Cu")
		(net "VR_PVCCP_RTN")
	)
	(segment
		(start 23.2156 -52.959)
		(end 23.2156 -53.24221)
		(width 0.127)
		(layer "F.Cu")
		(net "VR_PVCCP_RTN")
	)
	(via
		(at 23.749 -52.832)
		(size 0.7112)
		(drill 0.3556)
		(layers "F.Cu" "B.Cu")
		(net "VR_PVCCP_RTN")
	)
	(via
		(at 101.457252 -61.935106)
		(size 0.508)
		(drill 0.254)
		(layers "F.Cu" "B.Cu")
		(net "VR_PVCCP_RTN")
	)
	(via
		(at 23.5966 -51.818032)
		(size 0.508)
		(drill 0.254)
		(layers "F.Cu" "B.Cu")
		(net "VR_PVCCP_RTN")
	)
	(segment
		(start 23.5966 -52.6796)
		(end 23.749 -52.832)
		(width 0.127)
		(layer "B.Cu")
		(net "VR_PVCCP_RTN")
	)
	(segment
		(start 23.5966 -51.818032)
		(end 23.5966 -52.6796)
		(width 0.127)
		(layer "B.Cu")
		(net "VR_PVCCP_RTN")
	)
	(segment
		(start 91.53652 -62.97295)
		(end 69.051678 -62.97295)
		(width 0.127)
		(layer "In9.Cu")
		(net "VR_PVCCP_RTN")
	)
	(segment
		(start 56.923432 -54.9275)
		(end 25.5143 -54.9275)
		(width 0.127)
		(layer "In9.Cu")
		(net "VR_PVCCP_RTN")
	)
	(segment
		(start 23.5712 -51.868578)
		(end 23.5712 -51.843432)
		(width 0.127)
		(layer "In9.Cu")
		(net "VR_PVCCP_RTN")
	)
	(segment
		(start 101.211634 -62.611)
		(end 91.89847 -62.611)
		(width 0.127)
		(layer "In9.Cu")
		(net "VR_PVCCP_RTN")
	)
	(segment
		(start 101.457252 -61.935106)
		(end 101.456236 -62.366398)
		(width 0.127)
		(layer "In9.Cu")
		(net "VR_PVCCP_RTN")
	)
	(segment
		(start 101.456236 -62.366398)
		(end 101.211634 -62.611)
		(width 0.127)
		(layer "In9.Cu")
		(net "VR_PVCCP_RTN")
	)
	(segment
		(start 68.384928 -62.3062)
		(end 66.9798 -62.3062)
		(width 0.127)
		(layer "In9.Cu")
		(net "VR_PVCCP_RTN")
	)
	(segment
		(start 69.051678 -62.97295)
		(end 68.384928 -62.3062)
		(width 0.127)
		(layer "In9.Cu")
		(net "VR_PVCCP_RTN")
	)
	(segment
		(start 60.784232 -58.7883)
		(end 56.923432 -54.9275)
		(width 0.127)
		(layer "In9.Cu")
		(net "VR_PVCCP_RTN")
	)
	(segment
		(start 23.2918 -52.705)
		(end 23.2918 -52.147978)
		(width 0.127)
		(layer "In9.Cu")
		(net "VR_PVCCP_RTN")
	)
	(segment
		(start 23.5712 -51.843432)
		(end 23.5966 -51.818032)
		(width 0.127)
		(layer "In9.Cu")
		(net "VR_PVCCP_RTN")
	)
	(segment
		(start 25.5143 -54.9275)
		(end 23.2918 -52.705)
		(width 0.127)
		(layer "In9.Cu")
		(net "VR_PVCCP_RTN")
	)
	(segment
		(start 63.4619 -58.7883)
		(end 60.784232 -58.7883)
		(width 0.127)
		(layer "In9.Cu")
		(net "VR_PVCCP_RTN")
	)
	(segment
		(start 91.89847 -62.611)
		(end 91.53652 -62.97295)
		(width 0.127)
		(layer "In9.Cu")
		(net "VR_PVCCP_RTN")
	)
	(segment
		(start 66.9798 -62.3062)
		(end 63.4619 -58.7883)
		(width 0.127)
		(layer "In9.Cu")
		(net "VR_PVCCP_RTN")
	)
	(segment
		(start 23.2918 -52.147978)
		(end 23.5712 -51.868578)
		(width 0.127)
		(layer "In9.Cu")
		(net "VR_PVCCP_RTN")
	)
	(segment
		(start 149.361144 -69.39026)
		(end 149.361144 -69.364606)
		(width 0.1778)
		(layer "F.Cu")
		(net "M_A_CS_N3")
	)
	(segment
		(start 99.352608 -48.783494)
		(end 99.323906 -48.783494)
		(width 0.1016)
		(layer "F.Cu")
		(net "M_A_CS_N3")
	)
	(segment
		(start 149.349968 -70.806564)
		(end 149.349968 -69.401436)
		(width 0.1778)
		(layer "F.Cu")
		(net "M_A_CS_N3")
	)
	(segment
		(start 99.323906 -48.783494)
		(end 98.933 -49.1744)
		(width 0.1016)
		(layer "F.Cu")
		(net "M_A_CS_N3")
	)
	(segment
		(start 149.349968 -69.401436)
		(end 149.361144 -69.39026)
		(width 0.1778)
		(layer "F.Cu")
		(net "M_A_CS_N3")
	)
	(via
		(at 149.361144 -69.364606)
		(size 0.4318)
		(drill 0.2032)
		(layers "F.Cu" "B.Cu")
		(net "M_A_CS_N3")
	)
	(via
		(at 98.933 -49.1744)
		(size 0.4318)
		(drill 0.2032)
		(layers "F.Cu" "B.Cu")
		(net "M_A_CS_N3")
	)
	(segment
		(start 143.620998 -65.6082)
		(end 143.620998 -67.0306)
		(width 0.1524)
		(layer "In7.Cu")
		(net "M_A_CS_N3")
	)
	(segment
		(start 145.380202 -65.405)
		(end 144.992598 -65.405)
		(width 0.1524)
		(layer "In7.Cu")
		(net "M_A_CS_N3")
	)
	(segment
		(start 141.2494 -65.024)
		(end 141.2494 -64.0588)
		(width 0.1524)
		(layer "In7.Cu")
		(net "M_A_CS_N3")
	)
	(segment
		(start 144.230598 -66.9798)
		(end 144.230598 -65.6082)
		(width 0.1524)
		(layer "In7.Cu")
		(net "M_A_CS_N3")
	)
	(segment
		(start 146.2024 -68.075556)
		(end 146.2024 -67.8688)
		(width 0.1524)
		(layer "In7.Cu")
		(net "M_A_CS_N3")
	)
	(segment
		(start 144.840198 -66.9798)
		(end 144.687798 -67.1322)
		(width 0.1524)
		(layer "In7.Cu")
		(net "M_A_CS_N3")
	)
	(segment
		(start 146.351244 -68.2244)
		(end 146.2024 -68.075556)
		(width 0.1524)
		(layer "In7.Cu")
		(net "M_A_CS_N3")
	)
	(segment
		(start 140.7668 -63.5762)
		(end 139.573 -63.5762)
		(width 0.1524)
		(layer "In7.Cu")
		(net "M_A_CS_N3")
	)
	(segment
		(start 143.163798 -67.183)
		(end 143.011398 -67.0306)
		(width 0.1524)
		(layer "In7.Cu")
		(net "M_A_CS_N3")
	)
	(segment
		(start 130.004566 -59.91225)
		(end 102.58425 -59.91225)
		(width 0.1524)
		(layer "In7.Cu")
		(net "M_A_CS_N3")
	)
	(segment
		(start 99.5172 -53.455062)
		(end 99.5172 -50.2412)
		(width 0.1016)
		(layer "In7.Cu")
		(net "M_A_CS_N3")
	)
	(segment
		(start 144.382998 -67.1322)
		(end 144.230598 -66.9798)
		(width 0.1524)
		(layer "In7.Cu")
		(net "M_A_CS_N3")
	)
	(segment
		(start 144.992598 -65.405)
		(end 144.840198 -65.5574)
		(width 0.1524)
		(layer "In7.Cu")
		(net "M_A_CS_N3")
	)
	(segment
		(start 143.620998 -67.0306)
		(end 143.468598 -67.183)
		(width 0.1524)
		(layer "In7.Cu")
		(net "M_A_CS_N3")
	)
	(segment
		(start 136.0678 -60.071)
		(end 130.163316 -60.071)
		(width 0.1524)
		(layer "In7.Cu")
		(net "M_A_CS_N3")
	)
	(segment
		(start 146.3548 -67.7164)
		(end 147.0152 -67.7164)
		(width 0.1524)
		(layer "In7.Cu")
		(net "M_A_CS_N3")
	)
	(segment
		(start 100.0252 -57.3532)
		(end 100.0252 -53.963062)
		(width 0.1016)
		(layer "In7.Cu")
		(net "M_A_CS_N3")
	)
	(segment
		(start 145.685002 -66.1162)
		(end 145.532602 -65.9638)
		(width 0.1524)
		(layer "In7.Cu")
		(net "M_A_CS_N3")
	)
	(segment
		(start 143.468598 -67.183)
		(end 143.163798 -67.183)
		(width 0.1524)
		(layer "In7.Cu")
		(net "M_A_CS_N3")
	)
	(segment
		(start 102.58425 -59.91225)
		(end 100.0252 -57.3532)
		(width 0.1524)
		(layer "In7.Cu")
		(net "M_A_CS_N3")
	)
	(segment
		(start 147.0152 -67.7164)
		(end 147.1676 -67.564)
		(width 0.1524)
		(layer "In7.Cu")
		(net "M_A_CS_N3")
	)
	(segment
		(start 146.2024 -67.8688)
		(end 146.3548 -67.7164)
		(width 0.1524)
		(layer "In7.Cu")
		(net "M_A_CS_N3")
	)
	(segment
		(start 147.1676 -67.564)
		(end 147.1676 -65.5574)
		(width 0.1524)
		(layer "In7.Cu")
		(net "M_A_CS_N3")
	)
	(segment
		(start 147.1676 -65.5574)
		(end 147.0152 -65.405)
		(width 0.1524)
		(layer "In7.Cu")
		(net "M_A_CS_N3")
	)
	(segment
		(start 143.773398 -65.4558)
		(end 143.620998 -65.6082)
		(width 0.1524)
		(layer "In7.Cu")
		(net "M_A_CS_N3")
	)
	(segment
		(start 100.0252 -53.963062)
		(end 99.5172 -53.455062)
		(width 0.1016)
		(layer "In7.Cu")
		(net "M_A_CS_N3")
	)
	(segment
		(start 144.078198 -65.4558)
		(end 143.773398 -65.4558)
		(width 0.1524)
		(layer "In7.Cu")
		(net "M_A_CS_N3")
	)
	(segment
		(start 148.765006 -69.364606)
		(end 148.5138 -69.1134)
		(width 0.1524)
		(layer "In7.Cu")
		(net "M_A_CS_N3")
	)
	(segment
		(start 148.5138 -69.1134)
		(end 148.5138 -68.4276)
		(width 0.1524)
		(layer "In7.Cu")
		(net "M_A_CS_N3")
	)
	(segment
		(start 146.2786 -65.5574)
		(end 146.2786 -65.9638)
		(width 0.1524)
		(layer "In7.Cu")
		(net "M_A_CS_N3")
	)
	(segment
		(start 146.1262 -66.1162)
		(end 145.685002 -66.1162)
		(width 0.1524)
		(layer "In7.Cu")
		(net "M_A_CS_N3")
	)
	(segment
		(start 139.573 -63.5762)
		(end 136.0678 -60.071)
		(width 0.1524)
		(layer "In7.Cu")
		(net "M_A_CS_N3")
	)
	(segment
		(start 144.840198 -65.5574)
		(end 144.840198 -66.9798)
		(width 0.1524)
		(layer "In7.Cu")
		(net "M_A_CS_N3")
	)
	(segment
		(start 144.230598 -65.6082)
		(end 144.078198 -65.4558)
		(width 0.1524)
		(layer "In7.Cu")
		(net "M_A_CS_N3")
	)
	(segment
		(start 145.532602 -65.5574)
		(end 145.380202 -65.405)
		(width 0.1524)
		(layer "In7.Cu")
		(net "M_A_CS_N3")
	)
	(segment
		(start 143.011398 -66.049398)
		(end 142.7734 -65.8114)
		(width 0.1524)
		(layer "In7.Cu")
		(net "M_A_CS_N3")
	)
	(segment
		(start 147.0152 -65.405)
		(end 146.431 -65.405)
		(width 0.1524)
		(layer "In7.Cu")
		(net "M_A_CS_N3")
	)
	(segment
		(start 98.933 -49.657)
		(end 98.933 -49.1744)
		(width 0.1016)
		(layer "In7.Cu")
		(net "M_A_CS_N3")
	)
	(segment
		(start 142.0368 -65.8114)
		(end 141.2494 -65.024)
		(width 0.1524)
		(layer "In7.Cu")
		(net "M_A_CS_N3")
	)
	(segment
		(start 145.532602 -65.9638)
		(end 145.532602 -65.5574)
		(width 0.1524)
		(layer "In7.Cu")
		(net "M_A_CS_N3")
	)
	(segment
		(start 144.687798 -67.1322)
		(end 144.382998 -67.1322)
		(width 0.1524)
		(layer "In7.Cu")
		(net "M_A_CS_N3")
	)
	(segment
		(start 142.7734 -65.8114)
		(end 142.0368 -65.8114)
		(width 0.1524)
		(layer "In7.Cu")
		(net "M_A_CS_N3")
	)
	(segment
		(start 141.2494 -64.0588)
		(end 140.7668 -63.5762)
		(width 0.1524)
		(layer "In7.Cu")
		(net "M_A_CS_N3")
	)
	(segment
		(start 143.011398 -67.0306)
		(end 143.011398 -66.049398)
		(width 0.1524)
		(layer "In7.Cu")
		(net "M_A_CS_N3")
	)
	(segment
		(start 146.2786 -65.9638)
		(end 146.1262 -66.1162)
		(width 0.1524)
		(layer "In7.Cu")
		(net "M_A_CS_N3")
	)
	(segment
		(start 146.431 -65.405)
		(end 146.2786 -65.5574)
		(width 0.1524)
		(layer "In7.Cu")
		(net "M_A_CS_N3")
	)
	(segment
		(start 148.5138 -68.4276)
		(end 148.3106 -68.2244)
		(width 0.1524)
		(layer "In7.Cu")
		(net "M_A_CS_N3")
	)
	(segment
		(start 148.3106 -68.2244)
		(end 146.351244 -68.2244)
		(width 0.1524)
		(layer "In7.Cu")
		(net "M_A_CS_N3")
	)
	(segment
		(start 149.361144 -69.364606)
		(end 148.765006 -69.364606)
		(width 0.1524)
		(layer "In7.Cu")
		(net "M_A_CS_N3")
	)
	(segment
		(start 130.163316 -60.071)
		(end 130.004566 -59.91225)
		(width 0.1524)
		(layer "In7.Cu")
		(net "M_A_CS_N3")
	)
	(segment
		(start 99.5172 -50.2412)
		(end 98.933 -49.657)
		(width 0.1016)
		(layer "In7.Cu")
		(net "M_A_CS_N3")
	)
	(segment
		(start 128.050036 -62.59322)
		(end 128.050036 -61.248036)
		(width 0.1143)
		(layer "F.Cu")
		(net "SMB_M_A1_R_DATA")
	)
	(segment
		(start 128.050036 -61.248036)
		(end 127.2032 -60.4012)
		(width 0.1143)
		(layer "F.Cu")
		(net "SMB_M_A1_R_DATA")
	)
	(segment
		(start 127.2032 -60.4012)
		(end 118.9228 -60.4012)
		(width 0.1143)
		(layer "F.Cu")
		(net "SMB_M_A1_R_DATA")
	)
	(segment
		(start 118.9228 -60.4012)
		(end 117.221 -62.103)
		(width 0.1143)
		(layer "F.Cu")
		(net "SMB_M_A1_R_DATA")
	)
	(segment
		(start 117.221 -63.7032)
		(end 117.221 -62.103)
		(width 0.1143)
		(layer "F.Cu")
		(net "SMB_M_A1_R_DATA")
	)
	(segment
		(start 117.475 -63.9572)
		(end 117.221 -63.7032)
		(width 0.1143)
		(layer "F.Cu")
		(net "SMB_M_A1_R_DATA")
	)
	(via
		(at 117.221 -62.103)
		(size 0.7112)
		(drill 0.3556)
		(layers "F.Cu" "B.Cu")
		(net "SMB_M_A1_R_DATA")
	)
	(segment
		(start 20.066 -65.151)
		(end 19.7358 -65.151)
		(width 0.2032)
		(layer "F.Cu")
		(net "VR_PVNN_VSEN_R")
	)
	(segment
		(start 20.8534 -65.9384)
		(end 20.066 -65.151)
		(width 0.2032)
		(layer "F.Cu")
		(net "VR_PVNN_VSEN_R")
	)
	(via
		(at 20.8534 -65.9384)
		(size 0.508)
		(drill 0.254)
		(layers "F.Cu" "B.Cu")
		(net "VR_PVNN_VSEN_R")
	)
	(via
		(at 18.161 -65.151)
		(size 0.7112)
		(drill 0.3556)
		(layers "F.Cu" "B.Cu")
		(net "VR_PVNN_VSEN_R")
	)
	(segment
		(start 17.526 -57.3786)
		(end 17.526 -57.3278)
		(width 0.2032)
		(layer "B.Cu")
		(net "VR_PVNN_VSEN_R")
	)
	(segment
		(start 16.764 -58.1406)
		(end 17.526 -57.3786)
		(width 0.2032)
		(layer "B.Cu")
		(net "VR_PVNN_VSEN_R")
	)
	(segment
		(start 18.161 -64.008)
		(end 16.9545 -62.8015)
		(width 0.2032)
		(layer "B.Cu")
		(net "VR_PVNN_VSEN_R")
	)
	(segment
		(start 17.526 -56.7182)
		(end 17.1958 -56.388)
		(width 0.2032)
		(layer "B.Cu")
		(net "VR_PVNN_VSEN_R")
	)
	(segment
		(start 20.2692 -66.5226)
		(end 18.763234 -66.5226)
		(width 0.2032)
		(layer "B.Cu")
		(net "VR_PVNN_VSEN_R")
	)
	(segment
		(start 16.764 -61.61913)
		(end 16.764 -58.1406)
		(width 0.2032)
		(layer "B.Cu")
		(net "VR_PVNN_VSEN_R")
	)
	(segment
		(start 16.9545 -61.80963)
		(end 16.764 -61.61913)
		(width 0.2032)
		(layer "B.Cu")
		(net "VR_PVNN_VSEN_R")
	)
	(segment
		(start 17.526 -57.3278)
		(end 17.526 -56.7182)
		(width 0.2032)
		(layer "B.Cu")
		(net "VR_PVNN_VSEN_R")
	)
	(segment
		(start 18.763234 -66.5226)
		(end 18.161 -65.920366)
		(width 0.2032)
		(layer "B.Cu")
		(net "VR_PVNN_VSEN_R")
	)
	(segment
		(start 18.161 -65.920366)
		(end 18.161 -65.151)
		(width 0.2032)
		(layer "B.Cu")
		(net "VR_PVNN_VSEN_R")
	)
	(segment
		(start 16.9545 -62.8015)
		(end 16.9545 -61.80963)
		(width 0.2032)
		(layer "B.Cu")
		(net "VR_PVNN_VSEN_R")
	)
	(segment
		(start 18.161 -65.151)
		(end 18.161 -64.008)
		(width 0.2032)
		(layer "B.Cu")
		(net "VR_PVNN_VSEN_R")
	)
	(segment
		(start 20.8534 -65.9384)
		(end 20.2692 -66.5226)
		(width 0.2032)
		(layer "B.Cu")
		(net "VR_PVNN_VSEN_R")
	)
	(segment
		(start 178.74996 -69.831458)
		(end 178.3334 -69.414898)
		(width 0.1778)
		(layer "F.Cu")
		(net "M_A_DQ21")
	)
	(segment
		(start 109.29874 -46.0502)
		(end 109.31144 -46.0629)
		(width 0.1016)
		(layer "F.Cu")
		(net "M_A_DQ21")
	)
	(segment
		(start 109.235494 -46.0502)
		(end 109.29874 -46.0502)
		(width 0.1016)
		(layer "F.Cu")
		(net "M_A_DQ21")
	)
	(segment
		(start 178.149758 -68.777358)
		(end 178.1302 -68.777358)
		(width 0.1778)
		(layer "F.Cu")
		(net "M_A_DQ21")
	)
	(segment
		(start 178.3334 -69.414898)
		(end 178.3334 -68.961)
		(width 0.1778)
		(layer "F.Cu")
		(net "M_A_DQ21")
	)
	(segment
		(start 178.3334 -68.961)
		(end 178.149758 -68.777358)
		(width 0.1778)
		(layer "F.Cu")
		(net "M_A_DQ21")
	)
	(segment
		(start 178.74996 -70.806564)
		(end 178.74996 -69.831458)
		(width 0.1778)
		(layer "F.Cu")
		(net "M_A_DQ21")
	)
	(segment
		(start 108.814108 -45.628814)
		(end 109.235494 -46.0502)
		(width 0.1016)
		(layer "F.Cu")
		(net "M_A_DQ21")
	)
	(via
		(at 178.1302 -68.777358)
		(size 0.4318)
		(drill 0.2032)
		(layers "F.Cu" "B.Cu")
		(net "M_A_DQ21")
	)
	(via
		(at 109.31144 -46.0629)
		(size 0.4318)
		(drill 0.2032)
		(layers "F.Cu" "B.Cu")
		(net "M_A_DQ21")
	)
	(segment
		(start 178.149758 -68.777358)
		(end 178.1302 -68.777358)
		(width 0.1778)
		(layer "B.Cu")
		(net "M_A_DQ21")
	)
	(segment
		(start 177.850038 -70.79996)
		(end 177.850038 -70.053962)
		(width 0.1778)
		(layer "B.Cu")
		(net "M_A_DQ21")
	)
	(segment
		(start 177.850038 -70.053962)
		(end 178.3334 -69.5706)
		(width 0.1778)
		(layer "B.Cu")
		(net "M_A_DQ21")
	)
	(segment
		(start 178.3334 -69.5706)
		(end 178.3334 -68.961)
		(width 0.1778)
		(layer "B.Cu")
		(net "M_A_DQ21")
	)
	(segment
		(start 178.3334 -68.961)
		(end 178.149758 -68.777358)
		(width 0.1778)
		(layer "B.Cu")
		(net "M_A_DQ21")
	)
	(segment
		(start 151.832056 -54.9275)
		(end 152.047448 -54.9275)
		(width 0.1524)
		(layer "In4.Cu")
		(net "M_A_DQ21")
	)
	(segment
		(start 111.7092 -47.2186)
		(end 111.088678 -46.598078)
		(width 0.1016)
		(layer "In4.Cu")
		(net "M_A_DQ21")
	)
	(segment
		(start 150.753572 -53.849016)
		(end 150.969472 -54.064916)
		(width 0.1524)
		(layer "In4.Cu")
		(net "M_A_DQ21")
	)
	(segment
		(start 152.363678 -54.61127)
		(end 152.57907 -54.61127)
		(width 0.1524)
		(layer "In4.Cu")
		(net "M_A_DQ21")
	)
	(segment
		(start 122.117866 -49.657)
		(end 122.549666 -49.2252)
		(width 0.1524)
		(layer "In4.Cu")
		(net "M_A_DQ21")
	)
	(segment
		(start 153.8478 -54.991)
		(end 153.8478 -54.7878)
		(width 0.1524)
		(layer "In4.Cu")
		(net "M_A_DQ21")
	)
	(segment
		(start 109.32414 -46.0756)
		(end 109.31144 -46.0629)
		(width 0.1016)
		(layer "In4.Cu")
		(net "M_A_DQ21")
	)
	(segment
		(start 114.0714 -50.5206)
		(end 117.5004 -50.5206)
		(width 0.1524)
		(layer "In4.Cu")
		(net "M_A_DQ21")
	)
	(segment
		(start 178.1683 -64.240156)
		(end 177.7746 -64.633856)
		(width 0.1524)
		(layer "In4.Cu")
		(net "M_A_DQ21")
	)
	(segment
		(start 170.825414 -60.833)
		(end 175.305212 -60.833)
		(width 0.1524)
		(layer "In4.Cu")
		(net "M_A_DQ21")
	)
	(segment
		(start 154.0002 -54.6354)
		(end 154.305 -54.6354)
		(width 0.1524)
		(layer "In4.Cu")
		(net "M_A_DQ21")
	)
	(segment
		(start 165.692836 -57.768236)
		(end 167.76065 -57.768236)
		(width 0.1524)
		(layer "In4.Cu")
		(net "M_A_DQ21")
	)
	(segment
		(start 122.549666 -49.2252)
		(end 143.365982 -49.2252)
		(width 0.1524)
		(layer "In4.Cu")
		(net "M_A_DQ21")
	)
	(segment
		(start 151.501094 -53.748686)
		(end 151.716486 -53.748686)
		(width 0.1524)
		(layer "In4.Cu")
		(net "M_A_DQ21")
	)
	(segment
		(start 143.365982 -49.2252)
		(end 145.042382 -50.9016)
		(width 0.1524)
		(layer "In4.Cu")
		(net "M_A_DQ21")
	)
	(segment
		(start 111.7092 -47.2186)
		(end 113.7666 -49.276)
		(width 0.1524)
		(layer "In4.Cu")
		(net "M_A_DQ21")
	)
	(segment
		(start 151.069802 -53.317394)
		(end 150.753572 -53.633624)
		(width 0.1524)
		(layer "In4.Cu")
		(net "M_A_DQ21")
	)
	(segment
		(start 154.6098 -55.1434)
		(end 163.068 -55.1434)
		(width 0.1524)
		(layer "In4.Cu")
		(net "M_A_DQ21")
	)
	(segment
		(start 154.4574 -54.991)
		(end 154.6098 -55.1434)
		(width 0.1524)
		(layer "In4.Cu")
		(net "M_A_DQ21")
	)
	(segment
		(start 113.7666 -50.2158)
		(end 114.0714 -50.5206)
		(width 0.1524)
		(layer "In4.Cu")
		(net "M_A_DQ21")
	)
	(segment
		(start 151.069802 -53.102002)
		(end 151.069802 -53.317394)
		(width 0.1524)
		(layer "In4.Cu")
		(net "M_A_DQ21")
	)
	(segment
		(start 151.932386 -53.964586)
		(end 151.932386 -54.179978)
		(width 0.1524)
		(layer "In4.Cu")
		(net "M_A_DQ21")
	)
	(segment
		(start 152.047448 -54.9275)
		(end 152.363678 -54.61127)
		(width 0.1524)
		(layer "In4.Cu")
		(net "M_A_DQ21")
	)
	(segment
		(start 178.1683 -63.696088)
		(end 178.1683 -64.240156)
		(width 0.1524)
		(layer "In4.Cu")
		(net "M_A_DQ21")
	)
	(segment
		(start 154.305 -54.6354)
		(end 154.4574 -54.7878)
		(width 0.1524)
		(layer "In4.Cu")
		(net "M_A_DQ21")
	)
	(segment
		(start 152.57907 -54.61127)
		(end 153.1112 -55.1434)
		(width 0.1524)
		(layer "In4.Cu")
		(net "M_A_DQ21")
	)
	(segment
		(start 110.149386 -46.598078)
		(end 109.626908 -46.0756)
		(width 0.1016)
		(layer "In4.Cu")
		(net "M_A_DQ21")
	)
	(segment
		(start 178.302158 -66.389758)
		(end 178.302158 -68.6054)
		(width 0.1524)
		(layer "In4.Cu")
		(net "M_A_DQ21")
	)
	(segment
		(start 178.302158 -68.6054)
		(end 178.1302 -68.777358)
		(width 0.1524)
		(layer "In4.Cu")
		(net "M_A_DQ21")
	)
	(segment
		(start 153.1112 -55.1434)
		(end 153.6954 -55.1434)
		(width 0.1524)
		(layer "In4.Cu")
		(net "M_A_DQ21")
	)
	(segment
		(start 109.626908 -46.0756)
		(end 109.32414 -46.0756)
		(width 0.1016)
		(layer "In4.Cu")
		(net "M_A_DQ21")
	)
	(segment
		(start 148.8694 -50.9016)
		(end 151.069802 -53.102002)
		(width 0.1524)
		(layer "In4.Cu")
		(net "M_A_DQ21")
	)
	(segment
		(start 177.7746 -65.8622)
		(end 178.302158 -66.389758)
		(width 0.1524)
		(layer "In4.Cu")
		(net "M_A_DQ21")
	)
	(segment
		(start 154.4574 -54.7878)
		(end 154.4574 -54.991)
		(width 0.1524)
		(layer "In4.Cu")
		(net "M_A_DQ21")
	)
	(segment
		(start 167.76065 -57.768236)
		(end 170.825414 -60.833)
		(width 0.1524)
		(layer "In4.Cu")
		(net "M_A_DQ21")
	)
	(segment
		(start 151.932386 -54.179978)
		(end 151.616156 -54.496208)
		(width 0.1524)
		(layer "In4.Cu")
		(net "M_A_DQ21")
	)
	(segment
		(start 175.305212 -60.833)
		(end 178.1683 -63.696088)
		(width 0.1524)
		(layer "In4.Cu")
		(net "M_A_DQ21")
	)
	(segment
		(start 153.8478 -54.7878)
		(end 154.0002 -54.6354)
		(width 0.1524)
		(layer "In4.Cu")
		(net "M_A_DQ21")
	)
	(segment
		(start 111.088678 -46.598078)
		(end 110.149386 -46.598078)
		(width 0.1016)
		(layer "In4.Cu")
		(net "M_A_DQ21")
	)
	(segment
		(start 113.7666 -49.276)
		(end 113.7666 -50.2158)
		(width 0.1524)
		(layer "In4.Cu")
		(net "M_A_DQ21")
	)
	(segment
		(start 151.184864 -54.064916)
		(end 151.501094 -53.748686)
		(width 0.1524)
		(layer "In4.Cu")
		(net "M_A_DQ21")
	)
	(segment
		(start 151.716486 -53.748686)
		(end 151.932386 -53.964586)
		(width 0.1524)
		(layer "In4.Cu")
		(net "M_A_DQ21")
	)
	(segment
		(start 117.5004 -50.5206)
		(end 118.364 -49.657)
		(width 0.1524)
		(layer "In4.Cu")
		(net "M_A_DQ21")
	)
	(segment
		(start 153.6954 -55.1434)
		(end 153.8478 -54.991)
		(width 0.1524)
		(layer "In4.Cu")
		(net "M_A_DQ21")
	)
	(segment
		(start 150.753572 -53.633624)
		(end 150.753572 -53.849016)
		(width 0.1524)
		(layer "In4.Cu")
		(net "M_A_DQ21")
	)
	(segment
		(start 150.969472 -54.064916)
		(end 151.184864 -54.064916)
		(width 0.1524)
		(layer "In4.Cu")
		(net "M_A_DQ21")
	)
	(segment
		(start 145.042382 -50.9016)
		(end 148.8694 -50.9016)
		(width 0.1524)
		(layer "In4.Cu")
		(net "M_A_DQ21")
	)
	(segment
		(start 151.616156 -54.496208)
		(end 151.616156 -54.7116)
		(width 0.1524)
		(layer "In4.Cu")
		(net "M_A_DQ21")
	)
	(segment
		(start 163.068 -55.1434)
		(end 165.692836 -57.768236)
		(width 0.1524)
		(layer "In4.Cu")
		(net "M_A_DQ21")
	)
	(segment
		(start 177.7746 -64.633856)
		(end 177.7746 -65.8622)
		(width 0.1524)
		(layer "In4.Cu")
		(net "M_A_DQ21")
	)
	(segment
		(start 151.616156 -54.7116)
		(end 151.832056 -54.9275)
		(width 0.1524)
		(layer "In4.Cu")
		(net "M_A_DQ21")
	)
	(segment
		(start 118.364 -49.657)
		(end 122.117866 -49.657)
		(width 0.1524)
		(layer "In4.Cu")
		(net "M_A_DQ21")
	)
	(segment
		(start 94.6658 -30.329886)
		(end 94.6658 -30.394402)
		(width 0.1397)
		(layer "F.Cu")
		(net "CLK_100M_CPU_HFHPLL_DN")
	)
	(segment
		(start 94.333568 -29.997654)
		(end 94.6658 -30.329886)
		(width 0.1397)
		(layer "F.Cu")
		(net "CLK_100M_CPU_HFHPLL_DN")
	)
	(via
		(at 94.6658 -30.394402)
		(size 0.4318)
		(drill 0.2032)
		(layers "F.Cu" "B.Cu")
		(net "CLK_100M_CPU_HFHPLL_DN")
	)
	(via
		(at 50.07356 -38.61054)
		(size 0.508)
		(drill 0.254)
		(layers "F.Cu" "B.Cu")
		(net "CLK_100M_CPU_HFHPLL_DN")
	)
	(segment
		(start 49.8856 -39.87546)
		(end 49.403 -39.39286)
		(width 0.1397)
		(layer "B.Cu")
		(net "CLK_100M_CPU_HFHPLL_DN")
	)
	(segment
		(start 49.8856 -41.60266)
		(end 49.8856 -39.87546)
		(width 0.1397)
		(layer "B.Cu")
		(net "CLK_100M_CPU_HFHPLL_DN")
	)
	(segment
		(start 50.5206 -44.32554)
		(end 50.8762 -43.96994)
		(width 0.1397)
		(layer "B.Cu")
		(net "CLK_100M_CPU_HFHPLL_DN")
	)
	(segment
		(start 49.73066 -38.61054)
		(end 50.07356 -38.61054)
		(width 0.1397)
		(layer "B.Cu")
		(net "CLK_100M_CPU_HFHPLL_DN")
	)
	(segment
		(start 50.8762 -43.96994)
		(end 50.8762 -42.59326)
		(width 0.1397)
		(layer "B.Cu")
		(net "CLK_100M_CPU_HFHPLL_DN")
	)
	(segment
		(start 49.403 -38.9382)
		(end 49.73066 -38.61054)
		(width 0.1397)
		(layer "B.Cu")
		(net "CLK_100M_CPU_HFHPLL_DN")
	)
	(segment
		(start 48.668178 -47.097188)
		(end 49.295812 -47.097188)
		(width 0.1397)
		(layer "B.Cu")
		(net "CLK_100M_CPU_HFHPLL_DN")
	)
	(segment
		(start 50.5206 -45.8724)
		(end 50.5206 -44.32554)
		(width 0.1397)
		(layer "B.Cu")
		(net "CLK_100M_CPU_HFHPLL_DN")
	)
	(segment
		(start 49.403 -39.39286)
		(end 49.403 -38.9382)
		(width 0.1397)
		(layer "B.Cu")
		(net "CLK_100M_CPU_HFHPLL_DN")
	)
	(segment
		(start 49.295812 -47.097188)
		(end 50.5206 -45.8724)
		(width 0.1397)
		(layer "B.Cu")
		(net "CLK_100M_CPU_HFHPLL_DN")
	)
	(segment
		(start 50.8762 -42.59326)
		(end 49.8856 -41.60266)
		(width 0.1397)
		(layer "B.Cu")
		(net "CLK_100M_CPU_HFHPLL_DN")
	)
	(segment
		(start 64.26835 -28.400756)
		(end 66.341244 -28.400756)
		(width 0.1143)
		(layer "In4.Cu")
		(net "CLK_100M_CPU_HFHPLL_DN")
	)
	(segment
		(start 70.344284 -27.9781)
		(end 75.206606 -27.9781)
		(width 0.1143)
		(layer "In4.Cu")
		(net "CLK_100M_CPU_HFHPLL_DN")
	)
	(segment
		(start 85.12937 -28.215844)
		(end 87.875364 -28.215844)
		(width 0.1143)
		(layer "In4.Cu")
		(net "CLK_100M_CPU_HFHPLL_DN")
	)
	(segment
		(start 50.07356 -38.26764)
		(end 50.7619 -37.5793)
		(width 0.1143)
		(layer "In4.Cu")
		(net "CLK_100M_CPU_HFHPLL_DN")
	)
	(segment
		(start 55.2577 -33.778698)
		(end 57.019698 -32.0167)
		(width 0.1143)
		(layer "In4.Cu")
		(net "CLK_100M_CPU_HFHPLL_DN")
	)
	(segment
		(start 83.081114 -27.051)
		(end 84.39531 -28.365196)
		(width 0.1143)
		(layer "In4.Cu")
		(net "CLK_100M_CPU_HFHPLL_DN")
	)
	(segment
		(start 68.15455 -26.58745)
		(end 68.953634 -26.58745)
		(width 0.1143)
		(layer "In4.Cu")
		(net "CLK_100M_CPU_HFHPLL_DN")
	)
	(segment
		(start 60.652406 -32.0167)
		(end 64.26835 -28.400756)
		(width 0.1143)
		(layer "In4.Cu")
		(net "CLK_100M_CPU_HFHPLL_DN")
	)
	(segment
		(start 84.980018 -28.365196)
		(end 85.12937 -28.215844)
		(width 0.1143)
		(layer "In4.Cu")
		(net "CLK_100M_CPU_HFHPLL_DN")
	)
	(segment
		(start 87.875364 -28.215844)
		(end 88.51392 -28.8544)
		(width 0.1143)
		(layer "In4.Cu")
		(net "CLK_100M_CPU_HFHPLL_DN")
	)
	(segment
		(start 50.7619 -37.5793)
		(end 53.770022 -37.5793)
		(width 0.1143)
		(layer "In4.Cu")
		(net "CLK_100M_CPU_HFHPLL_DN")
	)
	(segment
		(start 66.341244 -28.400756)
		(end 68.15455 -26.58745)
		(width 0.1143)
		(layer "In4.Cu")
		(net "CLK_100M_CPU_HFHPLL_DN")
	)
	(segment
		(start 76.133706 -27.051)
		(end 83.081114 -27.051)
		(width 0.1143)
		(layer "In4.Cu")
		(net "CLK_100M_CPU_HFHPLL_DN")
	)
	(segment
		(start 88.51392 -29.494226)
		(end 89.061544 -30.04185)
		(width 0.1143)
		(layer "In4.Cu")
		(net "CLK_100M_CPU_HFHPLL_DN")
	)
	(segment
		(start 92.668344 -30.04185)
		(end 93.370146 -30.743652)
		(width 0.1143)
		(layer "In4.Cu")
		(net "CLK_100M_CPU_HFHPLL_DN")
	)
	(segment
		(start 75.206606 -27.9781)
		(end 76.133706 -27.051)
		(width 0.1143)
		(layer "In4.Cu")
		(net "CLK_100M_CPU_HFHPLL_DN")
	)
	(segment
		(start 88.51392 -28.8544)
		(end 88.51392 -29.494226)
		(width 0.1143)
		(layer "In4.Cu")
		(net "CLK_100M_CPU_HFHPLL_DN")
	)
	(segment
		(start 93.370146 -30.743652)
		(end 94.31655 -30.743652)
		(width 0.1143)
		(layer "In4.Cu")
		(net "CLK_100M_CPU_HFHPLL_DN")
	)
	(segment
		(start 55.2577 -36.091622)
		(end 55.2577 -33.778698)
		(width 0.1143)
		(layer "In4.Cu")
		(net "CLK_100M_CPU_HFHPLL_DN")
	)
	(segment
		(start 94.31655 -30.743652)
		(end 94.6658 -30.394402)
		(width 0.1143)
		(layer "In4.Cu")
		(net "CLK_100M_CPU_HFHPLL_DN")
	)
	(segment
		(start 53.770022 -37.5793)
		(end 55.2577 -36.091622)
		(width 0.1143)
		(layer "In4.Cu")
		(net "CLK_100M_CPU_HFHPLL_DN")
	)
	(segment
		(start 57.019698 -32.0167)
		(end 60.652406 -32.0167)
		(width 0.1143)
		(layer "In4.Cu")
		(net "CLK_100M_CPU_HFHPLL_DN")
	)
	(segment
		(start 84.39531 -28.365196)
		(end 84.980018 -28.365196)
		(width 0.1143)
		(layer "In4.Cu")
		(net "CLK_100M_CPU_HFHPLL_DN")
	)
	(segment
		(start 89.061544 -30.04185)
		(end 92.668344 -30.04185)
		(width 0.1143)
		(layer "In4.Cu")
		(net "CLK_100M_CPU_HFHPLL_DN")
	)
	(segment
		(start 50.07356 -38.61054)
		(end 50.07356 -38.26764)
		(width 0.1143)
		(layer "In4.Cu")
		(net "CLK_100M_CPU_HFHPLL_DN")
	)
	(segment
		(start 68.953634 -26.58745)
		(end 70.344284 -27.9781)
		(width 0.1143)
		(layer "In4.Cu")
		(net "CLK_100M_CPU_HFHPLL_DN")
	)
	(segment
		(start 93.8403 -53.85816)
		(end 93.8403 -53.5559)
		(width 0.1016)
		(layer "F.Cu")
		(net "M_A_DQ59")
	)
	(segment
		(start 93.8403 -53.5559)
		(end 94.588584 -52.807616)
		(width 0.1016)
		(layer "F.Cu")
		(net "M_A_DQ59")
	)
	(segment
		(start 129.850134 -64.892174)
		(end 129.95656 -64.9986)
		(width 0.1778)
		(layer "F.Cu")
		(net "M_A_DQ59")
	)
	(segment
		(start 94.588584 -51.47183)
		(end 94.564708 -51.447954)
		(width 0.1016)
		(layer "F.Cu")
		(net "M_A_DQ59")
	)
	(segment
		(start 129.850134 -62.59322)
		(end 129.850134 -64.892174)
		(width 0.1778)
		(layer "F.Cu")
		(net "M_A_DQ59")
	)
	(segment
		(start 129.95656 -64.9986)
		(end 129.95656 -65.012824)
		(width 0.1778)
		(layer "F.Cu")
		(net "M_A_DQ59")
	)
	(segment
		(start 94.588584 -52.807616)
		(end 94.588584 -51.47183)
		(width 0.1016)
		(layer "F.Cu")
		(net "M_A_DQ59")
	)
	(via
		(at 129.95656 -65.012824)
		(size 0.4318)
		(drill 0.2032)
		(layers "F.Cu" "B.Cu")
		(net "M_A_DQ59")
	)
	(via
		(at 93.8403 -53.85816)
		(size 0.4318)
		(drill 0.2032)
		(layers "F.Cu" "B.Cu")
		(net "M_A_DQ59")
	)
	(segment
		(start 130.150108 -62.599824)
		(end 130.150108 -64.819276)
		(width 0.1778)
		(layer "B.Cu")
		(net "M_A_DQ59")
	)
	(segment
		(start 130.150108 -64.819276)
		(end 129.95656 -65.012824)
		(width 0.1778)
		(layer "B.Cu")
		(net "M_A_DQ59")
	)
	(segment
		(start 93.4466 -54.26202)
		(end 93.4466 -56.4134)
		(width 0.1524)
		(layer "In7.Cu")
		(net "M_A_DQ59")
	)
	(segment
		(start 127.5334 -68.8594)
		(end 127.5334 -67.23761)
		(width 0.1524)
		(layer "In7.Cu")
		(net "M_A_DQ59")
	)
	(segment
		(start 92.7354 -64.706246)
		(end 96.130364 -68.10121)
		(width 0.1524)
		(layer "In7.Cu")
		(net "M_A_DQ59")
	)
	(segment
		(start 127.5334 -67.23761)
		(end 127.74041 -67.0306)
		(width 0.1524)
		(layer "In7.Cu")
		(net "M_A_DQ59")
	)
	(segment
		(start 96.130364 -68.10121)
		(end 98.2472 -68.10121)
		(width 0.1524)
		(layer "In7.Cu")
		(net "M_A_DQ59")
	)
	(segment
		(start 98.2472 -68.10121)
		(end 98.92919 -68.7832)
		(width 0.1524)
		(layer "In7.Cu")
		(net "M_A_DQ59")
	)
	(segment
		(start 119.0498 -68.7832)
		(end 119.658892 -69.392292)
		(width 0.1524)
		(layer "In7.Cu")
		(net "M_A_DQ59")
	)
	(segment
		(start 92.7354 -57.1246)
		(end 92.7354 -64.706246)
		(width 0.1524)
		(layer "In7.Cu")
		(net "M_A_DQ59")
	)
	(segment
		(start 127.000508 -69.392292)
		(end 127.5334 -68.8594)
		(width 0.1524)
		(layer "In7.Cu")
		(net "M_A_DQ59")
	)
	(segment
		(start 93.4466 -56.4134)
		(end 92.7354 -57.1246)
		(width 0.1524)
		(layer "In7.Cu")
		(net "M_A_DQ59")
	)
	(segment
		(start 128.5748 -67.0306)
		(end 129.0066 -66.5988)
		(width 0.1524)
		(layer "In7.Cu")
		(net "M_A_DQ59")
	)
	(segment
		(start 119.658892 -69.392292)
		(end 127.000508 -69.392292)
		(width 0.1524)
		(layer "In7.Cu")
		(net "M_A_DQ59")
	)
	(segment
		(start 98.92919 -68.7832)
		(end 119.0498 -68.7832)
		(width 0.1524)
		(layer "In7.Cu")
		(net "M_A_DQ59")
	)
	(segment
		(start 127.74041 -67.0306)
		(end 128.5748 -67.0306)
		(width 0.1524)
		(layer "In7.Cu")
		(net "M_A_DQ59")
	)
	(segment
		(start 129.0066 -66.5988)
		(end 129.0066 -65.962784)
		(width 0.1524)
		(layer "In7.Cu")
		(net "M_A_DQ59")
	)
	(segment
		(start 93.8403 -53.86832)
		(end 93.4466 -54.26202)
		(width 0.1524)
		(layer "In7.Cu")
		(net "M_A_DQ59")
	)
	(segment
		(start 129.0066 -65.962784)
		(end 129.95656 -65.012824)
		(width 0.1524)
		(layer "In7.Cu")
		(net "M_A_DQ59")
	)
	(segment
		(start 93.8403 -53.85816)
		(end 93.8403 -53.86832)
		(width 0.1524)
		(layer "In7.Cu")
		(net "M_A_DQ59")
	)
	(segment
		(start 24.3586 -51.7906)
		(end 24.2824 -51.8668)
		(width 0.2032)
		(layer "F.Cu")
		(net "VR_PVCCP_ISUMN_R")
	)
	(segment
		(start 24.2824 -53.086508)
		(end 23.876508 -53.4924)
		(width 0.2032)
		(layer "F.Cu")
		(net "VR_PVCCP_ISUMN_R")
	)
	(segment
		(start 22.062948 -54.463442)
		(end 22.72919 -53.7972)
		(width 0.2032)
		(layer "F.Cu")
		(net "VR_PVCCP_ISUMN_R")
	)
	(segment
		(start 24.2824 -52.6034)
		(end 24.2824 -53.086508)
		(width 0.2032)
		(layer "F.Cu")
		(net "VR_PVCCP_ISUMN_R")
	)
	(segment
		(start 22.062948 -55.547006)
		(end 22.062948 -54.463442)
		(width 0.2032)
		(layer "F.Cu")
		(net "VR_PVCCP_ISUMN_R")
	)
	(segment
		(start 24.2824 -51.8668)
		(end 24.2824 -52.6034)
		(width 0.2032)
		(layer "F.Cu")
		(net "VR_PVCCP_ISUMN_R")
	)
	(segment
		(start 23.571708 -53.7972)
		(end 23.876508 -53.4924)
		(width 0.2032)
		(layer "F.Cu")
		(net "VR_PVCCP_ISUMN_R")
	)
	(segment
		(start 22.72919 -53.7972)
		(end 23.571708 -53.7972)
		(width 0.2032)
		(layer "F.Cu")
		(net "VR_PVCCP_ISUMN_R")
	)
	(via
		(at 23.876508 -53.4924)
		(size 0.7112)
		(drill 0.3556)
		(layers "F.Cu" "B.Cu")
		(net "VR_PVCCP_ISUMN_R")
	)
	(segment
		(start 97.72396 -45.74032)
		(end 97.7138 -45.73016)
		(width 0.1016)
		(layer "F.Cu")
		(net "M_A_DQ37")
	)
	(segment
		(start 97.7138 -45.73016)
		(end 97.7138 -45.6946)
		(width 0.1016)
		(layer "F.Cu")
		(net "M_A_DQ37")
	)
	(segment
		(start 97.7138 -45.6946)
		(end 97.373694 -45.354494)
		(width 0.1016)
		(layer "F.Cu")
		(net "M_A_DQ37")
	)
	(segment
		(start 147.550124 -70.806564)
		(end 147.550124 -69.521324)
		(width 0.1778)
		(layer "F.Cu")
		(net "M_A_DQ37")
	)
	(segment
		(start 147.550124 -69.521324)
		(end 147.3708 -69.342)
		(width 0.1778)
		(layer "F.Cu")
		(net "M_A_DQ37")
	)
	(segment
		(start 97.373694 -45.354494)
		(end 97.366328 -45.354494)
		(width 0.1016)
		(layer "F.Cu")
		(net "M_A_DQ37")
	)
	(via
		(at 147.3708 -69.342)
		(size 0.4318)
		(drill 0.2032)
		(layers "F.Cu" "B.Cu")
		(net "M_A_DQ37")
	)
	(via
		(at 97.72396 -45.74032)
		(size 0.4318)
		(drill 0.2032)
		(layers "F.Cu" "B.Cu")
		(net "M_A_DQ37")
	)
	(segment
		(start 147.25015 -69.46265)
		(end 147.3708 -69.342)
		(width 0.1778)
		(layer "B.Cu")
		(net "M_A_DQ37")
	)
	(segment
		(start 147.25015 -70.79996)
		(end 147.25015 -69.46265)
		(width 0.1778)
		(layer "B.Cu")
		(net "M_A_DQ37")
	)
	(segment
		(start 106.68 -52.3748)
		(end 106.0704 -51.7652)
		(width 0.1524)
		(layer "In4.Cu")
		(net "M_A_DQ37")
	)
	(segment
		(start 124.00788 -54.3052)
		(end 119.131334 -54.3052)
		(width 0.1524)
		(layer "In4.Cu")
		(net "M_A_DQ37")
	)
	(segment
		(start 102.483158 -50.577242)
		(end 101.705918 -49.800002)
		(width 0.1524)
		(layer "In4.Cu")
		(net "M_A_DQ37")
	)
	(segment
		(start 146.9136 -68.40474)
		(end 147.0914 -68.22694)
		(width 0.1524)
		(layer "In4.Cu")
		(net "M_A_DQ37")
	)
	(segment
		(start 101.284278 -47.245524)
		(end 101.2825 -47.243746)
		(width 0.1016)
		(layer "In4.Cu")
		(net "M_A_DQ37")
	)
	(segment
		(start 126.238 -54.229)
		(end 125.939804 -54.229)
		(width 0.1524)
		(layer "In4.Cu")
		(net "M_A_DQ37")
	)
	(segment
		(start 127.762 -54.229)
		(end 127.381 -54.229)
		(width 0.1524)
		(layer "In4.Cu")
		(net "M_A_DQ37")
	)
	(segment
		(start 138.582654 -54.102)
		(end 136.5504 -54.102)
		(width 0.1524)
		(layer "In4.Cu")
		(net "M_A_DQ37")
	)
	(segment
		(start 126.619 -53.848)
		(end 126.238 -54.229)
		(width 0.1524)
		(layer "In4.Cu")
		(net "M_A_DQ37")
	)
	(segment
		(start 101.2825 -46.8503)
		(end 100.8126 -46.3804)
		(width 0.1016)
		(layer "In4.Cu")
		(net "M_A_DQ37")
	)
	(segment
		(start 101.2825 -47.243746)
		(end 101.2825 -46.8503)
		(width 0.1016)
		(layer "In4.Cu")
		(net "M_A_DQ37")
	)
	(segment
		(start 101.284278 -47.537878)
		(end 101.284278 -47.245524)
		(width 0.1016)
		(layer "In4.Cu")
		(net "M_A_DQ37")
	)
	(segment
		(start 132.459222 -54.102)
		(end 132.205222 -54.356)
		(width 0.1524)
		(layer "In4.Cu")
		(net "M_A_DQ37")
	)
	(segment
		(start 135.967724 -54.356)
		(end 135.713724 -54.102)
		(width 0.1524)
		(layer "In4.Cu")
		(net "M_A_DQ37")
	)
	(segment
		(start 144.385538 -55.5244)
		(end 143.126968 -55.5244)
		(width 0.1524)
		(layer "In4.Cu")
		(net "M_A_DQ37")
	)
	(segment
		(start 147.3708 -69.342)
		(end 146.9136 -68.8848)
		(width 0.1524)
		(layer "In4.Cu")
		(net "M_A_DQ37")
	)
	(segment
		(start 128.143 -53.848)
		(end 127.762 -54.229)
		(width 0.1524)
		(layer "In4.Cu")
		(net "M_A_DQ37")
	)
	(segment
		(start 130.382264 -54.102)
		(end 129.874264 -54.61)
		(width 0.1524)
		(layer "In4.Cu")
		(net "M_A_DQ37")
	)
	(segment
		(start 127 -53.848)
		(end 126.619 -53.848)
		(width 0.1524)
		(layer "In4.Cu")
		(net "M_A_DQ37")
	)
	(segment
		(start 104.018842 -50.577242)
		(end 102.483158 -50.577242)
		(width 0.1524)
		(layer "In4.Cu")
		(net "M_A_DQ37")
	)
	(segment
		(start 131.445 -54.102)
		(end 130.382264 -54.102)
		(width 0.1524)
		(layer "In4.Cu")
		(net "M_A_DQ37")
	)
	(segment
		(start 97.72396 -45.70984)
		(end 97.72396 -45.74032)
		(width 0.1016)
		(layer "In4.Cu")
		(net "M_A_DQ37")
	)
	(segment
		(start 100.6348 -46.3804)
		(end 99.6315 -45.3771)
		(width 0.1016)
		(layer "In4.Cu")
		(net "M_A_DQ37")
	)
	(segment
		(start 147.0914 -67.47002)
		(end 147.2438 -67.31762)
		(width 0.1524)
		(layer "In4.Cu")
		(net "M_A_DQ37")
	)
	(segment
		(start 106.0704 -51.7652)
		(end 105.2068 -51.7652)
		(width 0.1524)
		(layer "In4.Cu")
		(net "M_A_DQ37")
	)
	(segment
		(start 143.126968 -55.5244)
		(end 142.160498 -54.55793)
		(width 0.1524)
		(layer "In4.Cu")
		(net "M_A_DQ37")
	)
	(segment
		(start 147.7518 -66.5226)
		(end 147.7518 -65.9384)
		(width 0.1524)
		(layer "In4.Cu")
		(net "M_A_DQ37")
	)
	(segment
		(start 148.1328 -59.932316)
		(end 148.1328 -59.271662)
		(width 0.1524)
		(layer "In4.Cu")
		(net "M_A_DQ37")
	)
	(segment
		(start 108.01604 -52.565046)
		(end 108.014262 -52.565046)
		(width 0.1524)
		(layer "In4.Cu")
		(net "M_A_DQ37")
	)
	(segment
		(start 101.705918 -49.800002)
		(end 101.705918 -48.22825)
		(width 0.1524)
		(layer "In4.Cu")
		(net "M_A_DQ37")
	)
	(segment
		(start 136.2964 -54.356)
		(end 135.967724 -54.356)
		(width 0.1524)
		(layer "In4.Cu")
		(net "M_A_DQ37")
	)
	(segment
		(start 131.699 -54.356)
		(end 131.445 -54.102)
		(width 0.1524)
		(layer "In4.Cu")
		(net "M_A_DQ37")
	)
	(segment
		(start 118.902734 -54.5338)
		(end 109.3978 -54.5338)
		(width 0.1524)
		(layer "In4.Cu")
		(net "M_A_DQ37")
	)
	(segment
		(start 148.3106 -67.16522)
		(end 148.3106 -66.8274)
		(width 0.1524)
		(layer "In4.Cu")
		(net "M_A_DQ37")
	)
	(segment
		(start 146.9136 -68.8848)
		(end 146.9136 -68.40474)
		(width 0.1524)
		(layer "In4.Cu")
		(net "M_A_DQ37")
	)
	(segment
		(start 98.0567 -45.3771)
		(end 97.72396 -45.70984)
		(width 0.1016)
		(layer "In4.Cu")
		(net "M_A_DQ37")
	)
	(segment
		(start 148.1328 -59.271662)
		(end 144.385538 -55.5244)
		(width 0.1524)
		(layer "In4.Cu")
		(net "M_A_DQ37")
	)
	(segment
		(start 135.713724 -54.102)
		(end 132.459222 -54.102)
		(width 0.1524)
		(layer "In4.Cu")
		(net "M_A_DQ37")
	)
	(segment
		(start 129.286 -54.61)
		(end 128.524 -53.848)
		(width 0.1524)
		(layer "In4.Cu")
		(net "M_A_DQ37")
	)
	(segment
		(start 139.038584 -54.55793)
		(end 138.582654 -54.102)
		(width 0.1524)
		(layer "In4.Cu")
		(net "M_A_DQ37")
	)
	(segment
		(start 101.705918 -47.959518)
		(end 101.284278 -47.537878)
		(width 0.1016)
		(layer "In4.Cu")
		(net "M_A_DQ37")
	)
	(segment
		(start 125.558804 -53.848)
		(end 124.46508 -53.848)
		(width 0.1524)
		(layer "In4.Cu")
		(net "M_A_DQ37")
	)
	(segment
		(start 99.6315 -45.3771)
		(end 98.0567 -45.3771)
		(width 0.1016)
		(layer "In4.Cu")
		(net "M_A_DQ37")
	)
	(segment
		(start 109.093 -53.642006)
		(end 108.01604 -52.565046)
		(width 0.1524)
		(layer "In4.Cu")
		(net "M_A_DQ37")
	)
	(segment
		(start 108.014262 -52.565046)
		(end 107.824016 -52.3748)
		(width 0.1524)
		(layer "In4.Cu")
		(net "M_A_DQ37")
	)
	(segment
		(start 142.160498 -54.55793)
		(end 139.038584 -54.55793)
		(width 0.1524)
		(layer "In4.Cu")
		(net "M_A_DQ37")
	)
	(segment
		(start 147.9042 -66.675)
		(end 147.7518 -66.5226)
		(width 0.1524)
		(layer "In4.Cu")
		(net "M_A_DQ37")
	)
	(segment
		(start 101.705918 -48.22825)
		(end 101.705918 -47.959518)
		(width 0.1016)
		(layer "In4.Cu")
		(net "M_A_DQ37")
	)
	(segment
		(start 136.5504 -54.102)
		(end 136.2964 -54.356)
		(width 0.1524)
		(layer "In4.Cu")
		(net "M_A_DQ37")
	)
	(segment
		(start 129.874264 -54.61)
		(end 129.286 -54.61)
		(width 0.1524)
		(layer "In4.Cu")
		(net "M_A_DQ37")
	)
	(segment
		(start 109.3978 -54.5338)
		(end 109.093 -54.229)
		(width 0.1524)
		(layer "In4.Cu")
		(net "M_A_DQ37")
	)
	(segment
		(start 125.939804 -54.229)
		(end 125.558804 -53.848)
		(width 0.1524)
		(layer "In4.Cu")
		(net "M_A_DQ37")
	)
	(segment
		(start 147.0914 -68.22694)
		(end 147.0914 -67.47002)
		(width 0.1524)
		(layer "In4.Cu")
		(net "M_A_DQ37")
	)
	(segment
		(start 127.381 -54.229)
		(end 127 -53.848)
		(width 0.1524)
		(layer "In4.Cu")
		(net "M_A_DQ37")
	)
	(segment
		(start 147.7518 -65.9384)
		(end 148.3233 -65.3669)
		(width 0.1524)
		(layer "In4.Cu")
		(net "M_A_DQ37")
	)
	(segment
		(start 148.1582 -67.31762)
		(end 148.3106 -67.16522)
		(width 0.1524)
		(layer "In4.Cu")
		(net "M_A_DQ37")
	)
	(segment
		(start 147.2438 -67.31762)
		(end 148.1582 -67.31762)
		(width 0.1524)
		(layer "In4.Cu")
		(net "M_A_DQ37")
	)
	(segment
		(start 100.8126 -46.3804)
		(end 100.6348 -46.3804)
		(width 0.1016)
		(layer "In4.Cu")
		(net "M_A_DQ37")
	)
	(segment
		(start 148.3233 -65.3669)
		(end 148.3233 -60.122816)
		(width 0.1524)
		(layer "In4.Cu")
		(net "M_A_DQ37")
	)
	(segment
		(start 128.524 -53.848)
		(end 128.143 -53.848)
		(width 0.1524)
		(layer "In4.Cu")
		(net "M_A_DQ37")
	)
	(segment
		(start 148.3233 -60.122816)
		(end 148.1328 -59.932316)
		(width 0.1524)
		(layer "In4.Cu")
		(net "M_A_DQ37")
	)
	(segment
		(start 107.824016 -52.3748)
		(end 106.68 -52.3748)
		(width 0.1524)
		(layer "In4.Cu")
		(net "M_A_DQ37")
	)
	(segment
		(start 148.1582 -66.675)
		(end 147.9042 -66.675)
		(width 0.1524)
		(layer "In4.Cu")
		(net "M_A_DQ37")
	)
	(segment
		(start 105.2068 -51.7652)
		(end 104.018842 -50.577242)
		(width 0.1524)
		(layer "In4.Cu")
		(net "M_A_DQ37")
	)
	(segment
		(start 124.46508 -53.848)
		(end 124.00788 -54.3052)
		(width 0.1524)
		(layer "In4.Cu")
		(net "M_A_DQ37")
	)
	(segment
		(start 119.131334 -54.3052)
		(end 118.902734 -54.5338)
		(width 0.1524)
		(layer "In4.Cu")
		(net "M_A_DQ37")
	)
	(segment
		(start 109.093 -54.229)
		(end 109.093 -53.642006)
		(width 0.1524)
		(layer "In4.Cu")
		(net "M_A_DQ37")
	)
	(segment
		(start 148.3106 -66.8274)
		(end 148.1582 -66.675)
		(width 0.1524)
		(layer "In4.Cu")
		(net "M_A_DQ37")
	)
	(segment
		(start 132.205222 -54.356)
		(end 131.699 -54.356)
		(width 0.1524)
		(layer "In4.Cu")
		(net "M_A_DQ37")
	)
	(segment
		(start 19.812 -68.326)
		(end 19.5834 -68.326)
		(width 0.2032)
		(layer "F.Cu")
		(net "VR_PVNN_ISUMP")
	)
	(segment
		(start 20.863052 -61.292994)
		(end 20.863052 -62.569852)
		(width 0.2032)
		(layer "F.Cu")
		(net "VR_PVNN_ISUMP")
	)
	(segment
		(start 18.2372 -68.2752)
		(end 18.6944 -67.818)
		(width 0.2032)
		(layer "F.Cu")
		(net "VR_PVNN_ISUMP")
	)
	(segment
		(start 18.6944 -67.818)
		(end 18.6944 -67.591686)
		(width 0.2032)
		(layer "F.Cu")
		(net "VR_PVNN_ISUMP")
	)
	(segment
		(start 19.560286 -67.591686)
		(end 19.5834 -67.6148)
		(width 0.2032)
		(layer "F.Cu")
		(net "VR_PVNN_ISUMP")
	)
	(segment
		(start 18.6944 -67.591686)
		(end 19.560286 -67.591686)
		(width 0.2032)
		(layer "F.Cu")
		(net "VR_PVNN_ISUMP")
	)
	(segment
		(start 20.863052 -62.569852)
		(end 20.9296 -62.6364)
		(width 0.2032)
		(layer "F.Cu")
		(net "VR_PVNN_ISUMP")
	)
	(segment
		(start 19.5834 -67.6148)
		(end 20.3708 -67.6148)
		(width 0.2032)
		(layer "F.Cu")
		(net "VR_PVNN_ISUMP")
	)
	(segment
		(start 20.3708 -67.7672)
		(end 19.812 -68.326)
		(width 0.2032)
		(layer "F.Cu")
		(net "VR_PVNN_ISUMP")
	)
	(segment
		(start 20.3708 -67.6148)
		(end 20.3708 -67.7672)
		(width 0.2032)
		(layer "F.Cu")
		(net "VR_PVNN_ISUMP")
	)
	(via
		(at 21.3868 -64.897)
		(size 0.7112)
		(drill 0.3556)
		(layers "F.Cu" "B.Cu")
		(net "VR_PVNN_ISUMP")
	)
	(via
		(at 18.2372 -68.2752)
		(size 0.508)
		(drill 0.254)
		(layers "F.Cu" "B.Cu")
		(net "VR_PVNN_ISUMP")
	)
	(via
		(at 20.9296 -62.6364)
		(size 0.508)
		(drill 0.254)
		(layers "F.Cu" "B.Cu")
		(net "VR_PVNN_ISUMP")
	)
	(segment
		(start 18.2372 -68.2752)
		(end 18.8976 -67.6148)
		(width 0.2032)
		(layer "B.Cu")
		(net "VR_PVNN_ISUMP")
	)
	(segment
		(start 21.3868 -63.2968)
		(end 21.3868 -64.897)
		(width 0.2032)
		(layer "B.Cu")
		(net "VR_PVNN_ISUMP")
	)
	(segment
		(start 18.8976 -67.6148)
		(end 20.1422 -67.6148)
		(width 0.2032)
		(layer "B.Cu")
		(net "VR_PVNN_ISUMP")
	)
	(segment
		(start 21.3868 -66.3702)
		(end 21.3868 -64.897)
		(width 0.2032)
		(layer "B.Cu")
		(net "VR_PVNN_ISUMP")
	)
	(segment
		(start 20.9296 -62.8396)
		(end 21.3868 -63.2968)
		(width 0.2032)
		(layer "B.Cu")
		(net "VR_PVNN_ISUMP")
	)
	(segment
		(start 20.9296 -62.6364)
		(end 20.9296 -62.8396)
		(width 0.2032)
		(layer "B.Cu")
		(net "VR_PVNN_ISUMP")
	)
	(segment
		(start 20.1422 -67.6148)
		(end 21.3868 -66.3702)
		(width 0.2032)
		(layer "B.Cu")
		(net "VR_PVNN_ISUMP")
	)
	(segment
		(start 22.4028 -61.5188)
		(end 21.2852 -62.6364)
		(width 0.2032)
		(layer "B.Cu")
		(net "VR_PVNN_ISUMP")
	)
	(segment
		(start 21.2852 -62.6364)
		(end 20.9296 -62.6364)
		(width 0.2032)
		(layer "B.Cu")
		(net "VR_PVNN_ISUMP")
	)
	(segment
		(start 106.884216 -41.315386)
		(end 106.929936 -41.315386)
		(width 0.1016)
		(layer "F.Cu")
		(net "M_A_DQS_DP0")
	)
	(segment
		(start 186.8932 -66.511678)
		(end 186.732672 -66.672206)
		(width 0.1778)
		(layer "F.Cu")
		(net "M_A_DQS_DP0")
	)
	(segment
		(start 187.105798 -63.591948)
		(end 187.105798 -64.938402)
		(width 0.1778)
		(layer "F.Cu")
		(net "M_A_DQS_DP0")
	)
	(segment
		(start 106.929936 -41.315386)
		(end 107.290108 -40.955214)
		(width 0.1016)
		(layer "F.Cu")
		(net "M_A_DQS_DP0")
	)
	(segment
		(start 187.105798 -64.938402)
		(end 186.8932 -65.151)
		(width 0.1778)
		(layer "F.Cu")
		(net "M_A_DQS_DP0")
	)
	(segment
		(start 186.85002 -62.59322)
		(end 186.85002 -63.33617)
		(width 0.1778)
		(layer "F.Cu")
		(net "M_A_DQS_DP0")
	)
	(segment
		(start 186.85002 -63.33617)
		(end 187.105798 -63.591948)
		(width 0.1778)
		(layer "F.Cu")
		(net "M_A_DQS_DP0")
	)
	(segment
		(start 186.8932 -65.151)
		(end 186.8932 -66.511678)
		(width 0.1778)
		(layer "F.Cu")
		(net "M_A_DQS_DP0")
	)
	(via
		(at 186.732672 -66.672206)
		(size 0.4318)
		(drill 0.2032)
		(layers "F.Cu" "B.Cu")
		(net "M_A_DQS_DP0")
	)
	(via
		(at 106.884216 -41.315386)
		(size 0.4318)
		(drill 0.2032)
		(layers "F.Cu" "B.Cu")
		(net "M_A_DQS_DP0")
	)
	(segment
		(start 186.997594 -69.87921)
		(end 186.997594 -66.937128)
		(width 0.1778)
		(layer "B.Cu")
		(net "M_A_DQS_DP0")
	)
	(segment
		(start 186.997594 -66.937128)
		(end 186.732672 -66.672206)
		(width 0.1778)
		(layer "B.Cu")
		(net "M_A_DQS_DP0")
	)
	(segment
		(start 186.85002 -70.79996)
		(end 186.85002 -70.026784)
		(width 0.1778)
		(layer "B.Cu")
		(net "M_A_DQS_DP0")
	)
	(segment
		(start 186.85002 -70.026784)
		(end 186.997594 -69.87921)
		(width 0.1778)
		(layer "B.Cu")
		(net "M_A_DQS_DP0")
	)
	(segment
		(start 112.076484 -41.961562)
		(end 111.429292 -41.961562)
		(width 0.1016)
		(layer "In7.Cu")
		(net "M_A_DQS_DP0")
	)
	(segment
		(start 166.822628 -51.252628)
		(end 166.390828 -50.820828)
		(width 0.1524)
		(layer "In7.Cu")
		(net "M_A_DQS_DP0")
	)
	(segment
		(start 172.301408 -54.776116)
		(end 172.301408 -54.600094)
		(width 0.1524)
		(layer "In7.Cu")
		(net "M_A_DQS_DP0")
	)
	(segment
		(start 177.360072 -58.794142)
		(end 177.360072 -58.61812)
		(width 0.1524)
		(layer "In7.Cu")
		(net "M_A_DQS_DP0")
	)
	(segment
		(start 182.306976 -62.4078)
		(end 181.983634 -62.084458)
		(width 0.1524)
		(layer "In7.Cu")
		(net "M_A_DQS_DP0")
	)
	(segment
		(start 180.661818 -60.762642)
		(end 179.360576 -59.4614)
		(width 0.1524)
		(layer "In7.Cu")
		(net "M_A_DQS_DP0")
	)
	(segment
		(start 187.01004 -66.394838)
		(end 187.01004 -65.223136)
		(width 0.1524)
		(layer "In7.Cu")
		(net "M_A_DQS_DP0")
	)
	(segment
		(start 166.189406 -52.101242)
		(end 166.822628 -51.46802)
		(width 0.1524)
		(layer "In7.Cu")
		(net "M_A_DQS_DP0")
	)
	(segment
		(start 109.938566 -41.402762)
		(end 108.178092 -41.402762)
		(width 0.1016)
		(layer "In7.Cu")
		(net "M_A_DQS_DP0")
	)
	(segment
		(start 171.35729 -53.655976)
		(end 171.033948 -53.332634)
		(width 0.1524)
		(layer "In7.Cu")
		(net "M_A_DQS_DP0")
	)
	(segment
		(start 171.35729 -53.831998)
		(end 171.35729 -53.655976)
		(width 0.1524)
		(layer "In7.Cu")
		(net "M_A_DQS_DP0")
	)
	(segment
		(start 185.817002 -63.015876)
		(end 184.750456 -62.4078)
		(width 0.1524)
		(layer "In7.Cu")
		(net "M_A_DQS_DP0")
	)
	(segment
		(start 175.4124 -57.3786)
		(end 174.906432 -56.872632)
		(width 0.1524)
		(layer "In7.Cu")
		(net "M_A_DQS_DP0")
	)
	(segment
		(start 171.033948 -53.332634)
		(end 166.973758 -53.332634)
		(width 0.1524)
		(layer "In7.Cu")
		(net "M_A_DQS_DP0")
	)
	(segment
		(start 108.178092 -41.402762)
		(end 107.89793 -41.1226)
		(width 0.1016)
		(layer "In7.Cu")
		(net "M_A_DQS_DP0")
	)
	(segment
		(start 186.417204 -63.48603)
		(end 186.20613 -63.320676)
		(width 0.1524)
		(layer "In7.Cu")
		(net "M_A_DQS_DP0")
	)
	(segment
		(start 172.62475 -55.099458)
		(end 172.301408 -54.776116)
		(width 0.1524)
		(layer "In7.Cu")
		(net "M_A_DQS_DP0")
	)
	(segment
		(start 178.203352 -59.4614)
		(end 177.859182 -59.11723)
		(width 0.1524)
		(layer "In7.Cu")
		(net "M_A_DQS_DP0")
	)
	(segment
		(start 179.360576 -59.4614)
		(end 178.203352 -59.4614)
		(width 0.1524)
		(layer "In7.Cu")
		(net "M_A_DQS_DP0")
	)
	(segment
		(start 184.750456 -62.4078)
		(end 182.306976 -62.4078)
		(width 0.1524)
		(layer "In7.Cu")
		(net "M_A_DQS_DP0")
	)
	(segment
		(start 165.542214 -51.45405)
		(end 165.095174 -51.45405)
		(width 0.1524)
		(layer "In7.Cu")
		(net "M_A_DQS_DP0")
	)
	(segment
		(start 187.198 -65.035176)
		(end 187.198 -64.192404)
		(width 0.1524)
		(layer "In7.Cu")
		(net "M_A_DQS_DP0")
	)
	(segment
		(start 187.01004 -65.223136)
		(end 187.198 -65.035176)
		(width 0.1524)
		(layer "In7.Cu")
		(net "M_A_DQS_DP0")
	)
	(segment
		(start 171.680632 -54.15534)
		(end 171.35729 -53.831998)
		(width 0.1524)
		(layer "In7.Cu")
		(net "M_A_DQS_DP0")
	)
	(segment
		(start 171.856654 -54.15534)
		(end 171.680632 -54.15534)
		(width 0.1524)
		(layer "In7.Cu")
		(net "M_A_DQS_DP0")
	)
	(segment
		(start 181.161182 -61.262006)
		(end 180.98516 -61.262006)
		(width 0.1524)
		(layer "In7.Cu")
		(net "M_A_DQS_DP0")
	)
	(segment
		(start 186.732672 -66.672206)
		(end 187.01004 -66.394838)
		(width 0.1524)
		(layer "In7.Cu")
		(net "M_A_DQS_DP0")
	)
	(segment
		(start 174.906432 -56.872632)
		(end 174.906432 -56.124856)
		(width 0.1524)
		(layer "In7.Cu")
		(net "M_A_DQS_DP0")
	)
	(segment
		(start 181.983634 -62.084458)
		(end 181.807612 -62.084458)
		(width 0.1524)
		(layer "In7.Cu")
		(net "M_A_DQS_DP0")
	)
	(segment
		(start 187.198 -64.192404)
		(end 186.758326 -63.75273)
		(width 0.1524)
		(layer "In7.Cu")
		(net "M_A_DQS_DP0")
	)
	(segment
		(start 186.205114 -63.319914)
		(end 185.817002 -63.015876)
		(width 0.1524)
		(layer "In7.Cu")
		(net "M_A_DQS_DP0")
	)
	(segment
		(start 176.120552 -57.3786)
		(end 175.4124 -57.3786)
		(width 0.1524)
		(layer "In7.Cu")
		(net "M_A_DQS_DP0")
	)
	(segment
		(start 166.175436 -50.820828)
		(end 165.542214 -51.45405)
		(width 0.1524)
		(layer "In7.Cu")
		(net "M_A_DQS_DP0")
	)
	(segment
		(start 113.653824 -41.5798)
		(end 113.212626 -42.020998)
		(width 0.1524)
		(layer "In7.Cu")
		(net "M_A_DQS_DP0")
	)
	(segment
		(start 181.48427 -61.761116)
		(end 181.48427 -61.585094)
		(width 0.1524)
		(layer "In7.Cu")
		(net "M_A_DQS_DP0")
	)
	(segment
		(start 180.661818 -60.938664)
		(end 180.661818 -60.762642)
		(width 0.1524)
		(layer "In7.Cu")
		(net "M_A_DQS_DP0")
	)
	(segment
		(start 186.758326 -63.75273)
		(end 186.417458 -63.48603)
		(width 0.1524)
		(layer "In7.Cu")
		(net "M_A_DQS_DP0")
	)
	(segment
		(start 181.807612 -62.084458)
		(end 181.48427 -61.761116)
		(width 0.1524)
		(layer "In7.Cu")
		(net "M_A_DQS_DP0")
	)
	(segment
		(start 177.859182 -59.11723)
		(end 177.68316 -59.11723)
		(width 0.1524)
		(layer "In7.Cu")
		(net "M_A_DQS_DP0")
	)
	(segment
		(start 110.69193 -41.2242)
		(end 110.117128 -41.2242)
		(width 0.1016)
		(layer "In7.Cu")
		(net "M_A_DQS_DP0")
	)
	(segment
		(start 159.212534 -48.6918)
		(end 152.808432 -42.287698)
		(width 0.1524)
		(layer "In7.Cu")
		(net "M_A_DQS_DP0")
	)
	(segment
		(start 172.800772 -55.099458)
		(end 172.62475 -55.099458)
		(width 0.1524)
		(layer "In7.Cu")
		(net "M_A_DQS_DP0")
	)
	(segment
		(start 118.121176 -41.5798)
		(end 113.653824 -41.5798)
		(width 0.1524)
		(layer "In7.Cu")
		(net "M_A_DQS_DP0")
	)
	(segment
		(start 166.390828 -50.820828)
		(end 166.175436 -50.820828)
		(width 0.1524)
		(layer "In7.Cu")
		(net "M_A_DQS_DP0")
	)
	(segment
		(start 166.973758 -53.332634)
		(end 166.189406 -52.548282)
		(width 0.1524)
		(layer "In7.Cu")
		(net "M_A_DQS_DP0")
	)
	(segment
		(start 112.13592 -42.020998)
		(end 112.076484 -41.961562)
		(width 0.1016)
		(layer "In7.Cu")
		(net "M_A_DQS_DP0")
	)
	(segment
		(start 174.906432 -56.124856)
		(end 174.204376 -55.4228)
		(width 0.1524)
		(layer "In7.Cu")
		(net "M_A_DQS_DP0")
	)
	(segment
		(start 165.095174 -51.45405)
		(end 162.332924 -48.6918)
		(width 0.1524)
		(layer "In7.Cu")
		(net "M_A_DQS_DP0")
	)
	(segment
		(start 186.417458 -63.48603)
		(end 186.417204 -63.48603)
		(width 0.1524)
		(layer "In7.Cu")
		(net "M_A_DQS_DP0")
	)
	(segment
		(start 177.360072 -58.61812)
		(end 176.120552 -57.3786)
		(width 0.1524)
		(layer "In7.Cu")
		(net "M_A_DQS_DP0")
	)
	(segment
		(start 107.077002 -41.1226)
		(end 106.884216 -41.315386)
		(width 0.1016)
		(layer "In7.Cu")
		(net "M_A_DQS_DP0")
	)
	(segment
		(start 166.822628 -51.46802)
		(end 166.822628 -51.252628)
		(width 0.1524)
		(layer "In7.Cu")
		(net "M_A_DQS_DP0")
	)
	(segment
		(start 152.808432 -42.287698)
		(end 118.829074 -42.287698)
		(width 0.1524)
		(layer "In7.Cu")
		(net "M_A_DQS_DP0")
	)
	(segment
		(start 118.829074 -42.287698)
		(end 118.121176 -41.5798)
		(width 0.1524)
		(layer "In7.Cu")
		(net "M_A_DQS_DP0")
	)
	(segment
		(start 166.189406 -52.548282)
		(end 166.189406 -52.101242)
		(width 0.1524)
		(layer "In7.Cu")
		(net "M_A_DQS_DP0")
	)
	(segment
		(start 111.429292 -41.961562)
		(end 110.69193 -41.2242)
		(width 0.1016)
		(layer "In7.Cu")
		(net "M_A_DQS_DP0")
	)
	(segment
		(start 177.68316 -59.11723)
		(end 177.360072 -58.794142)
		(width 0.1524)
		(layer "In7.Cu")
		(net "M_A_DQS_DP0")
	)
	(segment
		(start 186.20613 -63.320676)
		(end 186.205114 -63.319914)
		(width 0.1524)
		(layer "In7.Cu")
		(net "M_A_DQS_DP0")
	)
	(segment
		(start 113.212626 -42.020998)
		(end 112.13592 -42.020998)
		(width 0.1524)
		(layer "In7.Cu")
		(net "M_A_DQS_DP0")
	)
	(segment
		(start 107.89793 -41.1226)
		(end 107.077002 -41.1226)
		(width 0.1016)
		(layer "In7.Cu")
		(net "M_A_DQS_DP0")
	)
	(segment
		(start 172.301408 -54.600094)
		(end 171.856654 -54.15534)
		(width 0.1524)
		(layer "In7.Cu")
		(net "M_A_DQS_DP0")
	)
	(segment
		(start 181.48427 -61.585094)
		(end 181.161182 -61.262006)
		(width 0.1524)
		(layer "In7.Cu")
		(net "M_A_DQS_DP0")
	)
	(segment
		(start 162.332924 -48.6918)
		(end 159.212534 -48.6918)
		(width 0.1524)
		(layer "In7.Cu")
		(net "M_A_DQS_DP0")
	)
	(segment
		(start 174.204376 -55.4228)
		(end 173.124114 -55.4228)
		(width 0.1524)
		(layer "In7.Cu")
		(net "M_A_DQS_DP0")
	)
	(segment
		(start 110.117128 -41.2242)
		(end 109.938566 -41.402762)
		(width 0.1016)
		(layer "In7.Cu")
		(net "M_A_DQS_DP0")
	)
	(segment
		(start 180.98516 -61.262006)
		(end 180.661818 -60.938664)
		(width 0.1524)
		(layer "In7.Cu")
		(net "M_A_DQS_DP0")
	)
	(segment
		(start 173.124114 -55.4228)
		(end 172.800772 -55.099458)
		(width 0.1524)
		(layer "In7.Cu")
		(net "M_A_DQS_DP0")
	)
	(segment
		(start 75.00366 -45.12183)
		(end 74.589386 -45.536104)
		(width 0.1143)
		(layer "F.Cu")
		(net "SMBUS_PECI_DATA")
	)
	(segment
		(start 80.208628 -41.811194)
		(end 79.38008 -41.811194)
		(width 0.1143)
		(layer "F.Cu")
		(net "SMBUS_PECI_DATA")
	)
	(segment
		(start 76.917042 -42.597578)
		(end 75.77455 -43.74007)
		(width 0.1143)
		(layer "F.Cu")
		(net "SMBUS_PECI_DATA")
	)
	(segment
		(start 75.77455 -44.35094)
		(end 75.00366 -45.12183)
		(width 0.1143)
		(layer "F.Cu")
		(net "SMBUS_PECI_DATA")
	)
	(segment
		(start 72.340978 -45.536104)
		(end 71.35495 -44.550076)
		(width 0.1143)
		(layer "F.Cu")
		(net "SMBUS_PECI_DATA")
	)
	(segment
		(start 70.736206 -43.2308)
		(end 69.9262 -43.2308)
		(width 0.1143)
		(layer "F.Cu")
		(net "SMBUS_PECI_DATA")
	)
	(segment
		(start 78.593696 -42.597578)
		(end 76.917042 -42.597578)
		(width 0.1143)
		(layer "F.Cu")
		(net "SMBUS_PECI_DATA")
	)
	(segment
		(start 75.77455 -43.74007)
		(end 75.77455 -44.35094)
		(width 0.1143)
		(layer "F.Cu")
		(net "SMBUS_PECI_DATA")
	)
	(segment
		(start 71.3359 -43.830494)
		(end 70.736206 -43.2308)
		(width 0.1143)
		(layer "F.Cu")
		(net "SMBUS_PECI_DATA")
	)
	(segment
		(start 71.35495 -44.550076)
		(end 71.35495 -44.535344)
		(width 0.1143)
		(layer "F.Cu")
		(net "SMBUS_PECI_DATA")
	)
	(segment
		(start 79.38008 -41.811194)
		(end 78.593696 -42.597578)
		(width 0.1143)
		(layer "F.Cu")
		(net "SMBUS_PECI_DATA")
	)
	(segment
		(start 71.35495 -44.535344)
		(end 71.3359 -44.516294)
		(width 0.1143)
		(layer "F.Cu")
		(net "SMBUS_PECI_DATA")
	)
	(segment
		(start 74.589386 -45.536104)
		(end 72.340978 -45.536104)
		(width 0.1143)
		(layer "F.Cu")
		(net "SMBUS_PECI_DATA")
	)
	(segment
		(start 69.9262 -43.2308)
		(end 69.0626 -43.2308)
		(width 0.1143)
		(layer "F.Cu")
		(net "SMBUS_PECI_DATA")
	)
	(segment
		(start 69.0626 -43.2308)
		(end 69.0118 -43.18)
		(width 0.1143)
		(layer "F.Cu")
		(net "SMBUS_PECI_DATA")
	)
	(segment
		(start 71.3359 -44.516294)
		(end 71.3359 -43.830494)
		(width 0.1143)
		(layer "F.Cu")
		(net "SMBUS_PECI_DATA")
	)
	(via
		(at 75.00366 -45.12183)
		(size 0.7112)
		(drill 0.3556)
		(layers "F.Cu" "B.Cu")
		(net "SMBUS_PECI_DATA")
	)
	(segment
		(start 145.750026 -70.053708)
		(end 145.8976 -69.906134)
		(width 0.1778)
		(layer "F.Cu")
		(net "M_A_DQS_DP4")
	)
	(segment
		(start 145.8976 -69.906134)
		(end 145.8976 -66.937128)
		(width 0.1778)
		(layer "F.Cu")
		(net "M_A_DQS_DP4")
	)
	(segment
		(start 97.715832 -47.98314)
		(end 97.715832 -47.800768)
		(width 0.1016)
		(layer "F.Cu")
		(net "M_A_DQS_DP4")
	)
	(segment
		(start 145.750026 -70.806564)
		(end 145.750026 -70.053708)
		(width 0.1778)
		(layer "F.Cu")
		(net "M_A_DQS_DP4")
	)
	(segment
		(start 97.876106 -47.640494)
		(end 98.067368 -47.640494)
		(width 0.1016)
		(layer "F.Cu")
		(net "M_A_DQS_DP4")
	)
	(segment
		(start 145.8976 -66.937128)
		(end 145.632678 -66.672206)
		(width 0.1778)
		(layer "F.Cu")
		(net "M_A_DQS_DP4")
	)
	(segment
		(start 97.715832 -47.800768)
		(end 97.876106 -47.640494)
		(width 0.1016)
		(layer "F.Cu")
		(net "M_A_DQS_DP4")
	)
	(via
		(at 145.632678 -66.672206)
		(size 0.4318)
		(drill 0.2032)
		(layers "F.Cu" "B.Cu")
		(net "M_A_DQS_DP4")
	)
	(via
		(at 97.715832 -47.98314)
		(size 0.4318)
		(drill 0.2032)
		(layers "F.Cu" "B.Cu")
		(net "M_A_DQS_DP4")
	)
	(segment
		(start 145.8976 -63.513208)
		(end 145.8976 -66.407284)
		(width 0.1778)
		(layer "B.Cu")
		(net "M_A_DQS_DP4")
	)
	(segment
		(start 145.8976 -66.407284)
		(end 145.632678 -66.672206)
		(width 0.1778)
		(layer "B.Cu")
		(net "M_A_DQS_DP4")
	)
	(segment
		(start 145.750026 -63.365634)
		(end 145.8976 -63.513208)
		(width 0.1778)
		(layer "B.Cu")
		(net "M_A_DQS_DP4")
	)
	(segment
		(start 145.750026 -62.599824)
		(end 145.750026 -63.365634)
		(width 0.1778)
		(layer "B.Cu")
		(net "M_A_DQS_DP4")
	)
	(segment
		(start 107.201208 -55.460392)
		(end 107.447588 -55.214012)
		(width 0.1524)
		(layer "In4.Cu")
		(net "M_A_DQS_DP4")
	)
	(segment
		(start 98.2218 -49.284128)
		(end 98.2218 -47.760128)
		(width 0.1016)
		(layer "In4.Cu")
		(net "M_A_DQS_DP4")
	)
	(segment
		(start 145.923 -66.381884)
		(end 145.923 -63.615062)
		(width 0.1524)
		(layer "In4.Cu")
		(net "M_A_DQS_DP4")
	)
	(segment
		(start 145.923 -63.615062)
		(end 145.644362 -63.336424)
		(width 0.1524)
		(layer "In4.Cu")
		(net "M_A_DQS_DP4")
	)
	(segment
		(start 107.447588 -54.807612)
		(end 107.067604 -54.427628)
		(width 0.1524)
		(layer "In4.Cu")
		(net "M_A_DQS_DP4")
	)
	(segment
		(start 141.0589 -57.605676)
		(end 141.0589 -57.253124)
		(width 0.1524)
		(layer "In4.Cu")
		(net "M_A_DQS_DP4")
	)
	(segment
		(start 138.1506 -56.6928)
		(end 109.459776 -56.6928)
		(width 0.1524)
		(layer "In4.Cu")
		(net "M_A_DQS_DP4")
	)
	(segment
		(start 142.454376 -58.5724)
		(end 141.771624 -58.5724)
		(width 0.1524)
		(layer "In4.Cu")
		(net "M_A_DQS_DP4")
	)
	(segment
		(start 101.730556 -51.68519)
		(end 99.94519 -51.68519)
		(width 0.1524)
		(layer "In4.Cu")
		(net "M_A_DQS_DP4")
	)
	(segment
		(start 145.5166 -62.357762)
		(end 145.644362 -62.23)
		(width 0.1524)
		(layer "In4.Cu")
		(net "M_A_DQS_DP4")
	)
	(segment
		(start 141.0589 -57.253124)
		(end 140.806424 -57.000648)
		(width 0.1524)
		(layer "In4.Cu")
		(net "M_A_DQS_DP4")
	)
	(segment
		(start 107.847892 -56.508904)
		(end 107.201208 -55.86222)
		(width 0.1524)
		(layer "In4.Cu")
		(net "M_A_DQS_DP4")
	)
	(segment
		(start 140.218414 -59.661044)
		(end 139.838684 -59.281314)
		(width 0.1524)
		(layer "In4.Cu")
		(net "M_A_DQS_DP4")
	)
	(segment
		(start 144.435576 -60.2742)
		(end 143.7894 -60.2742)
		(width 0.1524)
		(layer "In4.Cu")
		(net "M_A_DQS_DP4")
	)
	(segment
		(start 108.850176 -56.0832)
		(end 108.675424 -56.0832)
		(width 0.1524)
		(layer "In4.Cu")
		(net "M_A_DQS_DP4")
	)
	(segment
		(start 140.68298 -59.661044)
		(end 140.218414 -59.661044)
		(width 0.1524)
		(layer "In4.Cu")
		(net "M_A_DQS_DP4")
	)
	(segment
		(start 142.6718 -58.789824)
		(end 142.454376 -58.5724)
		(width 0.1524)
		(layer "In4.Cu")
		(net "M_A_DQS_DP4")
	)
	(segment
		(start 145.644362 -62.23)
		(end 145.644362 -61.482986)
		(width 0.1524)
		(layer "In4.Cu")
		(net "M_A_DQS_DP4")
	)
	(segment
		(start 99.6696 -51.4096)
		(end 99.6696 -50.379884)
		(width 0.1524)
		(layer "In4.Cu")
		(net "M_A_DQS_DP4")
	)
	(segment
		(start 99.457002 -50.167286)
		(end 99.457002 -50.11293)
		(width 0.1016)
		(layer "In4.Cu")
		(net "M_A_DQS_DP4")
	)
	(segment
		(start 144.720056 -60.734702)
		(end 144.720056 -60.55868)
		(width 0.1524)
		(layer "In4.Cu")
		(net "M_A_DQS_DP4")
	)
	(segment
		(start 138.762486 -58.205116)
		(end 138.382756 -57.825386)
		(width 0.1524)
		(layer "In4.Cu")
		(net "M_A_DQS_DP4")
	)
	(segment
		(start 145.632678 -66.672206)
		(end 145.923 -66.381884)
		(width 0.1524)
		(layer "In4.Cu")
		(net "M_A_DQS_DP4")
	)
	(segment
		(start 99.94519 -51.68519)
		(end 99.6696 -51.4096)
		(width 0.1524)
		(layer "In4.Cu")
		(net "M_A_DQS_DP4")
	)
	(segment
		(start 145.043398 -61.058044)
		(end 144.720056 -60.734702)
		(width 0.1524)
		(layer "In4.Cu")
		(net "M_A_DQS_DP4")
	)
	(segment
		(start 109.459776 -56.6928)
		(end 108.850176 -56.0832)
		(width 0.1524)
		(layer "In4.Cu")
		(net "M_A_DQS_DP4")
	)
	(segment
		(start 140.3604 -58.312558)
		(end 140.3604 -58.304176)
		(width 0.1524)
		(layer "In4.Cu")
		(net "M_A_DQS_DP4")
	)
	(segment
		(start 138.382756 -56.924956)
		(end 138.1506 -56.6928)
		(width 0.1524)
		(layer "In4.Cu")
		(net "M_A_DQS_DP4")
	)
	(segment
		(start 107.201208 -55.86222)
		(end 107.201208 -55.460392)
		(width 0.1524)
		(layer "In4.Cu")
		(net "M_A_DQS_DP4")
	)
	(segment
		(start 98.023172 -47.6758)
		(end 97.715832 -47.98314)
		(width 0.1016)
		(layer "In4.Cu")
		(net "M_A_DQS_DP4")
	)
	(segment
		(start 142.6718 -59.447176)
		(end 142.6718 -58.789824)
		(width 0.1524)
		(layer "In4.Cu")
		(net "M_A_DQS_DP4")
	)
	(segment
		(start 145.644362 -61.482986)
		(end 145.21942 -61.058044)
		(width 0.1524)
		(layer "In4.Cu")
		(net "M_A_DQS_DP4")
	)
	(segment
		(start 106.624628 -54.427628)
		(end 106.045 -53.848)
		(width 0.1524)
		(layer "In4.Cu")
		(net "M_A_DQS_DP4")
	)
	(segment
		(start 139.838684 -59.281314)
		(end 139.838684 -58.834274)
		(width 0.1524)
		(layer "In4.Cu")
		(net "M_A_DQS_DP4")
	)
	(segment
		(start 99.457002 -50.11293)
		(end 99.178872 -49.8348)
		(width 0.1016)
		(layer "In4.Cu")
		(net "M_A_DQS_DP4")
	)
	(segment
		(start 145.5166 -62.7888)
		(end 145.5166 -62.357762)
		(width 0.1524)
		(layer "In4.Cu")
		(net "M_A_DQS_DP4")
	)
	(segment
		(start 103.810054 -52.363878)
		(end 102.409244 -52.363878)
		(width 0.1524)
		(layer "In4.Cu")
		(net "M_A_DQS_DP4")
	)
	(segment
		(start 139.209526 -58.205116)
		(end 138.762486 -58.205116)
		(width 0.1524)
		(layer "In4.Cu")
		(net "M_A_DQS_DP4")
	)
	(segment
		(start 108.24972 -56.508904)
		(end 107.847892 -56.508904)
		(width 0.1524)
		(layer "In4.Cu")
		(net "M_A_DQS_DP4")
	)
	(segment
		(start 138.382756 -57.825386)
		(end 138.382756 -56.924956)
		(width 0.1524)
		(layer "In4.Cu")
		(net "M_A_DQS_DP4")
	)
	(segment
		(start 108.675424 -56.0832)
		(end 108.24972 -56.508904)
		(width 0.1524)
		(layer "In4.Cu")
		(net "M_A_DQS_DP4")
	)
	(segment
		(start 107.447588 -55.214012)
		(end 107.447588 -54.807612)
		(width 0.1524)
		(layer "In4.Cu")
		(net "M_A_DQS_DP4")
	)
	(segment
		(start 142.8242 -60.5536)
		(end 142.6972 -60.4266)
		(width 0.1524)
		(layer "In4.Cu")
		(net "M_A_DQS_DP4")
	)
	(segment
		(start 142.500858 -60.230512)
		(end 142.500858 -59.618118)
		(width 0.1524)
		(layer "In4.Cu")
		(net "M_A_DQS_DP4")
	)
	(segment
		(start 143.51 -60.5536)
		(end 142.8242 -60.5536)
		(width 0.1524)
		(layer "In4.Cu")
		(net "M_A_DQS_DP4")
	)
	(segment
		(start 139.838684 -58.834274)
		(end 140.3604 -58.312558)
		(width 0.1524)
		(layer "In4.Cu")
		(net "M_A_DQS_DP4")
	)
	(segment
		(start 140.413994 -57.000648)
		(end 139.209526 -58.205116)
		(width 0.1524)
		(layer "In4.Cu")
		(net "M_A_DQS_DP4")
	)
	(segment
		(start 142.6972 -60.4266)
		(end 142.696946 -60.4266)
		(width 0.1524)
		(layer "In4.Cu")
		(net "M_A_DQS_DP4")
	)
	(segment
		(start 140.806424 -57.000648)
		(end 140.413994 -57.000648)
		(width 0.1524)
		(layer "In4.Cu")
		(net "M_A_DQS_DP4")
	)
	(segment
		(start 144.720056 -60.55868)
		(end 144.435576 -60.2742)
		(width 0.1524)
		(layer "In4.Cu")
		(net "M_A_DQS_DP4")
	)
	(segment
		(start 142.696946 -60.4266)
		(end 142.500858 -60.230512)
		(width 0.1524)
		(layer "In4.Cu")
		(net "M_A_DQS_DP4")
	)
	(segment
		(start 107.067604 -54.427628)
		(end 106.624628 -54.427628)
		(width 0.1524)
		(layer "In4.Cu")
		(net "M_A_DQS_DP4")
	)
	(segment
		(start 106.045 -53.848)
		(end 105.294176 -53.848)
		(width 0.1524)
		(layer "In4.Cu")
		(net "M_A_DQS_DP4")
	)
	(segment
		(start 143.7894 -60.2742)
		(end 143.51 -60.5536)
		(width 0.1524)
		(layer "In4.Cu")
		(net "M_A_DQS_DP4")
	)
	(segment
		(start 145.644362 -63.336424)
		(end 145.644362 -62.916562)
		(width 0.1524)
		(layer "In4.Cu")
		(net "M_A_DQS_DP4")
	)
	(segment
		(start 145.644362 -62.916562)
		(end 145.5166 -62.7888)
		(width 0.1524)
		(layer "In4.Cu")
		(net "M_A_DQS_DP4")
	)
	(segment
		(start 105.294176 -53.848)
		(end 103.810054 -52.363878)
		(width 0.1524)
		(layer "In4.Cu")
		(net "M_A_DQS_DP4")
	)
	(segment
		(start 145.21942 -61.058044)
		(end 145.043398 -61.058044)
		(width 0.1524)
		(layer "In4.Cu")
		(net "M_A_DQS_DP4")
	)
	(segment
		(start 102.409244 -52.363878)
		(end 101.730556 -51.68519)
		(width 0.1524)
		(layer "In4.Cu")
		(net "M_A_DQS_DP4")
	)
	(segment
		(start 141.771624 -58.5724)
		(end 140.68298 -59.661044)
		(width 0.1524)
		(layer "In4.Cu")
		(net "M_A_DQS_DP4")
	)
	(segment
		(start 142.500858 -59.618118)
		(end 142.6718 -59.447176)
		(width 0.1524)
		(layer "In4.Cu")
		(net "M_A_DQS_DP4")
	)
	(segment
		(start 99.6696 -50.379884)
		(end 99.457002 -50.167286)
		(width 0.1524)
		(layer "In4.Cu")
		(net "M_A_DQS_DP4")
	)
	(segment
		(start 98.2218 -47.760128)
		(end 98.137472 -47.6758)
		(width 0.1016)
		(layer "In4.Cu")
		(net "M_A_DQS_DP4")
	)
	(segment
		(start 98.137472 -47.6758)
		(end 98.023172 -47.6758)
		(width 0.1016)
		(layer "In4.Cu")
		(net "M_A_DQS_DP4")
	)
	(segment
		(start 98.772472 -49.8348)
		(end 98.2218 -49.284128)
		(width 0.1016)
		(layer "In4.Cu")
		(net "M_A_DQS_DP4")
	)
	(segment
		(start 140.3604 -58.304176)
		(end 141.0589 -57.605676)
		(width 0.1524)
		(layer "In4.Cu")
		(net "M_A_DQS_DP4")
	)
	(segment
		(start 99.178872 -49.8348)
		(end 98.772472 -49.8348)
		(width 0.1016)
		(layer "In4.Cu")
		(net "M_A_DQS_DP4")
	)
	(segment
		(start 118.237 -63.119)
		(end 118.11 -62.992)
		(width 0.1143)
		(layer "F.Cu")
		(net "SMB_M_A1_R_CLK")
	)
	(segment
		(start 127.450088 -61.524388)
		(end 126.906782 -60.981082)
		(width 0.1143)
		(layer "F.Cu")
		(net "SMB_M_A1_R_CLK")
	)
	(segment
		(start 119.231918 -60.981082)
		(end 118.11 -62.103)
		(width 0.1143)
		(layer "F.Cu")
		(net "SMB_M_A1_R_CLK")
	)
	(segment
		(start 127.450088 -62.59322)
		(end 127.450088 -61.524388)
		(width 0.1143)
		(layer "F.Cu")
		(net "SMB_M_A1_R_CLK")
	)
	(segment
		(start 118.237 -63.9572)
		(end 118.237 -63.119)
		(width 0.1143)
		(layer "F.Cu")
		(net "SMB_M_A1_R_CLK")
	)
	(segment
		(start 118.11 -62.103)
		(end 118.11 -62.992)
		(width 0.1143)
		(layer "F.Cu")
		(net "SMB_M_A1_R_CLK")
	)
	(segment
		(start 126.906782 -60.981082)
		(end 119.231918 -60.981082)
		(width 0.1143)
		(layer "F.Cu")
		(net "SMB_M_A1_R_CLK")
	)
	(via
		(at 118.11 -62.992)
		(size 0.7112)
		(drill 0.3556)
		(layers "F.Cu" "B.Cu")
		(net "SMB_M_A1_R_CLK")
	)
	(segment
		(start 29.6926 -55.3212)
		(end 29.6672 -55.2958)
		(width 0.508)
		(layer "F.Cu")
		(net "VR_PVCCP_PHASE")
	)
	(segment
		(start 24.920448 -57.019952)
		(end 25.5524 -56.388)
		(width 0.2032)
		(layer "F.Cu")
		(net "VR_PVCCP_PHASE")
	)
	(segment
		(start 24.335994 -57.019952)
		(end 24.920448 -57.019952)
		(width 0.2032)
		(layer "F.Cu")
		(net "VR_PVCCP_PHASE")
	)
	(segment
		(start 29.591 -53.721)
		(end 29.591 -53.6448)
		(width 0.508)
		(layer "F.Cu")
		(net "VR_PVCCP_PHASE")
	)
	(segment
		(start 25.5524 -56.388)
		(end 25.5524 -56.1594)
		(width 0.2032)
		(layer "F.Cu")
		(net "VR_PVCCP_PHASE")
	)
	(segment
		(start 29.6672 -53.7972)
		(end 29.591 -53.721)
		(width 0.508)
		(layer "F.Cu")
		(net "VR_PVCCP_PHASE")
	)
	(segment
		(start 29.6672 -55.2958)
		(end 29.6672 -54.5084)
		(width 0.508)
		(layer "F.Cu")
		(net "VR_PVCCP_PHASE")
	)
	(segment
		(start 38.351206 -58.674)
		(end 37.084 -58.674)
		(width 0.508)
		(layer "F.Cu")
		(net "VR_PVCCP_PHASE")
	)
	(segment
		(start 29.6672 -54.5084)
		(end 29.6672 -53.7972)
		(width 0.508)
		(layer "F.Cu")
		(net "VR_PVCCP_PHASE")
	)
	(via
		(at 37.084 -58.674)
		(size 0.508)
		(drill 0.254)
		(layers "F.Cu" "B.Cu")
		(net "VR_PVCCP_PHASE")
	)
	(via
		(at 37.084 -57.9374)
		(size 0.7112)
		(drill 0.3556)
		(layers "F.Cu" "B.Cu")
		(net "VR_PVCCP_PHASE")
	)
	(via
		(at 25.5524 -56.1594)
		(size 0.508)
		(drill 0.254)
		(layers "F.Cu" "B.Cu")
		(net "VR_PVCCP_PHASE")
	)
	(via
		(at 29.591 -53.6448)
		(size 0.7112)
		(drill 0.4064)
		(layers "F.Cu" "B.Cu")
		(net "VR_PVCCP_PHASE")
	)
	(segment
		(start 37.084 -58.674)
		(end 37.084 -57.9374)
		(width 0.508)
		(layer "B.Cu")
		(net "VR_PVCCP_PHASE")
	)
	(segment
		(start 30.686502 -53.6448)
		(end 35.715702 -58.674)
		(width 0.508)
		(layer "In2.Cu")
		(net "VR_PVCCP_PHASE")
	)
	(segment
		(start 35.715702 -58.674)
		(end 37.084 -58.674)
		(width 0.508)
		(layer "In2.Cu")
		(net "VR_PVCCP_PHASE")
	)
	(segment
		(start 29.591 -53.6448)
		(end 30.686502 -53.6448)
		(width 0.508)
		(layer "In2.Cu")
		(net "VR_PVCCP_PHASE")
	)
	(segment
		(start 26.1366 -56.1594)
		(end 25.5524 -56.1594)
		(width 0.508)
		(layer "In7.Cu")
		(net "VR_PVCCP_PHASE")
	)
	(segment
		(start 29.591 -53.6448)
		(end 29.4894 -53.7464)
		(width 0.508)
		(layer "In7.Cu")
		(net "VR_PVCCP_PHASE")
	)
	(segment
		(start 29.4894 -53.7464)
		(end 28.5496 -53.7464)
		(width 0.508)
		(layer "In7.Cu")
		(net "VR_PVCCP_PHASE")
	)
	(segment
		(start 28.5496 -53.7464)
		(end 26.1366 -56.1594)
		(width 0.508)
		(layer "In7.Cu")
		(net "VR_PVCCP_PHASE")
	)
	(segment
		(start 101.981 -56.6928)
		(end 101.981 -54.1274)
		(width 0.1016)
		(layer "F.Cu")
		(net "M_A_DQ53")
	)
	(segment
		(start 137.94994 -70.806564)
		(end 137.94994 -69.741542)
		(width 0.1778)
		(layer "F.Cu")
		(net "M_A_DQ53")
	)
	(segment
		(start 100.970588 -52.031392)
		(end 100.970588 -51.953414)
		(width 0.1016)
		(layer "F.Cu")
		(net "M_A_DQ53")
	)
	(segment
		(start 100.8507 -52.9971)
		(end 100.8507 -52.15128)
		(width 0.1016)
		(layer "F.Cu")
		(net "M_A_DQ53")
	)
	(segment
		(start 100.8507 -52.15128)
		(end 100.970588 -52.031392)
		(width 0.1016)
		(layer "F.Cu")
		(net "M_A_DQ53")
	)
	(segment
		(start 137.778998 -69.5706)
		(end 137.778998 -69.046598)
		(width 0.1778)
		(layer "F.Cu")
		(net "M_A_DQ53")
	)
	(segment
		(start 137.94994 -69.741542)
		(end 137.778998 -69.5706)
		(width 0.1778)
		(layer "F.Cu")
		(net "M_A_DQ53")
	)
	(segment
		(start 137.778998 -69.046598)
		(end 137.541 -68.8086)
		(width 0.1778)
		(layer "F.Cu")
		(net "M_A_DQ53")
	)
	(segment
		(start 101.981 -54.1274)
		(end 100.8507 -52.9971)
		(width 0.1016)
		(layer "F.Cu")
		(net "M_A_DQ53")
	)
	(segment
		(start 101.5238 -57.15)
		(end 101.981 -56.6928)
		(width 0.1016)
		(layer "F.Cu")
		(net "M_A_DQ53")
	)
	(via
		(at 101.5238 -57.15)
		(size 0.4318)
		(drill 0.2032)
		(layers "F.Cu" "B.Cu")
		(net "M_A_DQ53")
	)
	(via
		(at 137.541 -68.8086)
		(size 0.4318)
		(drill 0.2032)
		(layers "F.Cu" "B.Cu")
		(net "M_A_DQ53")
	)
	(segment
		(start 137.778998 -69.339206)
		(end 137.778998 -69.046598)
		(width 0.1778)
		(layer "B.Cu")
		(net "M_A_DQ53")
	)
	(segment
		(start 137.649966 -69.468238)
		(end 137.778998 -69.339206)
		(width 0.1778)
		(layer "B.Cu")
		(net "M_A_DQ53")
	)
	(segment
		(start 137.649966 -70.79996)
		(end 137.649966 -69.468238)
		(width 0.1778)
		(layer "B.Cu")
		(net "M_A_DQ53")
	)
	(segment
		(start 137.778998 -69.046598)
		(end 137.541 -68.8086)
		(width 0.1778)
		(layer "B.Cu")
		(net "M_A_DQ53")
	)
	(segment
		(start 101.5238 -58.3946)
		(end 101.5238 -57.15)
		(width 0.1524)
		(layer "In4.Cu")
		(net "M_A_DQ53")
	)
	(segment
		(start 115.189 -61.4934)
		(end 114.8842 -61.4934)
		(width 0.1524)
		(layer "In4.Cu")
		(net "M_A_DQ53")
	)
	(segment
		(start 114.7318 -61.341)
		(end 114.7318 -60.6806)
		(width 0.1524)
		(layer "In4.Cu")
		(net "M_A_DQ53")
	)
	(segment
		(start 113.3602 -60.5282)
		(end 113.0554 -60.5282)
		(width 0.1524)
		(layer "In4.Cu")
		(net "M_A_DQ53")
	)
	(segment
		(start 112.7506 -61.7728)
		(end 111.8616 -61.7728)
		(width 0.1524)
		(layer "In4.Cu")
		(net "M_A_DQ53")
	)
	(segment
		(start 113.0554 -60.5282)
		(end 112.903 -60.6806)
		(width 0.1524)
		(layer "In4.Cu")
		(net "M_A_DQ53")
	)
	(segment
		(start 129.7432 -60.6806)
		(end 129.5908 -60.5282)
		(width 0.1524)
		(layer "In4.Cu")
		(net "M_A_DQ53")
	)
	(segment
		(start 138.9888 -64.8716)
		(end 138.9888 -63.9572)
		(width 0.1524)
		(layer "In4.Cu")
		(net "M_A_DQ53")
	)
	(segment
		(start 135.7122 -60.6806)
		(end 129.7432 -60.6806)
		(width 0.1524)
		(layer "In4.Cu")
		(net "M_A_DQ53")
	)
	(segment
		(start 114.1222 -61.6204)
		(end 113.9698 -61.7728)
		(width 0.1524)
		(layer "In4.Cu")
		(net "M_A_DQ53")
	)
	(segment
		(start 115.3414 -60.6806)
		(end 115.3414 -61.341)
		(width 0.1524)
		(layer "In4.Cu")
		(net "M_A_DQ53")
	)
	(segment
		(start 115.4938 -60.5282)
		(end 115.3414 -60.6806)
		(width 0.1524)
		(layer "In4.Cu")
		(net "M_A_DQ53")
	)
	(segment
		(start 137.541 -68.8086)
		(end 137.778998 -68.570602)
		(width 0.1524)
		(layer "In4.Cu")
		(net "M_A_DQ53")
	)
	(segment
		(start 103.3526 -59.2074)
		(end 102.3366 -59.2074)
		(width 0.1524)
		(layer "In4.Cu")
		(net "M_A_DQ53")
	)
	(segment
		(start 114.2746 -60.5282)
		(end 114.1222 -60.6806)
		(width 0.1524)
		(layer "In4.Cu")
		(net "M_A_DQ53")
	)
	(segment
		(start 115.3414 -61.341)
		(end 115.189 -61.4934)
		(width 0.1524)
		(layer "In4.Cu")
		(net "M_A_DQ53")
	)
	(segment
		(start 112.903 -60.6806)
		(end 112.903 -61.6204)
		(width 0.1524)
		(layer "In4.Cu")
		(net "M_A_DQ53")
	)
	(segment
		(start 113.5126 -60.6806)
		(end 113.3602 -60.5282)
		(width 0.1524)
		(layer "In4.Cu")
		(net "M_A_DQ53")
	)
	(segment
		(start 113.665 -61.7728)
		(end 113.5126 -61.6204)
		(width 0.1524)
		(layer "In4.Cu")
		(net "M_A_DQ53")
	)
	(segment
		(start 102.3366 -59.2074)
		(end 101.5238 -58.3946)
		(width 0.1524)
		(layer "In4.Cu")
		(net "M_A_DQ53")
	)
	(segment
		(start 111.379 -61.2902)
		(end 105.4354 -61.2902)
		(width 0.1524)
		(layer "In4.Cu")
		(net "M_A_DQ53")
	)
	(segment
		(start 137.778998 -68.570602)
		(end 137.778998 -66.081402)
		(width 0.1524)
		(layer "In4.Cu")
		(net "M_A_DQ53")
	)
	(segment
		(start 137.778998 -66.081402)
		(end 138.9888 -64.8716)
		(width 0.1524)
		(layer "In4.Cu")
		(net "M_A_DQ53")
	)
	(segment
		(start 138.9888 -63.9572)
		(end 135.7122 -60.6806)
		(width 0.1524)
		(layer "In4.Cu")
		(net "M_A_DQ53")
	)
	(segment
		(start 105.4354 -61.2902)
		(end 103.3526 -59.2074)
		(width 0.1524)
		(layer "In4.Cu")
		(net "M_A_DQ53")
	)
	(segment
		(start 114.7318 -60.6806)
		(end 114.5794 -60.5282)
		(width 0.1524)
		(layer "In4.Cu")
		(net "M_A_DQ53")
	)
	(segment
		(start 129.5908 -60.5282)
		(end 115.4938 -60.5282)
		(width 0.1524)
		(layer "In4.Cu")
		(net "M_A_DQ53")
	)
	(segment
		(start 112.903 -61.6204)
		(end 112.7506 -61.7728)
		(width 0.1524)
		(layer "In4.Cu")
		(net "M_A_DQ53")
	)
	(segment
		(start 113.9698 -61.7728)
		(end 113.665 -61.7728)
		(width 0.1524)
		(layer "In4.Cu")
		(net "M_A_DQ53")
	)
	(segment
		(start 114.8842 -61.4934)
		(end 114.7318 -61.341)
		(width 0.1524)
		(layer "In4.Cu")
		(net "M_A_DQ53")
	)
	(segment
		(start 114.5794 -60.5282)
		(end 114.2746 -60.5282)
		(width 0.1524)
		(layer "In4.Cu")
		(net "M_A_DQ53")
	)
	(segment
		(start 111.8616 -61.7728)
		(end 111.379 -61.2902)
		(width 0.1524)
		(layer "In4.Cu")
		(net "M_A_DQ53")
	)
	(segment
		(start 113.5126 -61.6204)
		(end 113.5126 -60.6806)
		(width 0.1524)
		(layer "In4.Cu")
		(net "M_A_DQ53")
	)
	(segment
		(start 114.1222 -60.6806)
		(end 114.1222 -61.6204)
		(width 0.1524)
		(layer "In4.Cu")
		(net "M_A_DQ53")
	)
	(segment
		(start 101.849936 -42.400474)
		(end 102.124256 -42.674794)
		(width 0.127)
		(layer "F.Cu")
		(net "TP_CPU_RSVD6")
	)
	(segment
		(start 101.849428 -42.400474)
		(end 101.849936 -42.400474)
		(width 0.127)
		(layer "F.Cu")
		(net "TP_CPU_RSVD6")
	)
	(segment
		(start 102.916228 -42.674794)
		(end 103.064056 -42.526966)
		(width 0.127)
		(layer "F.Cu")
		(net "TP_CPU_RSVD6")
	)
	(segment
		(start 102.124256 -42.674794)
		(end 102.916228 -42.674794)
		(width 0.127)
		(layer "F.Cu")
		(net "TP_CPU_RSVD6")
	)
	(segment
		(start 103.064056 -42.526966)
		(end 103.4034 -42.526966)
		(width 0.127)
		(layer "F.Cu")
		(net "TP_CPU_RSVD6")
	)
	(via
		(at 103.4034 -42.526966)
		(size 0.4318)
		(drill 0.2032)
		(layers "F.Cu" "B.Cu")
		(net "TP_CPU_RSVD6")
	)
	(segment
		(start 103.502968 -41.842436)
		(end 103.4034 -41.942004)
		(width 0.127)
		(layer "B.Cu")
		(net "TP_CPU_RSVD6")
	)
	(segment
		(start 103.4034 -41.942004)
		(end 103.4034 -42.526966)
		(width 0.127)
		(layer "B.Cu")
		(net "TP_CPU_RSVD6")
	)
	(zone
		(layer "F.Cu")
		(hatch none 0.5)
		(connect_pads
			(clearance 0)
		)
		(min_thickness 0.25)
		(keepout
			(tracks not_allowed)
			(vias allowed)
			(pads allowed)
			(copperpour not_allowed)
			(footprints allowed)
		)
		(placement
			(enabled no)
			(sheetname "")
		)
		(fill
			(thermal_gap 0.5)
			(thermal_bridge_width 0.5)
			(island_removal_mode 0)
		)
		(polygon
			(pts
				(arc
					(start 43.4086 -9.867138)
					(mid 43.024806 -10.250551)
					(end 43.408346 -10.634218)
				)
				(arc
					(start 44.327826 -10.634218)
					(mid 44.711366 -10.250678)
					(end 44.327826 -9.867138)
				)
				(xy 44.104052 -9.867138) (xy 44.104052 -9.910064)
				(arc
					(start 44.206922 -10.012934)
					(mid 44.516426 -10.439278)
					(end 44.090082 -10.129774)
				)
				(xy 43.987212 -10.026904) (xy 43.938952 -9.978644) (xy 43.938952 -9.910064) (xy 43.938952 -9.867138)
				(xy 43.761152 -9.867138) (xy 43.761152 -9.946132) (xy 43.761152 -10.014712) (xy 43.712892 -10.062972)
				(arc
					(start 43.64609 -10.129774)
					(mid 43.219746 -10.439278)
					(end 43.52925 -10.012934)
				)
				(xy 43.596052 -9.946132) (xy 43.596052 -9.867138)
			)
		)
	)
	(zone
		(layer "F.Cu")
		(hatch none 0.5)
		(connect_pads
			(clearance 0)
		)
		(min_thickness 0.25)
		(keepout
			(tracks not_allowed)
			(vias allowed)
			(pads allowed)
			(copperpour not_allowed)
			(footprints allowed)
		)
		(placement
			(enabled no)
			(sheetname "")
		)
		(fill
			(thermal_gap 0.5)
			(thermal_bridge_width 0.5)
			(island_removal_mode 0)
		)
		(polygon
			(pts
				(arc
					(start 89.6493 -53.87594)
					(mid 89.921451 -54.237753)
					(end 89.559638 -53.965602)
				)
				(xy 89.435178 -53.841142)
				(arc
					(start 89.415874 -54.043326)
					(mid 89.727024 -54.420008)
					(end 90.103706 -54.108858)
				)
				(arc
					(start 90.156792 -53.552598)
					(mid 89.953516 -53.204001)
					(end 89.558368 -53.285898)
				)
				(xy 89.558368 -53.469286)
				(arc
					(start 89.585546 -53.496464)
					(mid 90.034501 -53.463941)
					(end 89.623392 -53.64734)
				)
				(xy 89.609422 -53.64734) (xy 89.55659 -53.64734) (xy 89.519506 -53.610256) (xy 89.468452 -53.559202)
				(xy 89.46261 -53.55336) (xy 89.450672 -53.677312)
			)
		)
	)
	(zone
		(net "GND")
		(layer "F.Cu")
		(hatch none 0.5)
		(connect_pads
			(clearance 0.5)
		)
		(min_thickness 0.25)
		(fill yes
			(thermal_gap 0.5)
			(thermal_bridge_width 0.5)
			(island_removal_mode 0)
		)
		(polygon
			(pts
				(xy 139.7 -31.242) (xy 139.446 -31.496) (xy 139.446 -37.719) (xy 139.7 -37.973) (xy 145.796 -37.973)
				(xy 146.05 -37.719) (xy 146.05 -31.623) (xy 145.669 -31.242)
			)
		)
	)
	(zone
		(layer "F.Cu")
		(hatch none 0.5)
		(connect_pads
			(clearance 0)
		)
		(min_thickness 0.25)
		(keepout
			(tracks not_allowed)
			(vias allowed)
			(pads allowed)
			(copperpour not_allowed)
			(footprints allowed)
		)
		(placement
			(enabled no)
			(sheetname "")
		)
		(fill
			(thermal_gap 0.5)
			(thermal_bridge_width 0.5)
			(island_removal_mode 0)
		)
		(polygon
			(pts
				(arc
					(start 10.01014 -55.626254)
					(mid 9.668238 -55.244472)
					(end 9.25195 -55.54345)
				)
				(arc
					(start 9.373108 -55.54345)
					(mid 9.893195 -55.626)
					(end 9.373108 -55.70855)
				)
				(xy 9.24306 -55.70855) (xy 9.24306 -56.43245)
				(arc
					(start 9.373108 -56.43245)
					(mid 9.893195 -56.515)
					(end 9.373108 -56.59755)
				)
				(arc
					(start 9.25195 -56.59755)
					(mid 9.668119 -56.896383)
					(end 10.01014 -56.515)
				)
			)
		)
	)
	(zone
		(layer "F.Cu")
		(hatch none 0.5)
		(connect_pads
			(clearance 0)
		)
		(min_thickness 0.25)
		(keepout
			(tracks not_allowed)
			(vias allowed)
			(pads allowed)
			(copperpour not_allowed)
			(footprints allowed)
		)
		(placement
			(enabled no)
			(sheetname "")
		)
		(fill
			(thermal_gap 0.5)
			(thermal_bridge_width 0.5)
			(island_removal_mode 0)
		)
		(polygon
			(pts
				(arc
					(start 23.40864 -9.867138)
					(mid 23.024846 -10.250551)
					(end 23.408386 -10.634218)
				)
				(arc
					(start 24.327866 -10.634218)
					(mid 24.711406 -10.250678)
					(end 24.327866 -9.867138)
				)
				(xy 24.104092 -9.867138) (xy 24.104092 -9.910064)
				(arc
					(start 24.206962 -10.012934)
					(mid 24.516466 -10.439278)
					(end 24.090122 -10.129774)
				)
				(xy 23.987252 -10.026904) (xy 23.938992 -9.978644) (xy 23.938992 -9.910064) (xy 23.938992 -9.867138)
				(xy 23.761192 -9.867138) (xy 23.761192 -9.946132) (xy 23.761192 -10.014712) (xy 23.712932 -10.062972)
				(arc
					(start 23.64613 -10.129774)
					(mid 23.219786 -10.439278)
					(end 23.52929 -10.012934)
				)
				(xy 23.596092 -9.946132) (xy 23.596092 -9.867138)
			)
		)
	)
	(zone
		(net "P3V3")
		(layer "F.Cu")
		(hatch none 0.5)
		(connect_pads
			(clearance 0.5)
		)
		(min_thickness 0.25)
		(fill yes
			(thermal_gap 0.5)
			(thermal_bridge_width 0.5)
			(island_removal_mode 0)
		)
		(polygon
			(pts
				(xy 45.466 -14.732) (xy 45.339 -14.859) (xy 45.339 -15.621) (xy 45.466 -15.748) (xy 46.355 -15.748)
				(xy 46.609 -16.002) (xy 49.403 -16.002) (xy 49.53 -16.129) (xy 50.165 -16.129) (xy 50.292 -16.002)
				(xy 50.292 -15.621) (xy 49.403 -14.732)
			)
		)
		(polygon
			(pts
				(xy 49.53 -15.24) (xy 49.276 -15.24) (xy 49.276 -15.494) (xy 49.53 -15.494)
			)
		)
		(polygon
			(pts
				(xy 49.022 -15.24) (xy 48.514 -15.24) (xy 48.514 -15.494) (xy 49.022 -15.494)
			)
		)
		(polygon
			(pts
				(xy 48.26 -15.24) (xy 47.752 -15.24) (xy 47.752 -15.494) (xy 48.26 -15.494)
			)
		)
		(polygon
			(pts
				(xy 47.498 -15.24) (xy 46.99 -15.24) (xy 46.99 -15.494) (xy 47.498 -15.494)
			)
		)
		(polygon
			(pts
				(xy 46.736 -15.24) (xy 46.482 -15.24) (xy 46.482 -15.494) (xy 46.736 -15.494)
			)
		)
	)
	(zone
		(layer "F.Cu")
		(hatch none 0.5)
		(connect_pads
			(clearance 0)
		)
		(min_thickness 0.25)
		(keepout
			(tracks not_allowed)
			(vias allowed)
			(pads allowed)
			(copperpour not_allowed)
			(footprints allowed)
		)
		(placement
			(enabled no)
			(sheetname "")
		)
		(fill
			(thermal_gap 0.5)
			(thermal_bridge_width 0.5)
			(island_removal_mode 0)
		)
		(polygon
			(pts
				(arc
					(start 84.586572 -54.022498)
					(mid 84.247863 -53.670456)
					(end 83.895692 -54.009036)
				)
				(arc
					(start 83.885024 -54.567836)
					(mid 84.22386 -54.91988)
					(end 84.575904 -54.581044)
				)
				(xy 84.577936 -54.4703)
				(arc
					(start 84.433918 -54.4703)
					(mid 84.066339 -54.733505)
					(end 84.340954 -54.374288)
				)
				(xy 84.371688 -54.3433) (xy 84.42452 -54.3433) (xy 84.580476 -54.3433) (xy 84.582 -54.2671) (xy 84.455508 -54.2671)
				(xy 84.402676 -54.2671) (xy 84.365592 -54.230016)
				(arc
					(start 84.351622 -54.215792)
					(mid 84.079471 -53.853979)
					(end 84.441284 -54.12613)
				)
				(xy 84.455508 -54.1401) (xy 84.584286 -54.1401)
			)
		)
	)
	(zone
		(layer "F.Cu")
		(hatch none 0.5)
		(connect_pads
			(clearance 0)
		)
		(min_thickness 0.25)
		(keepout
			(tracks allowed)
			(vias allowed)
			(pads allowed)
			(copperpour allowed)
			(footprints not_allowed)
		)
		(placement
			(enabled no)
			(sheetname "")
		)
		(fill
			(thermal_gap 0.5)
			(thermal_bridge_width 0.5)
			(island_removal_mode 0)
		)
		(polygon
			(pts
				(arc
					(start 86.150958 -56.601106)
					(mid 85.450934 -58.701076)
					(end 86.150958 -60.800996)
				)
				(arc
					(start 91.750896 -60.800996)
					(mid 92.450818 -58.701076)
					(end 91.750896 -56.601106)
				)
			)
		)
	)
	(zone
		(layer "F.Cu")
		(hatch none 0.5)
		(connect_pads
			(clearance 0)
		)
		(min_thickness 0.25)
		(keepout
			(tracks not_allowed)
			(vias allowed)
			(pads allowed)
			(copperpour not_allowed)
			(footprints allowed)
		)
		(placement
			(enabled no)
			(sheetname "")
		)
		(fill
			(thermal_gap 0.5)
			(thermal_bridge_width 0.5)
			(island_removal_mode 0)
		)
		(polygon
			(pts
				(arc
					(start 59.078368 -10.552938)
					(mid 58.694574 -10.936351)
					(end 59.078114 -11.320018)
				)
				(arc
					(start 59.997594 -11.320018)
					(mid 60.381134 -10.936478)
					(end 59.997594 -10.552938)
				)
				(xy 59.77382 -10.552938) (xy 59.77382 -10.595864)
				(arc
					(start 59.87669 -10.698734)
					(mid 60.186194 -11.125078)
					(end 59.75985 -10.815574)
				)
				(xy 59.65698 -10.712704) (xy 59.60872 -10.664444) (xy 59.60872 -10.595864) (xy 59.60872 -10.552938)
				(xy 59.43092 -10.552938) (xy 59.43092 -10.631932) (xy 59.43092 -10.700512) (xy 59.38266 -10.748772)
				(arc
					(start 59.315858 -10.815574)
					(mid 58.889514 -11.125078)
					(end 59.199018 -10.698734)
				)
				(xy 59.26582 -10.631932) (xy 59.26582 -10.552938)
			)
		)
	)
	(zone
		(layer "F.Cu")
		(hatch none 0.5)
		(connect_pads
			(clearance 0)
		)
		(min_thickness 0.25)
		(keepout
			(tracks allowed)
			(vias allowed)
			(pads allowed)
			(copperpour allowed)
			(footprints allowed)
		)
		(placement
			(enabled no)
			(sheetname "")
		)
		(fill
			(thermal_gap 0.5)
			(thermal_bridge_width 0.5)
			(island_removal_mode 0)
		)
		(polygon
			(pts
				(xy 121.031 -72.771) (xy 121.031 -68.453) (xy 128.27 -68.453) (xy 128.27 -72.771)
			)
		)
	)
	(zone
		(net "VR_FET_SW_P12V_PVCCP_PVNN")
		(layer "F.Cu")
		(hatch none 0.5)
		(connect_pads
			(clearance 0.5)
		)
		(min_thickness 0.25)
		(fill yes
			(thermal_gap 0.5)
			(thermal_bridge_width 0.5)
			(island_removal_mode 0)
		)
		(polygon
			(pts
				(xy 37.973 -54.61) (xy 37.846 -54.737) (xy 37.846 -55.118) (xy 37.719 -55.245) (xy 31.623 -55.245)
				(xy 31.496 -55.372) (xy 31.496 -55.753) (xy 31.623 -55.88) (xy 31.623 -61.722) (xy 30.099 -63.246)
				(xy 29.845 -63.246) (xy 29.337 -63.754) (xy 29.337 -65.405) (xy 29.591 -65.659) (xy 32.893 -65.659)
				(xy 33.274 -65.278) (xy 35.941 -65.278) (xy 36.195 -65.024) (xy 36.195 -61.849) (xy 36.449 -61.595)
				(xy 39.751 -61.595) (xy 40.132 -61.214) (xy 40.132 -56.007) (xy 39.37 -55.245) (xy 39.37 -54.737)
				(xy 39.243 -54.61)
			)
		)
		(polygon
			(pts
				(xy 38.1 -58.801) (xy 36.703 -58.801) (xy 36.703 -60.071) (xy 36.83 -60.198) (xy 37.973 -60.198)
				(xy 38.354 -59.817) (xy 38.354 -59.055)
			)
		)
		(polygon
			(pts
				(xy 32.131 -55.7022) (xy 31.877 -55.7022) (xy 31.877 -55.9562) (xy 32.131 -55.9562)
			)
		)
		(polygon
			(pts
				(xy 38.7858 -54.9656) (xy 38.2778 -54.9656) (xy 38.2778 -55.2196) (xy 38.7858 -55.2196)
			)
		)
	)
	(zone
		(net "TPS74801_1V35_OUT")
		(layer "F.Cu")
		(hatch none 0.5)
		(connect_pads
			(clearance 0.5)
		)
		(min_thickness 0.25)
		(fill yes
			(thermal_gap 0.5)
			(thermal_bridge_width 0.5)
			(island_removal_mode 0)
		)
		(polygon
			(pts
				(xy 85.471 -15.367) (xy 85.344 -15.494) (xy 85.344 -17.145) (xy 85.598 -17.399) (xy 86.487 -17.399)
				(xy 86.995 -16.891) (xy 88.392 -16.891) (xy 88.9 -16.383) (xy 88.9 -15.494) (xy 88.773 -15.367)
			)
		)
	)
	(zone
		(net "GND")
		(layer "F.Cu")
		(hatch none 0.5)
		(connect_pads
			(clearance 0.5)
		)
		(min_thickness 0.25)
		(fill yes
			(thermal_gap 0.5)
			(thermal_bridge_width 0.5)
			(island_removal_mode 0)
		)
		(polygon
			(pts
				(xy 46.228 -63.627) (xy 46.101 -63.754) (xy 46.101 -64.77) (xy 46.228 -64.897) (xy 52.832 -64.897)
				(xy 53.086 -64.643) (xy 53.086 -63.754) (xy 52.959 -63.627)
			)
		)
		(polygon
			(pts
				(xy 51.054 -63.8429) (xy 50.8 -63.8429) (xy 50.8 -64.0969) (xy 51.054 -64.0969)
			)
		)
		(polygon
			(pts
				(xy 50.038 -63.8429) (xy 49.784 -63.8429) (xy 49.784 -64.0969) (xy 50.038 -64.0969)
			)
		)
	)
	(zone
		(net "VR_PVCCP_PWM_OUT")
		(layer "F.Cu")
		(hatch none 0.5)
		(connect_pads
			(clearance 0.5)
		)
		(min_thickness 0.25)
		(fill yes
			(thermal_gap 0.5)
			(thermal_bridge_width 0.5)
			(island_removal_mode 0)
		)
		(polygon
			(pts
				(xy 44.577 -53.721) (xy 44.45 -53.848) (xy 44.45 -54.737) (xy 43.307 -55.88) (xy 43.307 -58.928)
				(xy 43.434 -59.055) (xy 44.45 -59.055) (xy 44.704 -59.309) (xy 44.704 -60.198) (xy 45.466 -60.96)
				(xy 45.466 -62.357) (xy 45.847 -62.738) (xy 48.387 -62.738) (xy 48.641 -62.484) (xy 48.641 -55.753)
				(xy 48.387 -55.499) (xy 45.72 -55.499) (xy 45.466 -55.245) (xy 45.466 -53.848) (xy 45.339 -53.721)
			)
		)
	)
	(zone
		(net "GND")
		(layer "F.Cu")
		(hatch none 0.5)
		(connect_pads
			(clearance 0.5)
		)
		(min_thickness 0.25)
		(fill yes
			(thermal_gap 0.5)
			(thermal_bridge_width 0.5)
			(island_removal_mode 0)
		)
		(polygon
			(pts
				(xy 173.355 -11.176) (xy 171.577 -12.954) (xy 155.067 -12.954) (xy 154.94 -13.081) (xy 154.94 -15.113)
				(xy 157.226 -17.399) (xy 160.274 -17.399) (xy 163.195 -20.32) (xy 179.07 -20.32) (xy 180.848 -22.098)
				(xy 182.88 -22.098) (xy 183.007 -21.971) (xy 183.007 -19.812) (xy 183.261 -19.558) (xy 187.198 -19.558)
				(xy 188.976 -21.336) (xy 188.976 -22.479) (xy 188.849 -22.606) (xy 187.452 -22.606) (xy 187.325 -22.733)
				(xy 187.325 -23.368) (xy 187.452 -23.495) (xy 188.468 -23.495) (xy 190.5 -25.527) (xy 190.5 -25.908)
				(xy 189.865 -26.543) (xy 189.865 -27.305) (xy 189.992 -27.432) (xy 192.278 -27.432) (xy 192.405 -27.305)
				(xy 192.405 -26.797) (xy 192.278 -26.67) (xy 192.278 -26.162) (xy 197.104 -21.336) (xy 199.644 -21.336)
				(xy 199.771 -21.209) (xy 199.771 -18.796) (xy 200.533 -18.034) (xy 200.533 -12.7) (xy 199.009 -11.176)
				(xy 197.993 -11.176) (xy 193.802 -15.367) (xy 191.135 -15.367) (xy 191.008 -15.494) (xy 191.008 -15.875)
				(xy 190.627 -16.256) (xy 189.484 -16.256) (xy 189.357 -16.383) (xy 189.357 -17.145) (xy 189.738 -17.526)
				(xy 189.738 -18.034) (xy 189.484 -18.288) (xy 187.706 -18.288) (xy 187.325 -17.907) (xy 184.15 -17.907)
				(xy 184.023 -18.034) (xy 182.626 -18.034) (xy 182.372 -17.78) (xy 180.34 -17.78) (xy 179.578 -17.018)
				(xy 179.578 -14.986) (xy 179.959 -14.605) (xy 183.642 -14.605) (xy 183.896 -14.859) (xy 183.896 -15.367)
				(xy 184.023 -15.494) (xy 184.785 -15.494) (xy 184.912 -15.367) (xy 184.912 -11.557) (xy 184.531 -11.176)
			)
		)
		(polygon
			(pts
				(xy 191.0842 -26.3271) (xy 190.8302 -26.3271) (xy 190.8302 -26.5811) (xy 191.0842 -26.5811)
			)
		)
		(polygon
			(pts
				(xy 188.722 -22.9616) (xy 188.468 -22.9616) (xy 188.468 -23.2156) (xy 188.722 -23.2156)
			)
		)
		(polygon
			(pts
				(xy 188.214 -22.9616) (xy 187.96 -22.9616) (xy 187.96 -23.2156) (xy 188.214 -23.2156)
			)
		)
		(polygon
			(pts
				(xy 182.3339 -20.955) (xy 182.0799 -20.955) (xy 182.0799 -21.209) (xy 182.3339 -21.209)
			)
		)
		(polygon
			(pts
				(xy 189.5348 -18.6436) (xy 189.2808 -18.6436) (xy 189.2808 -18.8976) (xy 189.5348 -18.8976)
			)
		)
		(polygon
			(pts
				(xy 189.0268 -18.6436) (xy 188.7728 -18.6436) (xy 188.7728 -18.8976) (xy 189.0268 -18.8976)
			)
		)
		(polygon
			(pts
				(xy 181.229 -18.2372) (xy 180.975 -18.2372) (xy 180.975 -18.4912) (xy 181.229 -18.4912)
			)
		)
		(polygon
			(pts
				(xy 182.499 -18.1356) (xy 182.245 -18.1356) (xy 182.245 -18.3896) (xy 182.499 -18.3896)
			)
		)
		(polygon
			(pts
				(xy 181.991 -18.1356) (xy 181.737 -18.1356) (xy 181.737 -18.2372) (xy 181.483 -18.2372) (xy 181.483 -18.4912)
				(xy 181.737 -18.4912) (xy 181.737 -18.3896) (xy 181.991 -18.3896)
			)
		)
		(polygon
			(pts
				(xy 190.5 -17.0561) (xy 190.246 -17.0561) (xy 190.246 -17.3101) (xy 190.5 -17.3101)
			)
		)
		(polygon
			(pts
				(xy 184.1119 -14.097) (xy 183.8579 -14.097) (xy 183.8579 -14.605) (xy 184.1119 -14.605)
			)
		)
		(polygon
			(pts
				(xy 183.642 -13.6779) (xy 183.388 -13.6779) (xy 183.388 -13.9319) (xy 183.642 -13.9319)
			)
		)
		(polygon
			(pts
				(xy 182.626 -13.6779) (xy 182.118 -13.6779) (xy 182.118 -13.9319) (xy 182.626 -13.9319)
			)
		)
		(polygon
			(pts
				(xy 181.356 -13.6779) (xy 181.102 -13.6779) (xy 181.102 -13.9319) (xy 181.356 -13.9319)
			)
		)
		(polygon
			(pts
				(xy 171.8818 -13.628878) (xy 171.6278 -13.628878) (xy 171.6278 -13.882878) (xy 171.8818 -13.882878)
			)
		)
		(polygon
			(pts
				(xy 170.8658 -13.628878) (xy 170.6118 -13.628878) (xy 170.6118 -13.882878) (xy 170.8658 -13.882878)
			)
		)
		(polygon
			(pts
				(xy 155.7782 -13.336778) (xy 155.5242 -13.336778) (xy 155.5242 -13.590778) (xy 155.7782 -13.590778)
			)
		)
		(polygon
			(pts
				(xy 165.6842 -13.311378) (xy 165.4302 -13.311378) (xy 165.4302 -13.565378) (xy 165.6842 -13.565378)
			)
		)
		(polygon
			(pts
				(xy 165.1762 -13.311378) (xy 164.9222 -13.311378) (xy 164.9222 -13.565378) (xy 165.1762 -13.565378)
			)
		)
		(polygon
			(pts
				(xy 164.2872 -13.311378) (xy 164.0332 -13.311378) (xy 164.0332 -13.565378) (xy 164.2872 -13.565378)
			)
		)
		(polygon
			(pts
				(xy 163.7792 -13.311378) (xy 163.5252 -13.311378) (xy 163.5252 -13.565378) (xy 163.7792 -13.565378)
			)
		)
		(polygon
			(pts
				(xy 162.1282 -13.311378) (xy 161.8742 -13.311378) (xy 161.8742 -13.565378) (xy 162.1282 -13.565378)
			)
		)
		(polygon
			(pts
				(xy 161.6202 -13.311378) (xy 161.036 -13.311378) (xy 161.036 -13.565378) (xy 161.6202 -13.565378)
			)
		)
		(polygon
			(pts
				(xy 160.782 -13.311378) (xy 160.528 -13.311378) (xy 160.528 -13.565378) (xy 160.782 -13.565378)
			)
		)
		(polygon
			(pts
				(xy 184.1119 -13.081) (xy 183.8579 -13.081) (xy 183.8579 -13.335) (xy 184.1119 -13.335)
			)
		)
		(polygon
			(pts
				(xy 199.136 -11.6332) (xy 198.882 -11.6332) (xy 198.882 -11.8872) (xy 199.136 -11.8872)
			)
		)
		(polygon
			(pts
				(xy 198.628 -11.6332) (xy 198.374 -11.6332) (xy 198.374 -11.8872) (xy 198.628 -11.8872)
			)
		)
	)
	(zone
		(net "P12V")
		(layer "F.Cu")
		(hatch none 0.5)
		(connect_pads
			(clearance 0.5)
		)
		(min_thickness 0.25)
		(fill yes
			(thermal_gap 0.5)
			(thermal_bridge_width 0.5)
			(island_removal_mode 0)
		)
		(polygon
			(pts
				(xy 1.016 -38.989) (xy 0.762 -39.243) (xy 0.762 -41.91) (xy 1.016 -42.164) (xy 4.318 -42.164) (xy 5.461 -41.021)
				(xy 5.461 -39.243) (xy 5.207 -38.989)
			)
		)
		(polygon
			(pts
				(xy 4.5339 -40.2209) (xy 4.2799 -40.2209) (xy 4.2799 -40.4749) (xy 4.5339 -40.4749)
			)
		)
	)
	(zone
		(layer "F.Cu")
		(hatch none 0.5)
		(connect_pads
			(clearance 0)
		)
		(min_thickness 0.25)
		(keepout
			(tracks allowed)
			(vias allowed)
			(pads allowed)
			(copperpour allowed)
			(footprints allowed)
		)
		(placement
			(enabled no)
			(sheetname "")
		)
		(fill
			(thermal_gap 0.5)
			(thermal_bridge_width 0.5)
			(island_removal_mode 0)
		)
		(polygon
			(pts
				(xy 130.81 -42.037) (xy 130.81 -41.021) (xy 132.334 -41.021) (xy 132.334 -42.037)
			)
		)
	)
	(zone
		(layer "F.Cu")
		(hatch none 0.5)
		(connect_pads
			(clearance 0)
		)
		(min_thickness 0.25)
		(keepout
			(tracks not_allowed)
			(vias allowed)
			(pads allowed)
			(copperpour not_allowed)
			(footprints allowed)
		)
		(placement
			(enabled no)
			(sheetname "")
		)
		(fill
			(thermal_gap 0.5)
			(thermal_bridge_width 0.5)
			(island_removal_mode 0)
		)
		(polygon
			(pts
				(arc
					(start 10.01014 -64.516254)
					(mid 9.668238 -64.134472)
					(end 9.25195 -64.43345)
				)
				(arc
					(start 9.373108 -64.43345)
					(mid 9.893195 -64.516)
					(end 9.373108 -64.59855)
				)
				(xy 9.24306 -64.59855) (xy 9.24306 -65.32245)
				(arc
					(start 9.373108 -65.32245)
					(mid 9.893195 -65.405)
					(end 9.373108 -65.48755)
				)
				(arc
					(start 9.25195 -65.48755)
					(mid 9.668119 -65.786383)
					(end 10.01014 -65.405)
				)
			)
		)
	)
	(zone
		(layer "F.Cu")
		(hatch none 0.5)
		(connect_pads
			(clearance 0)
		)
		(min_thickness 0.25)
		(keepout
			(tracks allowed)
			(vias allowed)
			(pads allowed)
			(copperpour allowed)
			(footprints not_allowed)
		)
		(placement
			(enabled no)
			(sheetname "")
		)
		(fill
			(thermal_gap 0.5)
			(thermal_bridge_width 0.5)
			(island_removal_mode 0)
		)
		(polygon
			(pts
				(arc
					(start 14.429994 -43.805094)
					(mid 11.60018 -40.97528)
					(end 8.770112 -43.805094)
				)
				(arc
					(start 8.770112 -43.805094)
					(mid 11.60018 -46.635162)
					(end 14.429994 -43.805094)
				)
			)
		)
	)
	(zone
		(net "GND")
		(layer "F.Cu")
		(hatch none 0.5)
		(connect_pads
			(clearance 0.5)
		)
		(min_thickness 0.25)
		(fill yes
			(thermal_gap 0.5)
			(thermal_bridge_width 0.5)
			(island_removal_mode 0)
		)
		(polygon
			(pts
				(xy 117.602 -37.846) (xy 117.221 -38.227) (xy 117.221 -41.783) (xy 117.348 -41.91) (xy 121.793 -41.91)
				(xy 124.0028 -39.7002) (xy 124.0028 -38.6588) (xy 123.19 -37.846)
			)
		)
		(polygon
			(pts
				(xy 118.618 -38.217602) (xy 118.364 -38.217602) (xy 118.364 -38.471602) (xy 118.618 -38.471602)
			)
		)
		(polygon
			(pts
				(xy 118.11 -38.217602) (xy 117.856 -38.217602) (xy 117.856 -38.471602) (xy 118.11 -38.471602)
			)
		)
	)
	(zone
		(net "GND")
		(layer "F.Cu")
		(hatch none 0.5)
		(connect_pads
			(clearance 0.5)
		)
		(min_thickness 0.25)
		(fill yes
			(thermal_gap 0.5)
			(thermal_bridge_width 0.5)
			(island_removal_mode 0)
		)
		(polygon
			(pts
				(xy 110.289848 -48.022002) (xy 110.173262 -48.138588) (xy 110.173262 -48.443388) (xy 110.274862 -48.544988)
				(xy 111.417862 -48.544988) (xy 111.544862 -48.671988) (xy 111.544862 -50.729388) (xy 110.960662 -51.313588)
				(xy 110.960662 -52.467002) (xy 111.19866 -52.705) (xy 112.764062 -52.705) (xy 113.211864 -52.257198)
				(xy 113.211864 -49.221136) (xy 112.012984 -48.022002)
			)
		)
	)
	(zone
		(layer "F.Cu")
		(hatch none 0.5)
		(connect_pads
			(clearance 0)
		)
		(min_thickness 0.25)
		(keepout
			(tracks allowed)
			(vias allowed)
			(pads allowed)
			(copperpour allowed)
			(footprints not_allowed)
		)
		(placement
			(enabled no)
			(sheetname "")
		)
		(fill
			(thermal_gap 0.5)
			(thermal_bridge_width 0.5)
			(island_removal_mode 0)
		)
		(polygon
			(pts
				(xy 118.599966 -63.699898) (xy 118.599966 -69.600064) (xy 119.899938 -69.600064) (xy 119.899938 -63.699898)
			)
		)
	)
	(zone
		(layer "F.Cu")
		(hatch none 0.5)
		(connect_pads
			(clearance 0)
		)
		(min_thickness 0.25)
		(keepout
			(tracks allowed)
			(vias allowed)
			(pads allowed)
			(copperpour allowed)
			(footprints allowed)
		)
		(placement
			(enabled no)
			(sheetname "")
		)
		(fill
			(thermal_gap 0.5)
			(thermal_bridge_width 0.5)
			(island_removal_mode 0)
		)
		(polygon
			(pts
				(xy 143.5862 -24.1808) (xy 143.5862 -22.479) (xy 145.288 -22.479) (xy 145.288 -24.1808)
			)
		)
	)
	(zone
		(layer "F.Cu")
		(hatch none 0.5)
		(connect_pads
			(clearance 0)
		)
		(min_thickness 0.25)
		(keepout
			(tracks not_allowed)
			(vias allowed)
			(pads allowed)
			(copperpour not_allowed)
			(footprints allowed)
		)
		(placement
			(enabled no)
			(sheetname "")
		)
		(fill
			(thermal_gap 0.5)
			(thermal_bridge_width 0.5)
			(island_removal_mode 0)
		)
		(polygon
			(pts
				(arc
					(start 71.371206 -9.90092)
					(mid 70.987412 -10.284333)
					(end 71.370952 -10.668)
				)
				(arc
					(start 72.328532 -10.668)
					(mid 72.712072 -10.28446)
					(end 72.328532 -9.90092)
				)
				(xy 72.103742 -9.90092) (xy 72.103742 -9.94283)
				(arc
					(start 72.207628 -10.046716)
					(mid 72.517132 -10.47306)
					(end 72.090788 -10.163556)
				)
				(xy 71.986902 -10.05967) (xy 71.938642 -10.01141) (xy 71.938642 -9.94283) (xy 71.938642 -9.90092)
				(xy 71.760842 -9.90092) (xy 71.760842 -9.94283) (xy 71.760842 -10.01141) (xy 71.712582 -10.05967)
				(arc
					(start 71.608696 -10.163556)
					(mid 71.182352 -10.47306)
					(end 71.491856 -10.046716)
				)
				(xy 71.595742 -9.94283) (xy 71.595742 -9.90092)
			)
		)
	)
	(zone
		(net "P1V0_STBY_VOUT")
		(layer "F.Cu")
		(hatch none 0.5)
		(connect_pads
			(clearance 0.5)
		)
		(min_thickness 0.25)
		(fill yes
			(thermal_gap 0.5)
			(thermal_bridge_width 0.5)
			(island_removal_mode 0)
		)
		(polygon
			(pts
				(xy 56.642 -51.943) (xy 56.388 -52.197) (xy 56.388 -53.213) (xy 56.769 -53.594) (xy 56.769 -53.848)
				(xy 57.15 -54.229) (xy 59.563 -54.229) (xy 60.198 -53.594) (xy 62.357 -53.594) (xy 62.738 -53.213)
				(xy 63.627 -53.213) (xy 63.754 -53.086) (xy 63.754 -52.197) (xy 63.627 -52.07) (xy 59.182 -52.07)
				(xy 59.055 -52.197) (xy 59.055 -52.959) (xy 58.928 -53.086) (xy 57.658 -53.086) (xy 57.531 -52.959)
				(xy 57.531 -52.197) (xy 57.277 -51.943)
			)
		)
		(polygon
			(pts
				(xy 57.785 -53.5178) (xy 57.531 -53.5178) (xy 57.531 -53.7718) (xy 57.785 -53.7718)
			)
		)
		(polygon
			(pts
				(xy 57.277 -53.5178) (xy 57.023 -53.5178) (xy 57.023 -53.7718) (xy 57.277 -53.7718)
			)
		)
	)
	(zone
		(net "PV_VDDR")
		(layer "F.Cu")
		(hatch none 0.5)
		(connect_pads
			(clearance 0.5)
		)
		(min_thickness 0.25)
		(fill yes
			(thermal_gap 0.5)
			(thermal_bridge_width 0.5)
			(island_removal_mode 0)
		)
		(polygon
			(pts
				(xy 160.9852 -8.967978) (xy 160.8836 -9.069578) (xy 160.8836 -10.999978) (xy 160.7058 -11.177778)
				(xy 158.9786 -11.177778) (xy 158.8262 -11.025378) (xy 158.8262 -9.094978) (xy 158.7246 -8.993378)
				(xy 158.5722 -8.993378) (xy 158.4706 -9.094978) (xy 158.4706 -10.999978) (xy 158.2928 -11.177778)
				(xy 156.7434 -11.177778) (xy 156.3878 -10.822178) (xy 156.3878 -9.120378) (xy 156.3116 -9.044178)
				(xy 156.1592 -9.044178) (xy 156.1084 -9.094978) (xy 156.1084 -10.847578) (xy 155.956 -10.999978)
				(xy 155.954222 -10.999978) (xy 155.6512 -11.303) (xy 155.194 -11.303) (xy 155.067 -11.43) (xy 155.067 -12.5222)
				(xy 155.221178 -12.676378) (xy 171.4754 -12.676378) (xy 171.958 -12.193778) (xy 171.958 -11.431778)
				(xy 171.704 -11.177778) (xy 170.307 -11.177778) (xy 170.2054 -11.076178) (xy 170.2054 -9.145778)
				(xy 170.1038 -9.044178) (xy 169.9768 -9.044178) (xy 169.9006 -9.120378) (xy 169.9006 -11.050778)
				(xy 169.7736 -11.177778) (xy 168.021 -11.177778) (xy 167.8178 -10.974578) (xy 167.8178 -9.145778)
				(xy 167.7416 -9.069578) (xy 167.5384 -9.069578) (xy 167.4876 -9.120378) (xy 167.4876 -10.949178)
				(xy 167.259 -11.177778) (xy 165.608 -11.177778) (xy 165.4302 -10.999978) (xy 165.4302 -9.094978)
				(xy 165.3032 -8.967978) (xy 165.1762 -8.967978) (xy 165.0746 -9.069578) (xy 165.0746 -10.999978)
				(xy 164.8968 -11.177778) (xy 163.7792 -11.177778) (xy 163.6268 -11.025378) (xy 163.6268 -9.094978)
				(xy 163.4998 -8.967978) (xy 163.3982 -8.967978) (xy 163.2712 -9.094978) (xy 163.2712 -10.999978)
				(xy 163.0934 -11.177778) (xy 161.417 -11.177778) (xy 161.2138 -10.974578) (xy 161.2138 -9.069578)
				(xy 161.1122 -8.967978)
			)
		)
		(polygon
			(pts
				(xy 165.6842 -12.092178) (xy 165.4302 -12.092178) (xy 165.4302 -12.346178) (xy 165.6842 -12.346178)
			)
		)
		(polygon
			(pts
				(xy 165.1762 -12.092178) (xy 164.9222 -12.092178) (xy 164.9222 -12.346178) (xy 165.1762 -12.346178)
			)
		)
		(polygon
			(pts
				(xy 164.2872 -12.092178) (xy 164.0332 -12.092178) (xy 164.0332 -12.346178) (xy 164.2872 -12.346178)
			)
		)
		(polygon
			(pts
				(xy 163.7792 -12.092178) (xy 163.5252 -12.092178) (xy 163.5252 -12.346178) (xy 163.7792 -12.346178)
			)
		)
		(polygon
			(pts
				(xy 162.1282 -12.092178) (xy 161.8742 -12.092178) (xy 161.8742 -12.346178) (xy 162.1282 -12.346178)
			)
		)
		(polygon
			(pts
				(xy 161.6202 -12.092178) (xy 161.036 -12.092178) (xy 161.036 -12.346178) (xy 161.6202 -12.346178)
			)
		)
		(polygon
			(pts
				(xy 160.782 -12.092178) (xy 160.528 -12.092178) (xy 160.528 -12.346178) (xy 160.782 -12.346178)
			)
		)
		(polygon
			(pts
				(xy 155.7782 -11.811) (xy 155.5242 -11.811) (xy 155.5242 -12.320778) (xy 155.7782 -12.320778)
			)
		)
		(polygon
			(pts
				(xy 170.8658 -11.520678) (xy 170.6118 -11.520678) (xy 170.6118 -11.774678) (xy 170.8658 -11.774678)
			)
		)
	)
	(zone
		(layer "F.Cu")
		(hatch none 0.5)
		(connect_pads
			(clearance 0)
		)
		(min_thickness 0.25)
		(keepout
			(tracks not_allowed)
			(vias allowed)
			(pads allowed)
			(copperpour not_allowed)
			(footprints allowed)
		)
		(placement
			(enabled no)
			(sheetname "")
		)
		(fill
			(thermal_gap 0.5)
			(thermal_bridge_width 0.5)
			(island_removal_mode 0)
		)
		(polygon
			(pts
				(arc
					(start 35.408362 -9.867138)
					(mid 35.024822 -10.250678)
					(end 35.408362 -10.634218)
				)
				(arc
					(start 36.327588 -10.634218)
					(mid 36.711382 -10.250805)
					(end 36.327842 -9.867138)
				)
				(xy 36.104068 -9.867138) (xy 36.104068 -9.910064)
				(arc
					(start 36.206938 -10.012934)
					(mid 36.516442 -10.439278)
					(end 36.090098 -10.129774)
				)
				(xy 35.987228 -10.026904) (xy 35.938968 -9.978644) (xy 35.938968 -9.910064) (xy 35.938968 -9.867138)
				(xy 35.761168 -9.867138) (xy 35.761168 -9.946132) (xy 35.761168 -10.014712) (xy 35.712908 -10.062972)
				(arc
					(start 35.646106 -10.129774)
					(mid 35.219762 -10.439278)
					(end 35.529266 -10.012934)
				)
				(xy 35.596068 -9.946132) (xy 35.596068 -9.867138)
			)
		)
	)
	(zone
		(net "PV_VTT_DDR_B")
		(layer "F.Cu")
		(hatch none 0.5)
		(connect_pads
			(clearance 0.5)
		)
		(min_thickness 0.25)
		(fill yes
			(thermal_gap 0.5)
			(thermal_bridge_width 0.5)
			(island_removal_mode 0)
		)
		(polygon
			(pts
				(xy 191.262 -0.762) (xy 191.135 -0.889) (xy 191.135 -2.795778) (xy 191.8335 -3.494278) (xy 194.248278 -3.494278)
				(xy 195.199 -4.445) (xy 197.359778 -4.445) (xy 197.485 -4.319778) (xy 197.485 -1.016) (xy 197.231 -0.762)
			)
		)
		(polygon
			(pts
				(xy 196.8119 -3.429) (xy 196.5579 -3.429) (xy 196.5579 -3.683) (xy 196.8754 -3.937) (xy 197.1294 -3.937)
				(xy 197.1294 -3.683)
			)
		)
		(polygon
			(pts
				(xy 196.8119 -2.159) (xy 196.5579 -2.159) (xy 196.5579 -2.667) (xy 196.8119 -2.667)
			)
		)
		(polygon
			(pts
				(xy 196.8119 -1.143) (xy 196.5579 -1.143) (xy 196.5579 -1.397) (xy 196.8119 -1.397)
			)
		)
	)
	(zone
		(layer "F.Cu")
		(hatch none 0.5)
		(connect_pads
			(clearance 0)
		)
		(min_thickness 0.25)
		(keepout
			(tracks allowed)
			(vias allowed)
			(pads allowed)
			(copperpour allowed)
			(footprints not_allowed)
		)
		(placement
			(enabled no)
			(sheetname "")
		)
		(fill
			(thermal_gap 0.5)
			(thermal_bridge_width 0.5)
			(island_removal_mode 0)
		)
		(polygon
			(pts
				(xy 114.039904 -13.770102) (xy 114.039904 -9.230106) (xy 123.6599 -9.230106) (xy 123.6599 -13.770102)
			)
		)
	)
	(zone
		(net "VR_PVNN_PHASE")
		(layer "F.Cu")
		(hatch none 0.5)
		(connect_pads
			(clearance 0.5)
		)
		(min_thickness 0.25)
		(fill yes
			(thermal_gap 0.5)
			(thermal_bridge_width 0.5)
			(island_removal_mode 0)
		)
		(polygon
			(pts
				(xy 36.957 -63.246) (xy 36.703 -63.5) (xy 36.703 -65.278) (xy 36.449 -65.532) (xy 33.528 -65.532)
				(xy 33.401 -65.659) (xy 33.401 -66.421) (xy 33.528 -66.548) (xy 36.195 -66.548) (xy 36.322 -66.675)
				(xy 36.322 -67.945) (xy 35.433 -68.834) (xy 35.433 -69.342) (xy 35.687 -69.596) (xy 38.481 -69.596)
				(xy 38.862 -69.215) (xy 38.862 -63.373) (xy 38.735 -63.246)
			)
		)
	)
	(zone
		(layer "F.Cu")
		(hatch none 0.5)
		(connect_pads
			(clearance 0)
		)
		(min_thickness 0.25)
		(keepout
			(tracks allowed)
			(vias allowed)
			(pads allowed)
			(copperpour allowed)
			(footprints allowed)
		)
		(placement
			(enabled no)
			(sheetname "")
		)
		(fill
			(thermal_gap 0.5)
			(thermal_bridge_width 0.5)
			(island_removal_mode 0)
		)
		(polygon
			(pts
				(xy 78.130908 -63.373) (xy 77.114908 -63.373) (xy 77.114908 -61.640212) (xy 78.130908 -61.640212)
			)
		)
	)
	(zone
		(layer "F.Cu")
		(hatch none 0.5)
		(connect_pads
			(clearance 0)
		)
		(min_thickness 0.25)
		(keepout
			(tracks allowed)
			(vias allowed)
			(pads allowed)
			(copperpour allowed)
			(footprints allowed)
		)
		(placement
			(enabled no)
			(sheetname "")
		)
		(fill
			(thermal_gap 0.5)
			(thermal_bridge_width 0.5)
			(island_removal_mode 0)
		)
		(polygon
			(pts
				(xy 153.3144 -26.4922) (xy 153.3144 -25.9588) (xy 154.1018 -25.9588) (xy 154.1018 -26.4922)
			)
		)
	)
	(zone
		(net "P3V3_STBY")
		(layer "F.Cu")
		(hatch none 0.5)
		(connect_pads
			(clearance 0.5)
		)
		(min_thickness 0.25)
		(fill yes
			(thermal_gap 0.5)
			(thermal_bridge_width 0.5)
			(island_removal_mode 0)
		)
		(polygon
			(pts
				(xy 45.7835 -37.6809) (xy 45.466 -37.9984) (xy 45.466 -38.5318) (xy 46.609 -39.6748) (xy 46.609 -42.672)
				(xy 46.2534 -43.0276) (xy 46.2534 -44.4754) (xy 46.1518 -44.577) (xy 46.1518 -45.0342) (xy 45.974 -45.212)
				(xy 44.831 -45.212) (xy 44.196 -44.577) (xy 41.6306 -44.577) (xy 40.6654 -45.5422) (xy 40.6654 -46.1264)
				(xy 41.783 -47.244) (xy 43.815 -47.244) (xy 44.45 -46.609) (xy 47.498 -46.609) (xy 47.879 -46.228)
				(xy 47.879 -44.323) (xy 49.2887 -42.9133) (xy 49.2887 -38.9763) (xy 47.9933 -37.6809)
			)
		)
		(polygon
			(pts
				(xy 46.863 -44.831) (xy 46.609 -44.831) (xy 46.609 -45.085) (xy 46.863 -45.085)
			)
		)
		(polygon
			(pts
				(xy 46.863 -44.323) (xy 46.609 -44.323) (xy 46.609 -44.577) (xy 46.863 -44.577)
			)
		)
		(polygon
			(pts
				(xy 48.0314 -37.9984) (xy 47.7774 -37.9984) (xy 47.7774 -38.2524) (xy 48.0314 -38.2524)
			)
		)
		(polygon
			(pts
				(xy 47.5234 -37.9984) (xy 46.99 -37.9984) (xy 46.99 -38.2524) (xy 47.5234 -38.2524)
			)
		)
		(polygon
			(pts
				(xy 46.736 -37.9984) (xy 46.482 -37.9984) (xy 46.482 -38.2524) (xy 46.736 -38.2524)
			)
		)
	)
	(zone
		(net "GND")
		(layer "F.Cu")
		(hatch none 0.5)
		(connect_pads
			(clearance 0.5)
		)
		(min_thickness 0.25)
		(fill yes
			(thermal_gap 0.5)
			(thermal_bridge_width 0.5)
			(island_removal_mode 0)
		)
		(polygon
			(pts
				(xy 169.799 -35.179) (xy 169.672 -35.306) (xy 169.672 -36.576) (xy 170.815 -37.719) (xy 171.577 -37.719)
				(xy 172.339 -38.481) (xy 172.339 -43.942) (xy 171.577 -44.704) (xy 170.561 -44.704) (xy 169.799 -43.942)
				(xy 169.799 -42.545) (xy 169.672 -42.418) (xy 169.291 -42.418) (xy 169.164 -42.545) (xy 169.164 -44.577)
				(xy 171.45 -46.863) (xy 171.45 -48.641) (xy 171.196 -48.895) (xy 170.688 -48.895) (xy 170.434 -48.641)
				(xy 170.434 -46.482) (xy 170.307 -46.355) (xy 169.799 -46.355) (xy 169.672 -46.482) (xy 169.672 -49.911)
				(xy 171.196 -51.435) (xy 171.196 -53.594) (xy 168.656 -56.134) (xy 163.957 -56.134) (xy 163.83 -56.007)
				(xy 163.83 -51.689) (xy 163.449 -51.308) (xy 160.528 -51.308) (xy 160.274 -51.562) (xy 160.274 -57.277)
				(xy 160.147 -57.404) (xy 145.034 -57.404) (xy 144.907 -57.277) (xy 144.907 -56.642) (xy 144.78 -56.515)
				(xy 144.145 -56.515) (xy 144.018 -56.642) (xy 144.018 -58.166) (xy 142.748 -59.436) (xy 141.097 -59.436)
				(xy 140.97 -59.563) (xy 140.97 -61.087) (xy 141.224 -61.341) (xy 145.161 -61.341) (xy 147.2946 -59.2074)
				(xy 162.4076 -59.2074) (xy 163.068 -58.547) (xy 163.83 -58.547) (xy 164.084 -58.801) (xy 164.084 -60.706)
				(xy 164.592 -61.214) (xy 180.975 -61.214) (xy 181.864 -60.325) (xy 181.864 -53.086) (xy 182.118 -52.832)
				(xy 182.626 -52.832) (xy 182.753 -52.705) (xy 182.753 -52.197) (xy 182.499 -51.943) (xy 182.499 -51.435)
				(xy 182.372 -51.308) (xy 181.737 -51.308) (xy 181.483 -51.054) (xy 181.483 -49.784) (xy 180.34 -48.641)
				(xy 180.34 -47.625) (xy 179.197 -46.482) (xy 178.943 -46.482) (xy 178.816 -46.609) (xy 178.816 -58.039)
				(xy 177.165 -59.69) (xy 174.879 -59.69) (xy 173.609 -58.42) (xy 173.609 -57.404) (xy 173.482 -57.277)
				(xy 172.847 -57.277) (xy 172.593 -57.023) (xy 172.593 -55.499) (xy 172.974 -55.118) (xy 173.355 -55.118)
				(xy 173.482 -54.991) (xy 173.482 -51.435) (xy 172.466 -50.419) (xy 172.466 -46.101) (xy 172.593 -45.974)
				(xy 173.99 -45.974) (xy 174.752 -45.212) (xy 174.752 -44.704) (xy 174.625 -44.577) (xy 173.863 -44.577)
				(xy 173.228 -43.942) (xy 173.228 -42.672) (xy 173.355 -42.545) (xy 174.371 -42.545) (xy 174.498 -42.418)
				(xy 174.498 -41.91) (xy 174.371 -41.783) (xy 173.482 -41.783) (xy 173.355 -41.656) (xy 173.355 -40.64)
				(xy 173.482 -40.513) (xy 174.879 -40.513) (xy 175.133 -40.767) (xy 177.419 -40.767) (xy 177.546 -40.64)
				(xy 177.546 -36.449) (xy 177.292 -36.195) (xy 175.133 -36.195) (xy 174.117 -35.179)
			)
		)
		(polygon
			(pts
				(xy 164.7952 -60.452) (xy 164.5412 -60.452) (xy 164.5412 -60.706) (xy 164.7952 -60.706)
			)
		)
		(polygon
			(pts
				(xy 142.0241 -60.325) (xy 141.7701 -60.325) (xy 141.7701 -60.579) (xy 142.0241 -60.579)
			)
		)
		(polygon
			(pts
				(xy 164.7952 -59.944) (xy 164.5412 -59.944) (xy 164.5412 -60.198) (xy 164.7952 -60.198)
			)
		)
		(polygon
			(pts
				(xy 153.3652 -58.7883) (xy 153.1112 -58.7883) (xy 153.1112 -59.0423) (xy 153.3652 -59.0423)
			)
		)
		(polygon
			(pts
				(xy 157.734 -58.5724) (xy 157.48 -58.5724) (xy 157.48 -58.8264) (xy 157.734 -58.8264)
			)
		)
		(polygon
			(pts
				(xy 157.226 -58.5724) (xy 156.972 -58.5724) (xy 156.972 -58.8264) (xy 157.226 -58.8264)
			)
		)
		(polygon
			(pts
				(xy 155.956 -58.5724) (xy 155.702 -58.5724) (xy 155.702 -58.8264) (xy 155.956 -58.8264)
			)
		)
		(polygon
			(pts
				(xy 155.448 -58.5724) (xy 154.9146 -58.5724) (xy 154.9146 -58.8264) (xy 155.448 -58.8264)
			)
		)
		(polygon
			(pts
				(xy 154.6606 -58.5724) (xy 154.4066 -58.5724) (xy 154.1272 -58.7883) (xy 154.1272 -59.0423) (xy 154.3812 -59.0423)
				(xy 154.6606 -58.8264)
			)
		)
		(polygon
			(pts
				(xy 152.146 -58.5724) (xy 151.892 -58.5724) (xy 151.892 -58.8264) (xy 152.146 -58.8264)
			)
		)
		(polygon
			(pts
				(xy 151.638 -58.5724) (xy 151.384 -58.5724) (xy 151.384 -58.8264) (xy 151.638 -58.8264)
			)
		)
		(polygon
			(pts
				(xy 154.3812 -58.0009) (xy 154.1272 -58.0009) (xy 154.1272 -58.2549) (xy 154.3812 -58.2549)
			)
		)
		(polygon
			(pts
				(xy 153.3652 -58.0009) (xy 153.1112 -58.0009) (xy 153.1112 -58.2549) (xy 153.3652 -58.2549)
			)
		)
		(polygon
			(pts
				(xy 144.6276 -57.785) (xy 144.3736 -57.785) (xy 144.3736 -58.039) (xy 144.6276 -58.039)
			)
		)
		(polygon
			(pts
				(xy 173.228 -57.7342) (xy 172.974 -57.7342) (xy 172.974 -57.9882) (xy 173.228 -57.9882)
			)
		)
		(polygon
			(pts
				(xy 144.6276 -57.277) (xy 144.3736 -57.277) (xy 144.3736 -57.531) (xy 144.6276 -57.531)
			)
		)
		(polygon
			(pts
				(xy 167.386 -56.4896) (xy 167.132 -56.4896) (xy 167.132 -56.7436) (xy 167.386 -56.7436)
			)
		)
		(polygon
			(pts
				(xy 166.878 -56.4896) (xy 166.624 -56.4896) (xy 166.624 -56.7436) (xy 166.878 -56.7436)
			)
		)
		(polygon
			(pts
				(xy 182.372 -52.197) (xy 182.118 -52.197) (xy 182.118 -52.451) (xy 182.372 -52.451)
			)
		)
		(polygon
			(pts
				(xy 181.991 -51.6636) (xy 181.737 -51.6636) (xy 181.737 -51.9176) (xy 181.991 -51.9176)
			)
		)
		(polygon
			(pts
				(xy 179.4256 -49.022) (xy 179.1716 -49.022) (xy 179.1716 -49.276) (xy 179.4256 -49.276)
			)
		)
		(polygon
			(pts
				(xy 179.4256 -48.514) (xy 179.1716 -48.514) (xy 179.1716 -48.768) (xy 179.4256 -48.768)
			)
		)
		(polygon
			(pts
				(xy 174.2186 -44.8818) (xy 173.9646 -44.8818) (xy 173.9646 -45.1358) (xy 174.2186 -45.1358)
			)
		)
		(polygon
			(pts
				(xy 173.3931 -40.132) (xy 173.1391 -40.132) (xy 173.1391 -40.386) (xy 173.3931 -40.386)
			)
		)
		(polygon
			(pts
				(xy 173.3931 -39.116) (xy 173.1391 -39.116) (xy 173.1391 -39.37) (xy 173.3931 -39.37)
			)
		)
	)
	(zone
		(layer "F.Cu")
		(hatch none 0.5)
		(connect_pads
			(clearance 0)
		)
		(min_thickness 0.25)
		(keepout
			(tracks not_allowed)
			(vias allowed)
			(pads allowed)
			(copperpour not_allowed)
			(footprints allowed)
		)
		(placement
			(enabled no)
			(sheetname "")
		)
		(fill
			(thermal_gap 0.5)
			(thermal_bridge_width 0.5)
			(island_removal_mode 0)
		)
		(polygon
			(pts
				(arc
					(start 39.408608 -9.867138)
					(mid 39.024814 -10.250551)
					(end 39.408354 -10.634218)
				)
				(arc
					(start 40.327834 -10.634218)
					(mid 40.711374 -10.250678)
					(end 40.327834 -9.867138)
				)
				(xy 40.103806 -9.867138) (xy 40.103806 -9.90981)
				(arc
					(start 40.20693 -10.012934)
					(mid 40.516434 -10.439278)
					(end 40.09009 -10.129774)
				)
				(xy 39.986966 -10.02665) (xy 39.938706 -9.97839) (xy 39.938706 -9.90981) (xy 39.938706 -9.867138)
				(xy 39.760906 -9.867138) (xy 39.760906 -9.946386) (xy 39.760906 -10.014966) (xy 39.712646 -10.063226)
				(arc
					(start 39.646098 -10.129774)
					(mid 39.219754 -10.439278)
					(end 39.529258 -10.012934)
				)
				(xy 39.595806 -9.946386) (xy 39.595806 -9.867138)
			)
		)
	)
	(zone
		(layer "F.Cu")
		(hatch none 0.5)
		(connect_pads
			(clearance 0)
		)
		(min_thickness 0.25)
		(keepout
			(tracks allowed)
			(vias allowed)
			(pads allowed)
			(copperpour allowed)
			(footprints allowed)
		)
		(placement
			(enabled no)
			(sheetname "")
		)
		(fill
			(thermal_gap 0.5)
			(thermal_bridge_width 0.5)
			(island_removal_mode 0)
		)
		(polygon
			(pts
				(xy 129.159 -31.623) (xy 129.159 -29.718) (xy 132.334 -29.718) (xy 132.334 -31.623)
			)
		)
	)
	(zone
		(net "PVDDR_VIN")
		(layer "F.Cu")
		(hatch none 0.5)
		(connect_pads
			(clearance 0.5)
		)
		(min_thickness 0.25)
		(fill yes
			(thermal_gap 0.5)
			(thermal_bridge_width 0.5)
			(island_removal_mode 0)
		)
		(polygon
			(pts
				(xy 198.628 -22.987) (xy 198.374 -23.241) (xy 198.374 -24.003) (xy 198.628 -24.257) (xy 199.898 -24.257)
				(xy 200.279 -24.638) (xy 200.279 -27.178) (xy 200.914 -27.813) (xy 200.914 -31.877) (xy 201.422 -32.385)
				(xy 201.422 -34.163) (xy 201.295 -34.29) (xy 199.39 -34.29) (xy 199.136 -34.544) (xy 199.136 -35.306)
				(xy 199.263 -35.433) (xy 204.851 -35.433) (xy 204.978 -35.306) (xy 204.978 -34.925) (xy 204.851 -34.798)
				(xy 203.962 -34.798) (xy 203.835 -34.671) (xy 203.835 -32.385) (xy 204.978 -31.242) (xy 204.978 -28.829)
				(xy 204.343 -28.194) (xy 204.343 -25.781) (xy 202.946 -24.384) (xy 202.946 -23.114) (xy 202.819 -22.987)
			)
		)
	)
	(zone
		(layer "F.Cu")
		(hatch none 0.5)
		(connect_pads
			(clearance 0)
		)
		(min_thickness 0.25)
		(keepout
			(tracks not_allowed)
			(vias allowed)
			(pads allowed)
			(copperpour not_allowed)
			(footprints allowed)
		)
		(placement
			(enabled no)
			(sheetname "")
		)
		(fill
			(thermal_gap 0.5)
			(thermal_bridge_width 0.5)
			(island_removal_mode 0)
		)
		(polygon
			(pts
				(arc
					(start 69.52234 -27.52344)
					(mid 69.140705 -27.138123)
					(end 68.75526 -27.51963)
				)
				(arc
					(start 68.75145 -28.403296)
					(mid 69.133212 -28.788614)
					(end 69.51853 -28.406852)
				)
				(xy 69.51853 -28.405074) (xy 69.51853 -28.403296) (xy 69.519292 -28.23845) (xy 69.418454 -28.23845)
				(arc
					(start 69.372734 -28.28417)
					(mid 68.94639 -28.593674)
					(end 69.255894 -28.16733)
				)
				(xy 69.301614 -28.12161) (xy 69.349874 -28.07335) (xy 69.418454 -28.07335) (xy 69.520054 -28.07335)
				(xy 69.520816 -27.89555) (xy 69.464682 -27.89555) (xy 69.396102 -27.89555) (xy 69.347842 -27.84729)
				(arc
					(start 69.259704 -27.759152)
					(mid 68.9502 -27.332808)
					(end 69.376544 -27.642312)
				)
				(xy 69.464682 -27.73045) (xy 69.521324 -27.73045)
			)
		)
	)
	(zone
		(layer "F.Cu")
		(hatch none 0.5)
		(connect_pads
			(clearance 0)
		)
		(min_thickness 0.25)
		(keepout
			(tracks allowed)
			(vias allowed)
			(pads allowed)
			(copperpour allowed)
			(footprints allowed)
		)
		(placement
			(enabled no)
			(sheetname "")
		)
		(fill
			(thermal_gap 0.5)
			(thermal_bridge_width 0.5)
			(island_removal_mode 0)
		)
		(polygon
			(pts
				(xy 141.3256 -45.466) (xy 140.716 -45.466) (xy 140.716 -44.6786) (xy 141.3256 -44.6786)
			)
		)
	)
	(zone
		(net "P3V3_CPU")
		(layer "F.Cu")
		(hatch none 0.5)
		(connect_pads
			(clearance 0.5)
		)
		(min_thickness 0.25)
		(fill yes
			(thermal_gap 0.5)
			(thermal_bridge_width 0.5)
			(island_removal_mode 0)
		)
		(polygon
			(pts
				(xy 48.768 -26.035) (xy 48.514 -26.289) (xy 48.514 -27.178) (xy 48.641 -27.305) (xy 50.1396 -27.305)
				(xy 50.1523 -27.3177) (xy 50.165 -27.305) (xy 52.7558 -27.305) (xy 52.959 -27.1018) (xy 52.959 -26.289)
				(xy 52.705 -26.035)
			)
		)
	)
	(zone
		(layer "F.Cu")
		(hatch none 0.5)
		(connect_pads
			(clearance 0)
		)
		(min_thickness 0.25)
		(keepout
			(tracks not_allowed)
			(vias allowed)
			(pads allowed)
			(copperpour not_allowed)
			(footprints allowed)
		)
		(placement
			(enabled no)
			(sheetname "")
		)
		(fill
			(thermal_gap 0.5)
			(thermal_bridge_width 0.5)
			(island_removal_mode 0)
		)
		(polygon
			(pts
				(arc
					(start 79.37119 -9.95172)
					(mid 78.987396 -10.335133)
					(end 79.370936 -10.7188)
				)
				(arc
					(start 80.328516 -10.7188)
					(mid 80.712056 -10.33526)
					(end 80.328516 -9.95172)
				)
				(xy 80.103726 -9.95172) (xy 80.103726 -9.99363)
				(arc
					(start 80.207612 -10.097516)
					(mid 80.517116 -10.52386)
					(end 80.090772 -10.214356)
				)
				(xy 79.986886 -10.11047) (xy 79.938626 -10.06221) (xy 79.938626 -9.99363) (xy 79.938626 -9.95172)
				(xy 79.760826 -9.95172) (xy 79.760826 -9.99363) (xy 79.760826 -10.06221) (xy 79.712566 -10.11047)
				(arc
					(start 79.60868 -10.214356)
					(mid 79.182336 -10.52386)
					(end 79.49184 -10.097516)
				)
				(xy 79.595726 -9.99363) (xy 79.595726 -9.95172)
			)
		)
	)
	(zone
		(layer "F.Cu")
		(hatch none 0.5)
		(connect_pads
			(clearance 0)
		)
		(min_thickness 0.25)
		(keepout
			(tracks allowed)
			(vias allowed)
			(pads allowed)
			(copperpour allowed)
			(footprints not_allowed)
		)
		(placement
			(enabled no)
			(sheetname "")
		)
		(fill
			(thermal_gap 0.5)
			(thermal_bridge_width 0.5)
			(island_removal_mode 0)
		)
		(polygon
			(pts
				(xy 56.799988 -63.699898) (xy 56.799988 -69.600064) (xy 58.09996 -69.600064) (xy 58.09996 -63.699898)
			)
		)
	)
	(zone
		(layer "F.Cu")
		(hatch none 0.5)
		(connect_pads
			(clearance 0)
		)
		(min_thickness 0.25)
		(keepout
			(tracks allowed)
			(vias allowed)
			(pads allowed)
			(copperpour allowed)
			(footprints allowed)
		)
		(placement
			(enabled no)
			(sheetname "")
		)
		(fill
			(thermal_gap 0.5)
			(thermal_bridge_width 0.5)
			(island_removal_mode 0)
		)
		(polygon
			(pts
				(xy 140.4366 -58.4962) (xy 133.477 -58.4962) (xy 133.477 -54.5592) (xy 140.4366 -54.5592)
			)
		)
	)
	(zone
		(layer "F.Cu")
		(hatch none 0.5)
		(connect_pads
			(clearance 0)
		)
		(min_thickness 0.25)
		(keepout
			(tracks allowed)
			(vias allowed)
			(pads allowed)
			(copperpour allowed)
			(footprints allowed)
		)
		(placement
			(enabled no)
			(sheetname "")
		)
		(fill
			(thermal_gap 0.5)
			(thermal_bridge_width 0.5)
			(island_removal_mode 0)
		)
		(polygon
			(pts
				(xy 152.146 -41.529) (xy 152.146 -40.513) (xy 153.67 -40.513) (xy 153.67 -41.529)
			)
		)
	)
	(zone
		(layer "F.Cu")
		(hatch none 0.5)
		(connect_pads
			(clearance 0)
		)
		(min_thickness 0.25)
		(keepout
			(tracks not_allowed)
			(vias allowed)
			(pads allowed)
			(copperpour not_allowed)
			(footprints allowed)
		)
		(placement
			(enabled no)
			(sheetname "")
		)
		(fill
			(thermal_gap 0.5)
			(thermal_bridge_width 0.5)
			(island_removal_mode 0)
		)
		(polygon
			(pts
				(arc
					(start 82.0293 -53.0098)
					(mid 81.6864 -52.6669)
					(end 81.3435 -53.0098)
				)
				(arc
					(start 81.3435 -53.593746)
					(mid 81.686273 -53.9369)
					(end 82.0293 -53.594)
				)
				(xy 82.0293 -53.5178)
				(arc
					(start 81.902046 -53.5178)
					(mid 81.516328 -53.746922)
					(end 81.784952 -53.387752)
				)
				(xy 81.807304 -53.3654) (xy 82.0293 -53.3654) (xy 82.0293 -53.2892) (xy 81.858104 -53.2892)
				(arc
					(start 81.784952 -53.216048)
					(mid 81.524767 -52.848167)
					(end 81.892648 -53.108352)
				)
				(xy 81.921096 -53.1368) (xy 82.0293 -53.1368)
			)
		)
	)
	(zone
		(layer "F.Cu")
		(hatch none 0.5)
		(connect_pads
			(clearance 0)
		)
		(min_thickness 0.25)
		(keepout
			(tracks allowed)
			(vias allowed)
			(pads allowed)
			(copperpour allowed)
			(footprints allowed)
		)
		(placement
			(enabled no)
			(sheetname "")
		)
		(fill
			(thermal_gap 0.5)
			(thermal_bridge_width 0.5)
			(island_removal_mode 0)
		)
		(polygon
			(pts
				(xy 190.373 -12.066778) (xy 190.373 -7.748778) (xy 197.612 -7.748778) (xy 197.612 -12.066778)
			)
		)
	)
	(zone
		(net "P1V1")
		(layer "F.Cu")
		(hatch none 0.5)
		(connect_pads
			(clearance 0.5)
		)
		(min_thickness 0.25)
		(fill yes
			(thermal_gap 0.5)
			(thermal_bridge_width 0.5)
			(island_removal_mode 0)
		)
		(polygon
			(pts
				(xy 96.286828 -36.989512) (xy 96.053402 -37.222938) (xy 96.053402 -37.800788) (xy 96.479614 -38.227)
				(xy 96.51619 -38.227) (xy 96.51619 -38.497256) (xy 95.991934 -39.021512) (xy 95.991934 -39.259002)
				(xy 96.22663 -39.493698) (xy 97.79 -39.493698) (xy 98.034348 -39.24935) (xy 98.025712 -39.240714)
				(xy 98.025712 -38.26129) (xy 97.515934 -37.751512) (xy 97.515934 -37.116512) (xy 97.388934 -36.989512)
			)
		)
	)
	(zone
		(layer "F.Cu")
		(hatch none 0.5)
		(connect_pads
			(clearance 0)
		)
		(min_thickness 0.25)
		(keepout
			(tracks not_allowed)
			(vias allowed)
			(pads allowed)
			(copperpour not_allowed)
			(footprints allowed)
		)
		(placement
			(enabled no)
			(sheetname "")
		)
		(fill
			(thermal_gap 0.5)
			(thermal_bridge_width 0.5)
			(island_removal_mode 0)
		)
		(polygon
			(pts
				(xy 90.7161 -53.553614)
				(arc
					(start 90.918538 -53.756306)
					(mid 91.190689 -54.118119)
					(end 90.828876 -53.845968)
				)
				(xy 90.693494 -53.71084) (xy 90.681556 -53.93817)
				(arc
					(start 90.684096 -53.938424)
					(mid 91.010994 -54.30139)
					(end 91.37396 -53.974492)
				)
				(xy 91.3765 -53.974746) (xy 91.405964 -53.414422) (xy 91.40571 -53.414168)
				(arc
					(start 91.403424 -53.414168)
					(mid 91.254827 -53.111688)
					(end 90.9193 -53.07965)
				)
				(xy 90.9193 -53.166772)
				(arc
					(start 90.948002 -53.195728)
					(mid 91.220153 -53.557541)
					(end 90.85834 -53.28539)
				)
				(xy 90.829384 -53.256688) (xy 90.7923 -53.219604)
				(arc
					(start 90.7923 -53.175662)
					(mid 90.741918 -53.257551)
					(end 90.7161 -53.35016)
				)
			)
		)
	)
	(zone
		(net "GND")
		(layer "F.Cu")
		(hatch none 0.5)
		(connect_pads
			(clearance 0.5)
		)
		(min_thickness 0.25)
		(fill yes
			(thermal_gap 0.5)
			(thermal_bridge_width 0.5)
			(island_removal_mode 0)
		)
		(polygon
			(pts
				(xy 136.652 -54.864) (xy 136.525 -54.991) (xy 136.525 -60.706) (xy 136.398 -60.833) (xy 132.842 -60.833)
				(xy 132.715 -60.706) (xy 132.715 -58.293) (xy 132.588 -58.166) (xy 130.175 -58.166) (xy 129.921 -58.42)
				(xy 129.921 -60.96) (xy 130.429 -61.468) (xy 136.906 -61.468) (xy 138.303 -60.071) (xy 138.303 -54.991)
				(xy 138.176 -54.864)
			)
		)
		(polygon
			(pts
				(xy 137.2362 -60.3504) (xy 136.9822 -60.3504) (xy 136.9822 -60.6044) (xy 137.2362 -60.6044)
			)
		)
		(polygon
			(pts
				(xy 131.9149 -60.325) (xy 131.6609 -60.325) (xy 131.6609 -60.579) (xy 131.9149 -60.579)
			)
		)
		(polygon
			(pts
				(xy 137.1346 -59.5884) (xy 136.8806 -59.5884) (xy 136.8806 -59.8424) (xy 136.9822 -59.8424) (xy 136.9822 -60.0964)
				(xy 137.2362 -60.0964) (xy 137.2362 -59.8424) (xy 137.1346 -59.8424)
			)
		)
		(polygon
			(pts
				(xy 137.1346 -59.0804) (xy 136.8806 -59.0804) (xy 136.8806 -59.3344) (xy 137.1346 -59.3344)
			)
		)
		(polygon
			(pts
				(xy 131.9149 -59.055) (xy 131.6609 -59.055) (xy 131.6609 -59.563) (xy 131.9149 -59.563)
			)
		)
	)
	(zone
		(layer "F.Cu")
		(hatch none 0.5)
		(connect_pads
			(clearance 0)
		)
		(min_thickness 0.25)
		(keepout
			(tracks allowed)
			(vias allowed)
			(pads allowed)
			(copperpour allowed)
			(footprints allowed)
		)
		(placement
			(enabled no)
			(sheetname "")
		)
		(fill
			(thermal_gap 0.5)
			(thermal_bridge_width 0.5)
			(island_removal_mode 0)
		)
		(polygon
			(pts
				(xy 152.0444 -48.020732) (xy 152.0444 -54.1528) (xy 144.711928 -54.1528) (xy 144.711928 -48.020732)
			)
		)
	)
	(zone
		(layer "F.Cu")
		(hatch none 0.5)
		(connect_pads
			(clearance 0)
		)
		(min_thickness 0.25)
		(keepout
			(tracks not_allowed)
			(vias allowed)
			(pads allowed)
			(copperpour not_allowed)
			(footprints allowed)
		)
		(placement
			(enabled no)
			(sheetname "")
		)
		(fill
			(thermal_gap 0.5)
			(thermal_bridge_width 0.5)
			(island_removal_mode 0)
		)
		(polygon
			(pts
				(arc
					(start 80.264254 -60.0329)
					(mid 79.9211 -60.375673)
					(end 80.264 -60.7187)
				)
				(xy 80.39735 -60.7187) (xy 80.39735 -60.62599)
				(arc
					(start 80.356456 -60.584842)
					(mid 80.102373 -60.214173)
					(end 80.473042 -60.468256)
				)
				(xy 80.51419 -60.50915) (xy 80.56245 -60.55741) (xy 80.56245 -60.62599) (xy 80.56245 -60.7187) (xy 80.74025 -60.7187)
				(xy 80.74025 -60.63869) (xy 80.74025 -60.57011) (xy 80.78851 -60.52185)
				(arc
					(start 80.842358 -60.468256)
					(mid 81.213027 -60.214173)
					(end 80.958944 -60.584842)
				)
				(xy 80.90535 -60.63869) (xy 80.90535 -60.7187)
				(arc
					(start 81.0514 -60.7187)
					(mid 81.3943 -60.3758)
					(end 81.0514 -60.0329)
				)
			)
		)
	)
	(zone
		(layer "F.Cu")
		(hatch none 0.5)
		(connect_pads
			(clearance 0)
		)
		(min_thickness 0.25)
		(keepout
			(tracks allowed)
			(vias allowed)
			(pads allowed)
			(copperpour allowed)
			(footprints allowed)
		)
		(placement
			(enabled no)
			(sheetname "")
		)
		(fill
			(thermal_gap 0.5)
			(thermal_bridge_width 0.5)
			(island_removal_mode 0)
		)
		(polygon
			(pts
				(xy 134.747 -46.355) (xy 133.731 -46.355) (xy 133.731 -44.831) (xy 134.747 -44.831)
			)
		)
	)
	(zone
		(layer "F.Cu")
		(hatch none 0.5)
		(connect_pads
			(clearance 0)
		)
		(min_thickness 0.25)
		(keepout
			(tracks not_allowed)
			(vias allowed)
			(pads allowed)
			(copperpour not_allowed)
			(footprints allowed)
		)
		(placement
			(enabled no)
			(sheetname "")
		)
		(fill
			(thermal_gap 0.5)
			(thermal_bridge_width 0.5)
			(island_removal_mode 0)
		)
		(polygon
			(pts
				(arc
					(start 10.01014 -60.960254)
					(mid 9.668238 -60.578472)
					(end 9.25195 -60.87745)
				)
				(arc
					(start 9.373108 -60.87745)
					(mid 9.893195 -60.96)
					(end 9.373108 -61.04255)
				)
				(xy 9.24306 -61.04255) (xy 9.24306 -61.76645)
				(arc
					(start 9.373108 -61.76645)
					(mid 9.893195 -61.849)
					(end 9.373108 -61.93155)
				)
				(arc
					(start 9.25195 -61.93155)
					(mid 9.668119 -62.230383)
					(end 10.01014 -61.849)
				)
			)
		)
	)
	(zone
		(layer "F.Cu")
		(hatch none 0.5)
		(connect_pads
			(clearance 0)
		)
		(min_thickness 0.25)
		(keepout
			(tracks allowed)
			(vias allowed)
			(pads allowed)
			(copperpour allowed)
			(footprints allowed)
		)
		(placement
			(enabled no)
			(sheetname "")
		)
		(fill
			(thermal_gap 0.5)
			(thermal_bridge_width 0.5)
			(island_removal_mode 0)
		)
		(polygon
			(pts
				(xy 150.6982 -24.2062) (xy 150.6982 -22.5044) (xy 151.4856 -22.5044) (xy 151.4856 -24.2062)
			)
		)
	)
	(zone
		(layer "F.Cu")
		(hatch none 0.5)
		(connect_pads
			(clearance 0)
		)
		(min_thickness 0.25)
		(keepout
			(tracks not_allowed)
			(vias allowed)
			(pads allowed)
			(copperpour not_allowed)
			(footprints allowed)
		)
		(placement
			(enabled no)
			(sheetname "")
		)
		(fill
			(thermal_gap 0.5)
			(thermal_bridge_width 0.5)
			(island_removal_mode 0)
		)
		(polygon
			(pts
				(xy 83.433158 -55.988458) (xy 83.550252 -55.854092) (xy 83.40725 -55.71109)
				(arc
					(start 83.364832 -55.668672)
					(mid 83.41172 -55.22659)
					(end 83.571334 -55.641494)
				)
				(xy 83.659218 -55.729378)
				(arc
					(start 83.701636 -55.68061)
					(mid 83.668625 -55.193446)
					(end 83.18119 -55.226204)
				)
				(arc
					(start 82.803746 -55.65902)
					(mid 82.83702 -56.146446)
					(end 83.324446 -56.113172)
				)
				(arc
					(start 83.241388 -56.030368)
					(mid 82.842591 -55.829684)
					(end 83.288886 -55.844186)
				)
				(xy 83.296506 -55.851806)
			)
		)
	)
	(zone
		(net "VR_PVIN_P1V0_STBY")
		(layer "F.Cu")
		(hatch none 0.5)
		(connect_pads
			(clearance 0.5)
		)
		(min_thickness 0.25)
		(fill yes
			(thermal_gap 0.5)
			(thermal_bridge_width 0.5)
			(island_removal_mode 0)
		)
		(polygon
			(pts
				(xy 56.261 -47.625) (xy 55.626 -48.26) (xy 52.578 -48.26) (xy 51.308 -49.53) (xy 51.308 -50.546)
				(xy 51.435 -50.673) (xy 52.324 -50.673) (xy 52.451 -50.546) (xy 52.451 -49.911) (xy 53.213 -49.149)
				(xy 53.848 -49.149) (xy 53.975 -49.276) (xy 53.975 -49.53) (xy 55.118 -50.673) (xy 56.007 -50.673)
				(xy 56.134 -50.546) (xy 56.134 -49.403) (xy 56.261 -49.276) (xy 56.896 -49.276) (xy 57.023 -49.149)
				(xy 57.023 -47.752) (xy 56.896 -47.625)
			)
		)
		(polygon
			(pts
				(xy 55.6768 -48.7426) (xy 55.4228 -48.7426) (xy 55.4228 -48.9966) (xy 55.6768 -48.9966)
			)
		)
		(polygon
			(pts
				(xy 53.9242 -48.4378) (xy 53.6702 -48.4378) (xy 53.6702 -48.6918) (xy 53.9242 -48.6918)
			)
		)
	)
	(zone
		(layer "F.Cu")
		(hatch none 0.5)
		(connect_pads
			(clearance 0)
		)
		(min_thickness 0.25)
		(keepout
			(tracks not_allowed)
			(vias allowed)
			(pads allowed)
			(copperpour not_allowed)
			(footprints allowed)
		)
		(placement
			(enabled no)
			(sheetname "")
		)
		(fill
			(thermal_gap 0.5)
			(thermal_bridge_width 0.5)
			(island_removal_mode 0)
		)
		(polygon
			(pts
				(arc
					(start 75.371198 -9.90092)
					(mid 74.987404 -10.284333)
					(end 75.370944 -10.668)
				)
				(arc
					(start 76.328524 -10.668)
					(mid 76.712064 -10.28446)
					(end 76.328524 -9.90092)
				)
				(xy 76.103734 -9.90092) (xy 76.103734 -9.94283)
				(arc
					(start 76.20762 -10.046716)
					(mid 76.517124 -10.47306)
					(end 76.09078 -10.163556)
				)
				(xy 75.986894 -10.05967) (xy 75.938634 -10.01141) (xy 75.938634 -9.94283) (xy 75.938634 -9.90092)
				(xy 75.760834 -9.90092) (xy 75.760834 -9.94283) (xy 75.760834 -10.01141) (xy 75.712574 -10.05967)
				(arc
					(start 75.608688 -10.163556)
					(mid 75.182344 -10.47306)
					(end 75.491848 -10.046716)
				)
				(xy 75.595734 -9.94283) (xy 75.595734 -9.90092)
			)
		)
	)
	(zone
		(layer "F.Cu")
		(hatch none 0.5)
		(connect_pads
			(clearance 0)
		)
		(min_thickness 0.25)
		(keepout
			(tracks not_allowed)
			(vias allowed)
			(pads allowed)
			(copperpour not_allowed)
			(footprints allowed)
		)
		(placement
			(enabled no)
			(sheetname "")
		)
		(fill
			(thermal_gap 0.5)
			(thermal_bridge_width 0.5)
			(island_removal_mode 0)
		)
		(polygon
			(pts
				(arc
					(start 86.030054 -54.801008)
					(mid 85.689948 -54.450234)
					(end 85.339174 -54.79034)
				)
				(arc
					(start 85.330538 -55.356506)
					(mid 85.670517 -55.707536)
					(end 86.021418 -55.367428)
				)
				(xy 86.02345 -55.22722) (xy 85.900768 -55.22722)
				(arc
					(start 85.87613 -55.251604)
					(mid 85.514317 -55.523755)
					(end 85.786468 -55.161942)
				)
				(xy 85.810852 -55.137304) (xy 85.847936 -55.10022) (xy 85.900768 -55.10022) (xy 86.025482 -55.10022)
				(xy 86.026752 -55.02402) (xy 85.875876 -55.02402) (xy 85.823044 -55.02402)
				(arc
					(start 85.795104 -54.995826)
					(mid 85.519339 -54.637709)
					(end 85.889592 -54.89702)
				)
				(xy 86.02853 -54.89702)
			)
		)
	)
	(zone
		(layer "F.Cu")
		(hatch none 0.5)
		(connect_pads
			(clearance 0)
		)
		(min_thickness 0.25)
		(keepout
			(tracks allowed)
			(vias allowed)
			(pads allowed)
			(copperpour allowed)
			(footprints not_allowed)
		)
		(placement
			(enabled no)
			(sheetname "")
		)
		(fill
			(thermal_gap 0.5)
			(thermal_bridge_width 0.5)
			(island_removal_mode 0)
		)
		(polygon
			(pts
				(xy 206.000096 0) (xy 163.620958 0) (xy 163.620958 -9.240012) (xy 194.00012 -9.240012) (xy 194.00012 -36.139882)
				(xy 192.499996 -36.139882) (xy 192.499996 -63.799974) (xy 124.499878 -63.799974) (xy 124.499878 -36.139882)
				(xy 126.000002 -36.139882) (xy 126.000002 -9.240012) (xy 163.121086 -9.240012) (xy 163.121086 0)
				(arc
					(start 106.000042 0)
					(mid 105.292937 -0.292893)
					(end 105.000044 -0.999998)
				)
				(xy 105.000044 -9.230106) (xy 123.6599 -9.230106) (xy 123.6599 -13.770102) (xy 118.474998 -13.770102)
				(xy 118.474998 -64.200024) (xy 99.54006 -64.200024) (xy 99.54006 -69.600064) (xy 99.000056 -69.600064)
				(xy 99.000056 -73.799954) (xy 118.599966 -73.799954) (xy 118.599966 -63.699898) (xy 119.899938 -63.699898)
				(xy 119.899938 -69.600064) (xy 122.599958 -69.600064) (xy 122.599958 -73.799954) (xy 206.000096 -73.799954)
			)
		)
	)
	(zone
		(layer "F.Cu")
		(hatch none 0.5)
		(connect_pads
			(clearance 0)
		)
		(min_thickness 0.25)
		(keepout
			(tracks not_allowed)
			(vias allowed)
			(pads allowed)
			(copperpour not_allowed)
			(footprints allowed)
		)
		(placement
			(enabled no)
			(sheetname "")
		)
		(fill
			(thermal_gap 0.5)
			(thermal_bridge_width 0.5)
			(island_removal_mode 0)
		)
		(polygon
			(pts
				(arc
					(start 99.781106 -60.369704)
					(mid 99.238816 -60.378086)
					(end 99.247198 -60.920376)
				)
				(xy 99.24542 -60.922154) (xy 99.86518 -61.523372) (xy 99.865434 -61.523372)
				(arc
					(start 99.866958 -61.521848)
					(mid 100.409565 -61.513655)
					(end 100.40112 -60.971176)
				)
				(xy 100.402898 -60.969398) (xy 100.278438 -60.848748) (xy 100.216716 -60.910724)
				(arc
					(start 100.216716 -60.99302)
					(mid 100.134166 -61.513107)
					(end 100.051616 -60.99302)
				)
				(xy 100.051616 -60.910724) (xy 100.051616 -60.842144) (xy 100.099876 -60.793884) (xy 100.160074 -60.733686)
				(xy 100.032312 -60.609988) (xy 99.96297 -60.67933) (xy 99.91471 -60.72759) (xy 99.84613 -60.72759)
				(arc
					(start 99.767644 -60.72759)
					(mid 99.247557 -60.64504)
					(end 99.767644 -60.56249)
				)
				(xy 99.84613 -60.56249) (xy 99.913694 -60.494926) (xy 99.782884 -60.367926)
			)
		)
	)
	(zone
		(layer "F.Cu")
		(hatch none 0.5)
		(connect_pads
			(clearance 0)
		)
		(min_thickness 0.25)
		(keepout
			(tracks not_allowed)
			(vias allowed)
			(pads allowed)
			(copperpour not_allowed)
			(footprints allowed)
		)
		(placement
			(enabled no)
			(sheetname "")
		)
		(fill
			(thermal_gap 0.5)
			(thermal_bridge_width 0.5)
			(island_removal_mode 0)
		)
		(polygon
			(pts
				(arc
					(start 13.55598 -47.66056)
					(mid 13.17244 -47.27702)
					(end 12.7889 -47.66056)
				)
				(xy 12.7889 -47.88535) (xy 12.83081 -47.88535)
				(arc
					(start 12.934696 -47.781464)
					(mid 13.36104 -47.47196)
					(end 13.051536 -47.898304)
				)
				(xy 12.94765 -48.00219) (xy 12.89939 -48.05045) (xy 12.83081 -48.05045) (xy 12.7889 -48.05045) (xy 12.7889 -48.22825)
				(xy 12.83081 -48.22825) (xy 12.89939 -48.22825) (xy 12.94765 -48.27651)
				(arc
					(start 13.051536 -48.380396)
					(mid 13.36104 -48.80674)
					(end 12.934696 -48.497236)
				)
				(xy 12.83081 -48.39335) (xy 12.7889 -48.39335)
				(arc
					(start 12.7889 -48.617886)
					(mid 13.172313 -49.00168)
					(end 13.55598 -48.61814)
				)
			)
		)
	)
	(zone
		(net "P1V8_STBY_LDO_IN1")
		(layer "F.Cu")
		(hatch none 0.5)
		(connect_pads
			(clearance 0.5)
		)
		(min_thickness 0.25)
		(fill yes
			(thermal_gap 0.5)
			(thermal_bridge_width 0.5)
			(island_removal_mode 0)
		)
		(polygon
			(pts
				(xy 168.148 -29.464) (xy 168.021 -29.591) (xy 168.021 -32.639) (xy 168.148 -32.766) (xy 169.164 -32.766)
				(xy 169.291 -32.639) (xy 171.704 -32.639) (xy 171.831 -32.512) (xy 171.831 -30.861) (xy 170.815 -29.845)
				(xy 169.418 -29.845) (xy 169.037 -29.464)
			)
		)
		(polygon
			(pts
				(xy 168.8211 -30.6324) (xy 168.5671 -30.6324) (xy 168.5671 -30.8864) (xy 168.8211 -30.8864)
			)
		)
		(polygon
			(pts
				(xy 168.8211 -29.6164) (xy 168.5671 -29.6164) (xy 168.5671 -29.8704) (xy 168.8211 -29.8704)
			)
		)
	)
	(zone
		(net "GND")
		(layer "F.Cu")
		(hatch none 0.5)
		(connect_pads
			(clearance 0.5)
		)
		(min_thickness 0.25)
		(fill yes
			(thermal_gap 0.5)
			(thermal_bridge_width 0.5)
			(island_removal_mode 0)
		)
		(polygon
			(pts
				(xy 135.001 -12.7) (xy 134.747 -12.954) (xy 134.747 -14.859) (xy 134.874 -14.986) (xy 136.906 -14.986)
				(xy 137.16 -15.24) (xy 137.16 -17.272) (xy 140.97 -21.082) (xy 140.97 -22.733) (xy 141.097 -22.86)
				(xy 141.732 -22.86) (xy 141.859 -22.733) (xy 141.859 -19.685) (xy 141.986 -19.558) (xy 143.256 -19.558)
				(xy 143.637 -19.177) (xy 145.034 -19.177) (xy 145.161 -19.05) (xy 145.161 -18.288) (xy 145.669 -17.78)
				(xy 148.082 -17.78) (xy 148.59 -18.288) (xy 148.59 -19.431) (xy 148.336 -19.685) (xy 148.336 -20.447)
				(xy 148.463 -20.574) (xy 151.257 -20.574) (xy 151.384 -20.701) (xy 151.384 -24.511) (xy 151.511 -24.638)
				(xy 151.892 -24.638) (xy 152.019 -24.511) (xy 152.019 -22.479) (xy 151.892 -22.352) (xy 151.892 -21.844)
				(xy 152.146 -21.59) (xy 154.051 -21.59) (xy 155.067 -22.606) (xy 155.067 -24.511) (xy 155.194 -24.638)
				(xy 155.448 -24.638) (xy 155.575 -24.511) (xy 155.575 -18.669) (xy 149.606 -12.7)
			)
		)
		(polygon
			(pts
				(xy 151.384 -19.9644) (xy 151.13 -19.9644) (xy 151.13 -20.2184) (xy 151.384 -20.2184)
			)
		)
		(polygon
			(pts
				(xy 150.876 -19.9644) (xy 150.368 -19.9644) (xy 150.368 -20.2184) (xy 150.876 -20.2184)
			)
		)
		(polygon
			(pts
				(xy 150.114 -19.9644) (xy 149.86 -19.9644) (xy 149.86 -20.2184) (xy 150.114 -20.2184)
			)
		)
		(polygon
			(pts
				(xy 149.098 -19.9644) (xy 148.844 -19.9644) (xy 148.844 -20.2184) (xy 149.098 -20.2184)
			)
		)
		(polygon
			(pts
				(xy 144.272 -18.4658) (xy 144.018 -18.4658) (xy 144.018 -18.7198) (xy 144.272 -18.7198)
			)
		)
		(polygon
			(pts
				(xy 143.764 -18.4658) (xy 143.51 -18.4658) (xy 143.51 -18.7198) (xy 143.764 -18.7198)
			)
		)
		(polygon
			(pts
				(xy 136.906 -14.3764) (xy 136.652 -14.3764) (xy 136.652 -14.6304) (xy 136.906 -14.6304)
			)
		)
		(polygon
			(pts
				(xy 136.398 -14.3764) (xy 136.144 -14.3764) (xy 136.144 -14.6304) (xy 136.398 -14.6304)
			)
		)
	)
	(zone
		(net "P12V")
		(layer "F.Cu")
		(hatch none 0.5)
		(connect_pads
			(clearance 0.5)
		)
		(min_thickness 0.25)
		(fill yes
			(thermal_gap 0.5)
			(thermal_bridge_width 0.5)
			(island_removal_mode 0)
		)
		(polygon
			(pts
				(xy 27.686 -66.294) (xy 27.432 -66.548) (xy 27.432 -69.3547) (xy 26.543 -70.2437) (xy 23.8379 -70.2437)
				(xy 22.5806 -71.501) (xy 22.5806 -72.5678) (xy 22.9108 -72.898) (xy 31.5722 -72.898) (xy 32.004 -72.4662)
				(xy 32.004 -68.6054) (xy 32.0167 -68.5927) (xy 32.004 -68.58) (xy 32.004 -66.548) (xy 31.75 -66.294)
			)
		)
		(polygon
			(pts
				(xy 28.3591 -68.58) (xy 28.1051 -68.58) (xy 28.1051 -68.834) (xy 28.3591 -68.834)
			)
		)
		(polygon
			(pts
				(xy 28.3591 -67.564) (xy 28.1051 -67.564) (xy 28.1051 -67.818) (xy 28.3591 -67.818)
			)
		)
	)
	(zone
		(net "GND")
		(layer "F.Cu")
		(hatch none 0.5)
		(connect_pads
			(clearance 0.5)
		)
		(min_thickness 0.25)
		(fill yes
			(thermal_gap 0.5)
			(thermal_bridge_width 0.5)
			(island_removal_mode 0)
		)
		(polygon
			(pts
				(xy 41.148 -35.814) (xy 41.021 -35.941) (xy 41.021 -37.465) (xy 40.386 -38.1) (xy 40.386 -38.735)
				(xy 40.513 -38.862) (xy 42.037 -38.862) (xy 42.291 -39.116) (xy 42.799 -39.116) (xy 43.053 -39.37)
				(xy 43.053 -39.624) (xy 43.18 -39.751) (xy 43.815 -39.751) (xy 43.942 -39.624) (xy 43.942 -39.116)
				(xy 43.815 -38.989) (xy 43.561 -38.989) (xy 43.307 -38.735) (xy 43.307 -37.465) (xy 43.561 -37.211)
				(xy 44.196 -37.211) (xy 44.323 -37.084) (xy 44.323 -36.83) (xy 43.942 -36.449) (xy 43.942 -35.941)
				(xy 43.815 -35.814)
			)
		)
		(polygon
			(pts
				(xy 42.9006 -38.4048) (xy 42.6466 -38.4048) (xy 42.6466 -38.6588) (xy 42.9006 -38.6588)
			)
		)
		(polygon
			(pts
				(xy 42.3926 -38.4048) (xy 42.1386 -38.4048) (xy 42.1386 -38.6588) (xy 42.3926 -38.6588)
			)
		)
		(polygon
			(pts
				(xy 40.9702 -38.2778) (xy 40.7162 -38.2778) (xy 40.7162 -38.5318) (xy 40.9702 -38.5318)
			)
		)
	)
	(zone
		(layer "F.Cu")
		(hatch none 0.5)
		(connect_pads
			(clearance 0)
		)
		(min_thickness 0.25)
		(keepout
			(tracks allowed)
			(vias allowed)
			(pads allowed)
			(copperpour allowed)
			(footprints allowed)
		)
		(placement
			(enabled no)
			(sheetname "")
		)
		(fill
			(thermal_gap 0.5)
			(thermal_bridge_width 0.5)
			(island_removal_mode 0)
		)
		(polygon
			(pts
				(xy 151.5872 -30.226) (xy 151.5872 -29.083) (xy 153.797 -29.083) (xy 153.797 -30.226)
			)
		)
	)
	(zone
		(layer "F.Cu")
		(hatch none 0.5)
		(connect_pads
			(clearance 0)
		)
		(min_thickness 0.25)
		(keepout
			(tracks allowed)
			(vias allowed)
			(pads allowed)
			(copperpour allowed)
			(footprints allowed)
		)
		(placement
			(enabled no)
			(sheetname "")
		)
		(fill
			(thermal_gap 0.5)
			(thermal_bridge_width 0.5)
			(island_removal_mode 0)
		)
		(polygon
			(pts
				(xy 152.2222 -37.2618) (xy 152.2222 -35.56) (xy 153.924 -35.56) (xy 153.924 -37.2618)
			)
		)
	)
	(zone
		(layer "F.Cu")
		(hatch none 0.5)
		(connect_pads
			(clearance 0)
		)
		(min_thickness 0.25)
		(keepout
			(tracks allowed)
			(vias allowed)
			(pads allowed)
			(copperpour allowed)
			(footprints allowed)
		)
		(placement
			(enabled no)
			(sheetname "")
		)
		(fill
			(thermal_gap 0.5)
			(thermal_bridge_width 0.5)
			(island_removal_mode 0)
		)
		(polygon
			(pts
				(xy 130.937 -39.624) (xy 130.937 -37.211) (xy 133.2992 -37.211) (xy 133.2992 -39.624)
			)
		)
	)
	(zone
		(layer "F.Cu")
		(hatch none 0.5)
		(connect_pads
			(clearance 0)
		)
		(min_thickness 0.25)
		(keepout
			(tracks not_allowed)
			(vias allowed)
			(pads allowed)
			(copperpour not_allowed)
			(footprints allowed)
		)
		(placement
			(enabled no)
			(sheetname "")
		)
		(fill
			(thermal_gap 0.5)
			(thermal_bridge_width 0.5)
			(island_removal_mode 0)
		)
		(polygon
			(pts
				(arc
					(start 19.408648 -9.867138)
					(mid 19.024854 -10.250551)
					(end 19.408394 -10.634218)
				)
				(arc
					(start 20.327874 -10.634218)
					(mid 20.711414 -10.250678)
					(end 20.327874 -9.867138)
				)
				(xy 20.103846 -9.867138) (xy 20.103846 -9.90981)
				(arc
					(start 20.20697 -10.012934)
					(mid 20.516474 -10.439278)
					(end 20.09013 -10.129774)
				)
				(xy 19.987006 -10.02665) (xy 19.938746 -9.97839) (xy 19.938746 -9.90981) (xy 19.938746 -9.867138)
				(xy 19.760946 -9.867138) (xy 19.760946 -9.946386) (xy 19.760946 -10.014966) (xy 19.712686 -10.063226)
				(arc
					(start 19.646138 -10.129774)
					(mid 19.219794 -10.439278)
					(end 19.529298 -10.012934)
				)
				(xy 19.595846 -9.946386) (xy 19.595846 -9.867138)
			)
		)
	)
	(zone
		(layer "F.Cu")
		(hatch none 0.5)
		(connect_pads
			(clearance 0)
		)
		(min_thickness 0.25)
		(keepout
			(tracks allowed)
			(vias allowed)
			(pads allowed)
			(copperpour allowed)
			(footprints allowed)
		)
		(placement
			(enabled no)
			(sheetname "")
		)
		(fill
			(thermal_gap 0.5)
			(thermal_bridge_width 0.5)
			(island_removal_mode 0)
		)
		(polygon
			(pts
				(xy 141.859 -24.2062) (xy 141.859 -23.6728) (xy 142.6464 -23.6728) (xy 142.6464 -24.2062)
			)
		)
	)
	(zone
		(net "GND")
		(layer "F.Cu")
		(hatch none 0.5)
		(connect_pads
			(clearance 0.5)
		)
		(min_thickness 0.25)
		(fill yes
			(thermal_gap 0.5)
			(thermal_bridge_width 0.5)
			(island_removal_mode 0)
		)
		(polygon
			(pts
				(xy 100.3808 -44.3738) (xy 99.8982 -44.8564) (xy 99.06 -44.8564) (xy 98.7806 -44.577) (xy 98.5012 -44.577)
				(xy 98.3488 -44.7294) (xy 98.044 -44.7294) (xy 97.8154 -44.5008) (xy 96.9264 -44.5008) (xy 96.8502 -44.577)
				(xy 96.8502 -44.7548) (xy 97.0026 -44.9072) (xy 97.2312 -44.9072) (xy 97.4344 -45.1104) (xy 98.2472 -45.1104)
				(xy 98.5012 -45.3644) (xy 100.1776 -45.3644) (xy 100.4316 -45.6184) (xy 100.711 -45.6184) (xy 101.2698 -45.0596)
				(xy 101.2698 -44.5262) (xy 101.1174 -44.3738)
			)
		)
	)
	(zone
		(net "GND")
		(layer "F.Cu")
		(hatch none 0.5)
		(connect_pads
			(clearance 0.5)
		)
		(min_thickness 0.25)
		(fill yes
			(thermal_gap 0.5)
			(thermal_bridge_width 0.5)
			(island_removal_mode 0)
		)
		(polygon
			(pts
				(xy 30.353 -55.499) (xy 29.21 -56.642) (xy 29.21 -60.833) (xy 28.702 -61.341) (xy 26.797 -61.341)
				(xy 26.67 -61.468) (xy 26.67 -62.484) (xy 27.051 -62.865) (xy 29.972 -62.865) (xy 31.369 -61.468)
				(xy 31.369 -56.134) (xy 31.242 -56.007) (xy 31.242 -55.626) (xy 31.115 -55.499)
			)
		)
		(polygon
			(pts
				(xy 30.353 -56.1721) (xy 30.099 -56.1721) (xy 30.099 -56.4261) (xy 30.353 -56.4261)
			)
		)
	)
	(zone
		(layer "F.Cu")
		(hatch none 0.5)
		(connect_pads
			(clearance 0)
		)
		(min_thickness 0.25)
		(keepout
			(tracks allowed)
			(vias allowed)
			(pads allowed)
			(copperpour allowed)
			(footprints allowed)
		)
		(placement
			(enabled no)
			(sheetname "")
		)
		(fill
			(thermal_gap 0.5)
			(thermal_bridge_width 0.5)
			(island_removal_mode 0)
		)
		(polygon
			(pts
				(xy 139.3444 -46.99) (xy 136.5758 -46.99) (xy 136.5758 -44.704) (xy 139.3444 -44.704)
			)
		)
	)
	(zone
		(layer "F.Cu")
		(hatch none 0.5)
		(connect_pads
			(clearance 0)
		)
		(min_thickness 0.25)
		(keepout
			(tracks allowed)
			(vias allowed)
			(pads allowed)
			(copperpour allowed)
			(footprints allowed)
		)
		(placement
			(enabled no)
			(sheetname "")
		)
		(fill
			(thermal_gap 0.5)
			(thermal_bridge_width 0.5)
			(island_removal_mode 0)
		)
		(polygon
			(pts
				(xy 16.891 -63.754) (xy 16.891 -52.959) (xy 25.781 -52.959) (xy 26.289 -53.467) (xy 26.289 -63.246)
				(xy 25.781 -63.754)
			)
		)
	)
	(zone
		(net "GND")
		(layer "F.Cu")
		(hatch none 0.5)
		(connect_pads
			(clearance 0.5)
		)
		(min_thickness 0.25)
		(fill yes
			(thermal_gap 0.5)
			(thermal_bridge_width 0.5)
			(island_removal_mode 0)
		)
		(polygon
			(pts
				(xy 196.469 -24.638) (xy 195.326 -25.781) (xy 195.326 -28.448) (xy 193.929 -29.845) (xy 193.929 -31.369)
				(xy 194.056 -31.496) (xy 198.247 -31.496) (xy 199.136 -32.385) (xy 200.279 -32.385) (xy 200.533 -32.131)
				(xy 200.533 -28.194) (xy 199.898 -27.559) (xy 199.898 -24.765) (xy 199.771 -24.638)
			)
		)
		(polygon
			(pts
				(xy 195.072 -30.7848) (xy 194.818 -30.7848) (xy 194.818 -31.0388) (xy 195.072 -31.0388)
			)
		)
		(polygon
			(pts
				(xy 194.564 -30.7848) (xy 194.31 -30.7848) (xy 194.31 -31.0388) (xy 194.564 -31.0388)
			)
		)
	)
	(zone
		(net "P1V0")
		(layer "F.Cu")
		(hatch none 0.5)
		(connect_pads
			(clearance 0.5)
		)
		(min_thickness 0.25)
		(fill yes
			(thermal_gap 0.5)
			(thermal_bridge_width 0.5)
			(island_removal_mode 0)
		)
		(polygon
			(pts
				(xy 22.225 -25.273) (xy 21.717 -25.781) (xy 21.717 -31.242) (xy 22.606 -32.131) (xy 29.591 -32.131)
				(xy 29.845 -31.877) (xy 29.845 -30.226) (xy 30.226 -29.845) (xy 31.877 -29.845) (xy 32.131 -29.591)
				(xy 32.131 -25.908) (xy 31.75 -25.527) (xy 23.495 -25.527) (xy 23.241 -25.273)
			)
		)
		(polygon
			(pts
				(xy 28.702 -31.2039) (xy 28.067 -31.2039) (xy 28.067 -31.4579) (xy 28.702 -31.4579)
			)
		)
		(polygon
			(pts
				(xy 27.305 -31.2039) (xy 26.67 -31.2039) (xy 26.67 -31.4579) (xy 27.305 -31.4579)
			)
		)
		(polygon
			(pts
				(xy 25.908 -31.2039) (xy 25.654 -31.2039) (xy 25.654 -31.4579) (xy 25.908 -31.4579)
			)
		)
	)
	(zone
		(layer "F.Cu")
		(hatch none 0.5)
		(connect_pads
			(clearance 0)
		)
		(min_thickness 0.25)
		(keepout
			(tracks not_allowed)
			(vias allowed)
			(pads allowed)
			(copperpour not_allowed)
			(footprints allowed)
		)
		(placement
			(enabled no)
			(sheetname "")
		)
		(fill
			(thermal_gap 0.5)
			(thermal_bridge_width 0.5)
			(island_removal_mode 0)
		)
		(polygon
			(pts
				(xy 91.210384 -54.656482) (xy 91.045284 -54.760622) (xy 91.17203 -54.887114)
				(arc
					(start 91.176348 -54.887114)
					(mid 91.62476 -54.950614)
					(end 91.176348 -55.014114)
				)
				(xy 91.17203 -55.014114) (xy 91.119198 -55.014114) (xy 91.082114 -54.97703) (xy 90.935302 -54.829964)
				(xy 90.869008 -54.871874) (xy 90.94978 -54.952392) (xy 90.986864 -54.989476)
				(arc
					(start 90.986864 -55.029354)
					(mid 90.928425 -55.47771)
					(end 90.850212 -55.032402)
				)
				(xy 90.759026 -54.941216) (xy 90.73769 -54.954678) (xy 90.73769 -54.954932)
				(arc
					(start 90.73896 -54.956964)
					(mid 90.631264 -55.433468)
					(end 91.107768 -55.541164)
				)
				(xy 91.109038 -55.543196) (xy 91.581732 -55.244746)
				(arc
					(start 91.580462 -55.242714)
					(mid 91.688158 -54.76621)
					(end 91.211654 -54.658514)
				)
			)
		)
	)
	(zone
		(layer "F.Cu")
		(hatch none 0.5)
		(connect_pads
			(clearance 0)
		)
		(min_thickness 0.25)
		(keepout
			(tracks not_allowed)
			(vias allowed)
			(pads allowed)
			(copperpour not_allowed)
			(footprints allowed)
		)
		(placement
			(enabled no)
			(sheetname "")
		)
		(fill
			(thermal_gap 0.5)
			(thermal_bridge_width 0.5)
			(island_removal_mode 0)
		)
		(polygon
			(pts
				(arc
					(start 47.408592 -9.867138)
					(mid 47.024798 -10.250551)
					(end 47.408338 -10.634218)
				)
				(arc
					(start 48.327818 -10.634218)
					(mid 48.711358 -10.250678)
					(end 48.327818 -9.867138)
				)
				(xy 48.104044 -9.867138) (xy 48.104044 -9.910064)
				(arc
					(start 48.206914 -10.012934)
					(mid 48.516418 -10.439278)
					(end 48.090074 -10.129774)
				)
				(xy 47.987204 -10.026904) (xy 47.938944 -9.978644) (xy 47.938944 -9.910064) (xy 47.938944 -9.867138)
				(xy 47.761144 -9.867138) (xy 47.761144 -9.946132) (xy 47.761144 -10.014712) (xy 47.712884 -10.062972)
				(arc
					(start 47.646082 -10.129774)
					(mid 47.219738 -10.439278)
					(end 47.529242 -10.012934)
				)
				(xy 47.596044 -9.946132) (xy 47.596044 -9.867138)
			)
		)
	)
	(zone
		(net "GND")
		(layer "F.Cu")
		(hatch none 0.5)
		(connect_pads
			(clearance 0.5)
		)
		(min_thickness 0.25)
		(fill yes
			(thermal_gap 0.5)
			(thermal_bridge_width 0.5)
			(island_removal_mode 0)
		)
		(polygon
			(pts
				(xy 57.404 -64.008) (xy 57.15 -64.262) (xy 57.15 -67.691) (xy 56.515 -68.326) (xy 43.307 -68.326)
				(xy 42.799 -68.834) (xy 42.799 -72.771) (xy 43.053 -73.025) (xy 61.341 -73.025) (xy 63.5 -70.866)
				(xy 63.5 -67.564) (xy 64.262 -66.802) (xy 65.659 -66.802) (xy 66.548 -65.913) (xy 66.548 -64.262)
				(xy 66.294 -64.008)
			)
		)
	)
	(zone
		(layer "F.Cu")
		(hatch none 0.5)
		(connect_pads
			(clearance 0)
		)
		(min_thickness 0.25)
		(keepout
			(tracks allowed)
			(vias allowed)
			(pads allowed)
			(copperpour allowed)
			(footprints allowed)
		)
		(placement
			(enabled no)
			(sheetname "")
		)
		(fill
			(thermal_gap 0.5)
			(thermal_bridge_width 0.5)
			(island_removal_mode 0)
		)
		(polygon
			(pts
				(xy 62.103 -46.863) (xy 62.103 -44.831) (xy 65.024 -44.831) (xy 65.024 -46.863)
			)
		)
	)
	(zone
		(net "GND")
		(layer "F.Cu")
		(hatch none 0.5)
		(connect_pads
			(clearance 0.5)
		)
		(min_thickness 0.25)
		(fill yes
			(thermal_gap 0.5)
			(thermal_bridge_width 0.5)
			(island_removal_mode 0)
		)
		(polygon
			(pts
				(xy 24.257 -21.59) (xy 23.876 -21.971) (xy 23.876 -24.892) (xy 24.13 -25.146) (xy 29.464 -25.146)
				(xy 29.718 -24.892) (xy 29.718 -21.844) (xy 29.464 -21.59)
			)
		)
	)
	(zone
		(net "P1V35")
		(layer "F.Cu")
		(hatch none 0.5)
		(connect_pads
			(clearance 0.5)
		)
		(min_thickness 0.25)
		(fill yes
			(thermal_gap 0.5)
			(thermal_bridge_width 0.5)
			(island_removal_mode 0)
		)
		(polygon
			(pts
				(xy 95.25 -34.163) (xy 94.742 -34.671) (xy 94.742 -34.925) (xy 94.996 -35.179) (xy 94.996 -35.306)
				(xy 94.869 -35.433) (xy 94.869 -35.687) (xy 95.377 -36.195) (xy 96.393 -36.195) (xy 96.52 -36.068)
				(xy 96.52 -35.941) (xy 95.631 -35.052) (xy 95.631 -34.29) (xy 95.504 -34.163)
			)
		)
	)
	(zone
		(net "P1V0")
		(layer "F.Cu")
		(hatch none 0.5)
		(connect_pads
			(clearance 0.5)
		)
		(min_thickness 0.25)
		(fill yes
			(thermal_gap 0.5)
			(thermal_bridge_width 0.5)
			(island_removal_mode 0)
		)
		(polygon
			(pts
				(xy 92.202 -30.099) (xy 92.075 -30.226) (xy 92.075 -30.48) (xy 91.821 -30.734) (xy 91.186 -30.734)
				(xy 90.678 -31.242) (xy 90.678 -32.385) (xy 90.551 -32.512) (xy 89.789 -32.512) (xy 89.408 -32.893)
				(xy 89.408 -34.036) (xy 89.154 -34.29) (xy 89.154 -34.925) (xy 89.662 -35.433) (xy 90.805 -35.433)
				(xy 90.932 -35.306) (xy 90.932 -35.179) (xy 90.297 -34.544) (xy 90.297 -34.163) (xy 90.551 -33.909)
				(xy 90.678 -33.909) (xy 91.821 -32.766) (xy 92.202 -32.766) (xy 92.329 -32.893) (xy 92.456 -32.893)
				(xy 92.583 -32.766) (xy 92.583 -30.226) (xy 92.456 -30.099)
			)
		)
	)
	(zone
		(net "P1V0_STBY")
		(layer "F.Cu")
		(hatch none 0.5)
		(connect_pads
			(clearance 0.5)
		)
		(min_thickness 0.25)
		(fill yes
			(thermal_gap 0.5)
			(thermal_bridge_width 0.5)
			(island_removal_mode 0)
		)
		(polygon
			(pts
				(xy 92.71 -33.528) (xy 91.948 -34.29) (xy 91.948 -35.179) (xy 92.329 -35.56) (xy 92.329 -35.687)
				(xy 91.694 -36.322) (xy 90.805 -36.322) (xy 90.424 -36.703) (xy 90.424 -36.957) (xy 90.551 -37.084)
				(xy 92.329 -37.084) (xy 92.583 -36.83) (xy 92.837 -36.83) (xy 92.964 -36.957) (xy 93.218 -36.957)
				(xy 93.345 -36.83) (xy 93.599 -36.83) (xy 93.726 -36.957) (xy 93.98 -36.957) (xy 94.107 -36.83)
				(xy 94.107 -35.179) (xy 93.853 -34.925) (xy 93.853 -34.671) (xy 94.107 -34.417) (xy 94.107 -33.655)
				(xy 93.98 -33.528)
			)
		)
	)
	(zone
		(layer "F.Cu")
		(hatch none 0.5)
		(connect_pads
			(clearance 0)
		)
		(min_thickness 0.25)
		(keepout
			(tracks allowed)
			(vias allowed)
			(pads allowed)
			(copperpour allowed)
			(footprints not_allowed)
		)
		(placement
			(enabled no)
			(sheetname "")
		)
		(fill
			(thermal_gap 0.5)
			(thermal_bridge_width 0.5)
			(island_removal_mode 0)
		)
		(polygon
			(pts
				(arc
					(start 8.770112 -19.60499)
					(mid 11.60018 -16.774922)
					(end 14.429994 -19.60499)
				)
				(arc
					(start 14.429994 -19.60499)
					(mid 11.60018 -22.434804)
					(end 8.770112 -19.60499)
				)
			)
		)
	)
	(zone
		(layer "F.Cu")
		(hatch none 0.5)
		(connect_pads
			(clearance 0)
		)
		(min_thickness 0.25)
		(keepout
			(tracks allowed)
			(vias allowed)
			(pads allowed)
			(copperpour allowed)
			(footprints allowed)
		)
		(placement
			(enabled no)
			(sheetname "")
		)
		(fill
			(thermal_gap 0.5)
			(thermal_bridge_width 0.5)
			(island_removal_mode 0)
		)
		(polygon
			(pts
				(xy 61.722 -42.926) (xy 61.722 -41.021) (xy 64.897 -41.021) (xy 64.897 -42.926)
			)
		)
	)
	(zone
		(net "PVNN")
		(layer "F.Cu")
		(hatch none 0.5)
		(connect_pads
			(clearance 0.5)
		)
		(min_thickness 0.25)
		(fill yes
			(thermal_gap 0.5)
			(thermal_bridge_width 0.5)
			(island_removal_mode 0)
		)
		(polygon
			(pts
				(xy 42.799 -63.5) (xy 42.672 -63.627) (xy 42.672 -67.564) (xy 43.053 -67.945) (xy 56.261 -67.945)
				(xy 56.642 -67.564) (xy 56.642 -64.135) (xy 56.261 -63.754) (xy 55.118 -63.754) (xy 53.594 -65.278)
				(xy 45.974 -65.278) (xy 45.72 -65.024) (xy 45.72 -64.389) (xy 44.831 -63.5)
			)
		)
		(polygon
			(pts
				(xy 51.054 -65.9511) (xy 50.8 -65.9511) (xy 50.8 -66.2051) (xy 51.054 -66.2051)
			)
		)
		(polygon
			(pts
				(xy 50.038 -65.9511) (xy 49.784 -65.9511) (xy 49.784 -66.2051) (xy 50.038 -66.2051)
			)
		)
	)
	(zone
		(layer "F.Cu")
		(hatch none 0.5)
		(connect_pads
			(clearance 0)
		)
		(min_thickness 0.25)
		(keepout
			(tracks allowed)
			(vias allowed)
			(pads allowed)
			(copperpour allowed)
			(footprints allowed)
		)
		(placement
			(enabled no)
			(sheetname "")
		)
		(fill
			(thermal_gap 0.5)
			(thermal_bridge_width 0.5)
			(island_removal_mode 0)
		)
		(polygon
			(pts
				(xy 14.224 -22.479) (xy 18.923 -22.479) (xy 18.923 -27.559) (xy 16.256 -27.559) (xy 16.256 -28.575)
				(xy 15.748 -29.083) (xy 11.303 -29.083) (xy 10.414 -29.083) (xy 9.779 -28.448) (xy 9.779 -22.733)
				(xy 10.033 -22.479) (xy 11.176 -22.479)
			)
		)
	)
	(zone
		(net "P12V")
		(layer "F.Cu")
		(hatch none 0.5)
		(connect_pads
			(clearance 0.5)
		)
		(min_thickness 0.25)
		(fill yes
			(thermal_gap 0.5)
			(thermal_bridge_width 0.5)
			(island_removal_mode 0)
		)
		(polygon
			(pts
				(xy 200.406 -18.923) (xy 200.025 -19.304) (xy 200.025 -22.479) (xy 200.152 -22.606) (xy 202.946 -22.606)
				(xy 203.073 -22.479) (xy 203.073 -19.177) (xy 202.819 -18.923)
			)
		)
	)
	(zone
		(net "P3V3_STBY_OUT")
		(layer "F.Cu")
		(hatch none 0.5)
		(connect_pads
			(clearance 0.5)
		)
		(min_thickness 0.25)
		(fill yes
			(thermal_gap 0.5)
			(thermal_bridge_width 0.5)
			(island_removal_mode 0)
		)
		(polygon
			(pts
				(xy 20.828 -34.925) (xy 20.701 -35.052) (xy 20.701 -36.957) (xy 20.193 -37.465) (xy 20.193 -42.545)
				(xy 20.828 -43.18) (xy 28.194 -43.18) (xy 28.321 -43.053) (xy 28.321 -41.148) (xy 27.94 -40.767)
				(xy 27.94 -36.957) (xy 27.813 -36.83) (xy 27.178 -36.83) (xy 26.924 -37.084) (xy 22.225 -37.084)
				(xy 21.209 -36.068) (xy 21.209 -35.052) (xy 21.082 -34.925)
			)
		)
		(polygon
			(pts
				(xy 24.892 -42.5704) (xy 24.638 -42.5704) (xy 24.638 -42.8244) (xy 24.892 -42.8244)
			)
		)
		(polygon
			(pts
				(xy 24.384 -42.5704) (xy 24.13 -42.5704) (xy 24.13 -42.8244) (xy 24.384 -42.8244)
			)
		)
		(polygon
			(pts
				(xy 24.003 -42.1259) (xy 23.749 -42.1259) (xy 23.749 -42.3799) (xy 24.003 -42.3799)
			)
		)
		(polygon
			(pts
				(xy 22.987 -42.1259) (xy 22.733 -42.1259) (xy 22.733 -42.3799) (xy 22.987 -42.3799)
			)
		)
		(polygon
			(pts
				(xy 27.1907 -37.5031) (xy 26.9367 -37.5031) (xy 26.9367 -37.7571) (xy 27.1907 -37.7571)
			)
		)
	)
	(zone
		(layer "F.Cu")
		(hatch none 0.5)
		(connect_pads
			(clearance 0)
		)
		(min_thickness 0.25)
		(keepout
			(tracks allowed)
			(vias allowed)
			(pads allowed)
			(copperpour allowed)
			(footprints allowed)
		)
		(placement
			(enabled no)
			(sheetname "")
		)
		(fill
			(thermal_gap 0.5)
			(thermal_bridge_width 0.5)
			(island_removal_mode 0)
		)
		(polygon
			(pts
				(xy 133.1976 -24.8666) (xy 133.1976 -21.971) (xy 139.065 -21.971) (xy 139.065 -24.8666)
			)
		)
	)
	(zone
		(layer "F.Cu")
		(hatch none 0.5)
		(connect_pads
			(clearance 0)
		)
		(min_thickness 0.25)
		(keepout
			(tracks allowed)
			(vias allowed)
			(pads allowed)
			(copperpour allowed)
			(footprints not_allowed)
		)
		(placement
			(enabled no)
			(sheetname "")
		)
		(fill
			(thermal_gap 0.5)
			(thermal_bridge_width 0.5)
			(island_removal_mode 0)
		)
		(polygon
			(pts
				(arc
					(start 0 -72.799956)
					(mid 0.292893 -73.507061)
					(end 0.999998 -73.799954)
				)
				(xy 99.000056 -73.799954) (xy 99.000056 -69.600064) (xy 77.659992 -69.600064) (xy 77.659992 -64.630046)
				(xy 68.039996 -64.630046) (xy 68.039996 -69.600064)
				(arc
					(start 52.889658 -69.600064)
					(mid 50.850038 -68.800027)
					(end 48.810418 -69.600064)
				)
				(xy 13.5001 -69.600064) (xy 13.5001 -65.79997) (xy 5.80009 -65.79997) (xy 5.80009 -58.999882) (xy 3.999992 -58.999882)
				(xy 3.999992 -14.699996)
				(arc
					(start 0.999998 -14.699996)
					(mid 0.292893 -14.992889)
					(end 0 -15.699994)
				)
			)
		)
	)
	(zone
		(net "GND")
		(layer "F.Cu")
		(hatch none 0.5)
		(connect_pads
			(clearance 0.5)
		)
		(min_thickness 0.25)
		(fill yes
			(thermal_gap 0.5)
			(thermal_bridge_width 0.5)
			(island_removal_mode 0)
		)
		(polygon
			(pts
				(xy 78.232 -48.895) (xy 77.978 -49.149) (xy 77.978 -50.546) (xy 78.613 -51.181) (xy 78.613 -51.943)
				(xy 77.851 -52.705) (xy 73.279 -52.705) (xy 72.39 -53.594) (xy 71.501 -53.594) (xy 71.247 -53.848)
				(xy 71.247 -54.483) (xy 71.501 -54.737) (xy 72.009 -54.737) (xy 72.263 -54.483) (xy 73.025 -54.483)
				(xy 74.041 -53.467) (xy 74.8284 -53.467) (xy 77.1144 -55.753) (xy 79.756 -55.753) (xy 80.772 -56.769)
				(xy 82.804 -56.769) (xy 82.931 -56.642) (xy 82.931 -56.261) (xy 81.407 -54.737) (xy 81.026 -54.737)
				(xy 80.772 -54.991) (xy 80.391 -54.991) (xy 80.264 -54.864) (xy 80.264 -53.975) (xy 80.391 -53.848)
				(xy 80.645 -53.848) (xy 80.899 -54.102) (xy 81.28 -54.102) (xy 81.407 -53.975) (xy 81.407 -52.959)
				(xy 83.439 -52.959) (xy 83.82 -52.578) (xy 83.82 -52.324) (xy 83.693 -52.197) (xy 82.804 -52.197)
				(xy 82.423 -51.816) (xy 82.423 -51.435) (xy 82.296 -51.308) (xy 81.407 -51.308) (xy 80.01 -49.911)
				(xy 80.01 -49.022) (xy 79.883 -48.895)
			)
		)
	)
	(zone
		(layer "F.Cu")
		(hatch none 0.5)
		(connect_pads
			(clearance 0)
		)
		(min_thickness 0.25)
		(keepout
			(tracks allowed)
			(vias allowed)
			(pads allowed)
			(copperpour allowed)
			(footprints not_allowed)
		)
		(placement
			(enabled no)
			(sheetname "")
		)
		(fill
			(thermal_gap 0.5)
			(thermal_bridge_width 0.5)
			(island_removal_mode 0)
		)
		(polygon
			(pts
				(xy 134.249922 -47.649892) (xy 134.249922 -51.660044) (xy 139.809982 -51.660044) (xy 139.809982 -47.649892)
			)
		)
	)
	(zone
		(net "P1V0")
		(layer "F.Cu")
		(hatch none 0.5)
		(connect_pads
			(clearance 0.5)
		)
		(min_thickness 0.25)
		(fill yes
			(thermal_gap 0.5)
			(thermal_bridge_width 0.5)
			(island_removal_mode 0)
		)
		(polygon
			(pts
				(xy 93.853 -42.926) (xy 93.599 -43.18) (xy 93.218 -43.18) (xy 93.091 -43.053) (xy 92.837 -43.053)
				(xy 92.329 -43.561) (xy 92.075 -43.561) (xy 91.567 -43.053) (xy 91.313 -43.053) (xy 91.186 -43.18)
				(xy 91.186 -43.307) (xy 91.821 -43.942) (xy 91.821 -44.958) (xy 92.075 -45.212) (xy 93.091 -45.212)
				(xy 93.218 -45.085) (xy 93.472 -45.085) (xy 93.599 -45.212) (xy 93.599 -45.847) (xy 94.107 -46.355)
				(xy 94.615 -46.355) (xy 94.869 -46.101) (xy 94.869 -43.053) (xy 94.742 -42.926)
			)
		)
	)
	(zone
		(net "P1V5_STBY_IN")
		(layer "F.Cu")
		(hatch none 0.5)
		(connect_pads
			(clearance 0.5)
		)
		(min_thickness 0.25)
		(fill yes
			(thermal_gap 0.5)
			(thermal_bridge_width 0.5)
			(island_removal_mode 0)
		)
		(polygon
			(pts
				(xy 28.321 -49.149) (xy 27.94 -49.53) (xy 27.94 -50.927) (xy 27.178 -51.689) (xy 27.178 -52.07)
				(xy 27.432 -52.324) (xy 28.321 -52.324) (xy 28.575 -52.578) (xy 29.591 -52.578) (xy 29.718 -52.451)
				(xy 29.718 -49.403) (xy 29.464 -49.149)
			)
		)
	)
	(zone
		(layer "F.Cu")
		(hatch none 0.5)
		(connect_pads
			(clearance 0)
		)
		(min_thickness 0.25)
		(keepout
			(tracks not_allowed)
			(vias allowed)
			(pads allowed)
			(copperpour not_allowed)
			(footprints allowed)
		)
		(placement
			(enabled no)
			(sheetname "")
		)
		(fill
			(thermal_gap 0.5)
			(thermal_bridge_width 0.5)
			(island_removal_mode 0)
		)
		(polygon
			(pts
				(arc
					(start 10.01014 -57.404254)
					(mid 9.668238 -57.022472)
					(end 9.25195 -57.32145)
				)
				(arc
					(start 9.373108 -57.32145)
					(mid 9.893195 -57.404)
					(end 9.373108 -57.48655)
				)
				(xy 9.24306 -57.48655) (xy 9.24306 -58.21045)
				(arc
					(start 9.373108 -58.21045)
					(mid 9.893195 -58.293)
					(end 9.373108 -58.37555)
				)
				(arc
					(start 9.25195 -58.37555)
					(mid 9.668119 -58.674383)
					(end 10.01014 -58.293)
				)
			)
		)
	)
	(zone
		(layer "F.Cu")
		(hatch none 0.5)
		(connect_pads
			(clearance 0)
		)
		(min_thickness 0.25)
		(keepout
			(tracks not_allowed)
			(vias allowed)
			(pads allowed)
			(copperpour not_allowed)
			(footprints allowed)
		)
		(placement
			(enabled no)
			(sheetname "")
		)
		(fill
			(thermal_gap 0.5)
			(thermal_bridge_width 0.5)
			(island_removal_mode 0)
		)
		(polygon
			(pts
				(arc
					(start 31.40837 -9.867138)
					(mid 31.02483 -10.250678)
					(end 31.40837 -10.634218)
				)
				(arc
					(start 32.327596 -10.634218)
					(mid 32.71139 -10.250805)
					(end 32.32785 -9.867138)
				)
				(xy 32.104076 -9.867138) (xy 32.104076 -9.910064)
				(arc
					(start 32.206946 -10.012934)
					(mid 32.51645 -10.439278)
					(end 32.090106 -10.129774)
				)
				(xy 31.987236 -10.026904) (xy 31.938976 -9.978644) (xy 31.938976 -9.910064) (xy 31.938976 -9.867138)
				(xy 31.761176 -9.867138) (xy 31.761176 -9.946132) (xy 31.761176 -10.014712) (xy 31.712916 -10.062972)
				(arc
					(start 31.646114 -10.129774)
					(mid 31.21977 -10.439278)
					(end 31.529274 -10.012934)
				)
				(xy 31.596076 -9.946132) (xy 31.596076 -9.867138)
			)
		)
	)
	(zone
		(layer "F.Cu")
		(hatch none 0.5)
		(connect_pads
			(clearance 0)
		)
		(min_thickness 0.25)
		(keepout
			(tracks allowed)
			(vias allowed)
			(pads allowed)
			(copperpour allowed)
			(footprints allowed)
		)
		(placement
			(enabled no)
			(sheetname "")
		)
		(fill
			(thermal_gap 0.5)
			(thermal_bridge_width 0.5)
			(island_removal_mode 0)
		)
		(polygon
			(pts
				(xy 39.9034 -33.6296) (xy 39.9034 -19.2786) (xy 43.18 -19.2786) (xy 43.18 -33.6296)
			)
		)
	)
	(zone
		(net "PV_VTT_DDR_A")
		(layer "F.Cu")
		(hatch none 0.5)
		(connect_pads
			(clearance 0.5)
		)
		(min_thickness 0.25)
		(fill yes
			(thermal_gap 0.5)
			(thermal_bridge_width 0.5)
			(island_removal_mode 0)
		)
		(polygon
			(pts
				(xy 120.523 -61.595) (xy 120.142 -61.976) (xy 120.142 -65.151) (xy 120.396 -65.405) (xy 125.349 -65.405)
				(xy 126.0475 -66.1035) (xy 126.0475 -70.8025) (xy 126.873 -71.628) (xy 127.254 -71.628) (xy 127.381 -71.501)
				(xy 127.381 -63.881) (xy 127.127 -63.627) (xy 127.127 -61.722) (xy 127 -61.595)
			)
		)
		(polygon
			(pts
				(xy 120.9929 -63.754) (xy 120.7389 -63.754) (xy 120.7389 -64.262) (xy 120.9929 -64.262)
			)
		)
		(polygon
			(pts
				(xy 120.8024 -62.484) (xy 120.5484 -62.484) (xy 120.5484 -62.738) (xy 120.7389 -62.992) (xy 120.9929 -62.992)
				(xy 120.9929 -62.738)
			)
		)
		(polygon
			(pts
				(xy 120.8024 -61.976) (xy 120.5484 -61.976) (xy 120.5484 -62.23) (xy 120.8024 -62.23)
			)
		)
	)
	(zone
		(net "P1V0")
		(layer "F.Cu")
		(hatch none 0.5)
		(connect_pads
			(clearance 0.5)
		)
		(min_thickness 0.25)
		(fill yes
			(thermal_gap 0.5)
			(thermal_bridge_width 0.5)
			(island_removal_mode 0)
		)
		(polygon
			(pts
				(xy 99.695 -33.798002) (xy 99.187 -34.306002) (xy 99.187 -34.560002) (xy 99.314 -34.687002) (xy 99.314 -35.068002)
				(xy 99.187 -35.195002) (xy 99.187 -35.322002) (xy 99.314 -35.449002) (xy 99.441 -35.449002) (xy 99.568 -35.322002)
				(xy 100.076 -35.322002) (xy 100.584 -35.830002) (xy 100.711 -35.830002) (xy 100.838 -35.703002)
				(xy 101.219 -35.703002) (xy 101.727 -36.211002) (xy 101.981 -36.211002) (xy 102.489 -35.703002)
				(xy 102.489 -34.814002) (xy 102.743 -34.560002) (xy 102.743 -34.306002) (xy 102.616 -34.179002)
				(xy 101.854 -34.179002) (xy 101.727 -34.306002) (xy 101.219 -34.306002) (xy 100.711 -33.798002)
			)
		)
	)
	(zone
		(layer "F.Cu")
		(hatch none 0.5)
		(connect_pads
			(clearance 0)
		)
		(min_thickness 0.25)
		(keepout
			(tracks not_allowed)
			(vias allowed)
			(pads allowed)
			(copperpour not_allowed)
			(footprints allowed)
		)
		(placement
			(enabled no)
			(sheetname "")
		)
		(fill
			(thermal_gap 0.5)
			(thermal_bridge_width 0.5)
			(island_removal_mode 0)
		)
		(polygon
			(pts
				(xy 63.70955 -14.3256)
				(arc
					(start 63.70955 -14.453108)
					(mid 63.627 -14.973195)
					(end 63.54445 -14.453108)
				)
				(arc
					(start 63.54445 -14.334744)
					(mid 63.248361 -14.748122)
					(end 63.627 -15.0876)
				)
				(arc
					(start 64.389 -15.0876)
					(mid 64.76773 -14.748132)
					(end 64.47155 -14.334744)
				)
				(arc
					(start 64.47155 -14.453108)
					(mid 64.389 -14.973195)
					(end 64.30645 -14.453108)
				)
				(xy 64.30645 -14.3256)
			)
		)
	)
	(zone
		(net "PVNN")
		(layer "F.Cu")
		(hatch none 0.5)
		(connect_pads
			(clearance 0.5)
		)
		(min_thickness 0.25)
		(fill yes
			(thermal_gap 0.5)
			(thermal_bridge_width 0.5)
			(island_removal_mode 0)
		)
		(polygon
			(pts
				(xy 93.345 -37.084) (xy 92.583 -37.846) (xy 92.583 -39.878) (xy 92.964 -40.259) (xy 92.964 -40.64)
				(xy 92.456 -41.148) (xy 91.694 -41.148) (xy 91.313 -41.529) (xy 91.313 -41.656) (xy 91.694 -42.037)
				(xy 92.456 -42.037) (xy 92.583 -42.164) (xy 92.837 -42.164) (xy 92.964 -42.037) (xy 93.218 -42.037)
				(xy 93.345 -42.164) (xy 93.599 -42.164) (xy 93.726 -42.037) (xy 96.393 -42.037) (xy 96.52 -42.164)
				(xy 96.774 -42.164) (xy 96.901 -42.037) (xy 97.155 -42.037) (xy 97.282 -42.164) (xy 97.663 -42.164)
				(xy 97.79 -42.037) (xy 98.806 -42.037) (xy 98.933 -42.164) (xy 99.187 -42.164) (xy 99.314 -42.037)
				(xy 99.568 -42.037) (xy 99.695 -42.164) (xy 99.949 -42.164) (xy 100.457 -41.656) (xy 100.457 -41.529)
				(xy 100.33 -41.402) (xy 98.552 -41.402) (xy 98.425 -41.529) (xy 98.044 -41.529) (xy 97.917 -41.402)
				(xy 97.79 -41.402) (xy 97.663 -41.529) (xy 97.282 -41.529) (xy 97.155 -41.402) (xy 96.901 -41.402)
				(xy 96.774 -41.529) (xy 96.52 -41.529) (xy 96.139 -41.148) (xy 95.377 -41.148) (xy 94.742 -40.513)
				(xy 94.742 -40.259) (xy 94.869 -40.132) (xy 94.869 -38.227) (xy 94.742 -38.1) (xy 94.742 -37.846)
				(xy 94.869 -37.719) (xy 94.869 -37.211) (xy 94.742 -37.084)
			)
		)
	)
	(zone
		(net "GND")
		(layer "F.Cu")
		(hatch none 0.5)
		(connect_pads
			(clearance 0.5)
		)
		(min_thickness 0.25)
		(fill yes
			(thermal_gap 0.5)
			(thermal_bridge_width 0.5)
			(island_removal_mode 0)
		)
		(polygon
			(pts
				(xy 34.671 -41.783) (xy 34.163 -42.291) (xy 34.163 -46.482) (xy 35.6616 -47.9806) (xy 39.624 -47.9806)
				(xy 39.7002 -47.9044) (xy 39.7002 -46.609) (xy 39.37 -46.2788) (xy 37.6428 -46.2788) (xy 37.4904 -46.1264)
				(xy 37.4904 -44.7548) (xy 37.6936 -44.5516) (xy 39.5224 -44.5516) (xy 39.8272 -44.2468) (xy 40.2082 -44.2468)
				(xy 40.386 -44.069) (xy 40.386 -42.926) (xy 40.132 -42.672) (xy 39.751 -42.672) (xy 39.624 -42.799)
				(xy 39.624 -43.5356) (xy 39.2176 -43.942) (xy 38.5826 -43.942) (xy 38.354 -43.7134) (xy 38.354 -42.291)
				(xy 38.2524 -42.1894) (xy 37.8714 -42.1894) (xy 37.465 -41.783)
			)
		)
		(polygon
			(pts
				(xy 37.973 -42.6212) (xy 37.719 -42.6212) (xy 37.719 -42.8752) (xy 37.973 -42.8752)
			)
		)
	)
	(zone
		(net "P1V2_STBY_LDO_OUT2")
		(layer "F.Cu")
		(hatch none 0.5)
		(connect_pads
			(clearance 0.5)
		)
		(min_thickness 0.25)
		(fill yes
			(thermal_gap 0.5)
			(thermal_bridge_width 0.5)
			(island_removal_mode 0)
		)
		(polygon
			(pts
				(xy 176.149 -23.495) (xy 173.736 -25.908) (xy 168.148 -25.908) (xy 168.021 -26.035) (xy 168.021 -28.829)
				(xy 168.148 -28.956) (xy 168.91 -28.956) (xy 169.037 -28.829) (xy 169.037 -28.194) (xy 169.672 -27.559)
				(xy 174.498 -27.559) (xy 175.387 -28.448) (xy 177.292 -28.448) (xy 177.419 -28.321) (xy 177.419 -23.749)
				(xy 177.165 -23.495)
			)
		)
		(polygon
			(pts
				(xy 169.0751 -27.686) (xy 168.8211 -27.686) (xy 168.8211 -27.94) (xy 169.0751 -27.94)
			)
		)
	)
	(zone
		(net "GND")
		(layer "F.Cu")
		(hatch none 0.5)
		(connect_pads
			(clearance 0.5)
		)
		(min_thickness 0.25)
		(fill yes
			(thermal_gap 0.5)
			(thermal_bridge_width 0.5)
			(island_removal_mode 0)
		)
		(polygon
			(pts
				(xy 22.606 -32.639) (xy 22.352 -32.893) (xy 22.352 -36.576) (xy 22.479 -36.703) (xy 26.416 -36.703)
				(xy 26.67 -36.449) (xy 26.67 -35.56) (xy 27.051 -35.179) (xy 29.591 -35.179) (xy 30.3276 -34.4424)
				(xy 30.3276 -33.9852) (xy 30.48 -33.8328) (xy 30.8864 -33.8328) (xy 31.0896 -33.6296) (xy 31.0896 -33.274)
				(xy 30.988 -33.1724) (xy 29.8704 -33.1724) (xy 29.718 -33.02) (xy 29.718 -32.766) (xy 29.591 -32.639)
			)
		)
		(polygon
			(pts
				(xy 29.7053 -34.5948) (xy 29.4513 -34.5948) (xy 29.4513 -34.8488) (xy 29.7053 -34.8488)
			)
		)
		(polygon
			(pts
				(xy 29.1973 -34.5948) (xy 28.9433 -34.5948) (xy 28.9433 -34.8488) (xy 29.1973 -34.8488)
			)
		)
		(polygon
			(pts
				(xy 29.718 -33.3121) (xy 29.464 -33.3121) (xy 29.464 -33.5661) (xy 29.718 -33.7566) (xy 29.972 -33.7566)
				(xy 29.972 -33.5026)
			)
		)
		(polygon
			(pts
				(xy 28.702 -33.3121) (xy 28.067 -33.3121) (xy 28.067 -33.5661) (xy 28.702 -33.5661)
			)
		)
		(polygon
			(pts
				(xy 27.305 -33.3121) (xy 26.67 -33.3121) (xy 26.67 -33.5661) (xy 27.305 -33.5661)
			)
		)
		(polygon
			(pts
				(xy 25.908 -33.3121) (xy 25.654 -33.3121) (xy 25.654 -33.5661) (xy 25.908 -33.5661)
			)
		)
	)
	(zone
		(net "GND")
		(layer "F.Cu")
		(hatch none 0.5)
		(connect_pads
			(clearance 0.5)
		)
		(min_thickness 0.25)
		(fill yes
			(thermal_gap 0.5)
			(thermal_bridge_width 0.5)
			(island_removal_mode 0)
		)
		(polygon
			(pts
				(xy 59.1566 -45.3136) (xy 58.4835 -45.9867) (xy 58.4835 -46.6725) (xy 57.531 -47.625) (xy 57.531 -49.276)
				(xy 57.658 -49.403) (xy 57.658 -49.657) (xy 57.785 -49.784) (xy 57.785 -50.292) (xy 57.658 -50.419)
				(xy 57.658 -51.181) (xy 57.7342 -51.2572) (xy 58.7756 -51.2572) (xy 59.0804 -51.562) (xy 62.611 -51.562)
				(xy 62.738 -51.435) (xy 62.738 -50.673) (xy 62.611 -50.546) (xy 62.23 -50.546) (xy 61.849 -50.165)
				(xy 61.849 -49.53) (xy 61.2902 -48.9712) (xy 60.6044 -48.9712) (xy 60.2361 -48.6029) (xy 60.2361 -47.9171)
				(xy 60.198 -47.879) (xy 60.198 -47.371) (xy 60.452 -47.117) (xy 60.452 -45.5168) (xy 60.2488 -45.3136)
			)
		)
	)
	(zone
		(net "GND")
		(layer "F.Cu")
		(hatch none 0.5)
		(connect_pads
			(clearance 0.5)
		)
		(min_thickness 0.25)
		(fill yes
			(thermal_gap 0.5)
			(thermal_bridge_width 0.5)
			(island_removal_mode 0)
		)
		(polygon
			(pts
				(xy 62.865 -53.594) (xy 62.484 -53.975) (xy 61.087 -53.975) (xy 59.69 -55.372) (xy 56.769 -55.372)
				(xy 56.642 -55.499) (xy 56.642 -56.388) (xy 56.769 -56.515) (xy 65.532 -56.515) (xy 65.786 -56.261)
				(xy 65.786 -53.975) (xy 65.405 -53.594)
			)
		)
		(polygon
			(pts
				(xy 65.405 -55.4609) (xy 65.151 -55.4609) (xy 65.151 -55.7149) (xy 65.405 -55.7149)
			)
		)
		(polygon
			(pts
				(xy 64.389 -55.4609) (xy 64.135 -55.4609) (xy 64.135 -55.7149) (xy 64.389 -55.7149)
			)
		)
	)
	(zone
		(net "GND")
		(layer "F.Cu")
		(hatch none 0.5)
		(connect_pads
			(clearance 0.5)
		)
		(min_thickness 0.25)
		(fill yes
			(thermal_gap 0.5)
			(thermal_bridge_width 0.5)
			(island_removal_mode 0)
		)
		(polygon
			(pts
				(xy 20.955 -8.636) (xy 20.574 -9.017) (xy 20.574 -9.906) (xy 20.828 -10.16) (xy 20.828 -10.414)
				(xy 20.066 -11.176) (xy 20.066 -14.097) (xy 19.685 -14.478) (xy 18.034 -14.478) (xy 17.018 -15.494)
				(xy 1.27 -15.494) (xy 0.762 -16.002) (xy 0.762 -28.321) (xy 1.016 -28.575) (xy 3.683 -28.575) (xy 3.937 -28.321)
				(xy 3.937 -25.527) (xy 4.191 -25.273) (xy 5.969 -25.273) (xy 6.096 -25.146) (xy 6.096 -24.257) (xy 6.35 -24.003)
				(xy 9.017 -24.003) (xy 9.144 -23.876) (xy 9.144 -22.86) (xy 9.017 -22.733) (xy 6.604 -22.733) (xy 6.477 -22.606)
				(xy 6.477 -21.082) (xy 6.731 -20.828) (xy 8.509 -20.828) (xy 10.414 -22.733) (xy 12.065 -22.733)
				(xy 12.319 -22.987) (xy 12.319 -28.575) (xy 11.684 -29.21) (xy 9.398 -29.21) (xy 9.144 -28.956)
				(xy 5.969 -28.956) (xy 5.842 -29.083) (xy 5.842 -30.353) (xy 6.35 -30.861) (xy 8.636 -30.861) (xy 9.144 -30.353)
				(xy 11.811 -30.353) (xy 12.192 -29.972) (xy 12.573 -29.972) (xy 12.827 -29.718) (xy 12.827 -29.337)
				(xy 13.335 -28.829) (xy 15.367 -28.829) (xy 15.621 -28.575) (xy 15.621 -23.114) (xy 15.113 -22.606)
				(xy 15.113 -21.971) (xy 15.367 -21.717) (xy 15.367 -20.066) (xy 15.748 -19.685) (xy 21.971 -19.685)
				(xy 22.987 -18.669) (xy 25.781 -18.669) (xy 25.908 -18.542) (xy 25.908 -15.748) (xy 27.432 -14.224)
				(xy 27.432 -11.049) (xy 26.924 -10.541) (xy 26.924 -10.033) (xy 27.305 -9.652) (xy 27.305 -9.017)
				(xy 27.051 -8.763) (xy 24.892 -8.763) (xy 24.638 -9.017) (xy 24.638 -9.906) (xy 24.892 -10.16) (xy 24.892 -10.541)
				(xy 24.511 -10.922) (xy 23.241 -10.922) (xy 22.86 -10.541) (xy 22.86 -10.16) (xy 23.241 -9.779)
				(xy 23.241 -9.017) (xy 22.86 -8.636)
			)
		)
		(polygon
			(pts
				(xy 10.6172 -29.9085) (xy 10.3632 -29.9085) (xy 10.3632 -30.1625) (xy 10.6172 -30.1625)
			)
		)
		(polygon
			(pts
				(xy 9.6012 -29.9085) (xy 9.3472 -29.9085) (xy 9.3472 -30.1625) (xy 9.6012 -30.1625)
			)
		)
		(polygon
			(pts
				(xy 12.4714 -29.083) (xy 12.2174 -29.083) (xy 12.2174 -29.337) (xy 12.4714 -29.337)
			)
		)
	)
	(zone
		(net "GND")
		(layer "F.Cu")
		(hatch none 0.5)
		(connect_pads
			(clearance 0.5)
		)
		(min_thickness 0.25)
		(fill yes
			(thermal_gap 0.5)
			(thermal_bridge_width 0.5)
			(island_removal_mode 0)
		)
		(polygon
			(pts
				(xy 45.8216 -48.514) (xy 45.6946 -48.641) (xy 45.6946 -49.2506) (xy 44.6024 -50.3428) (xy 43.1292 -50.3428)
				(xy 42.9006 -50.1142) (xy 42.9006 -49.8348) (xy 42.7482 -49.6824) (xy 41.6306 -49.6824) (xy 41.5036 -49.8094)
				(xy 41.5036 -52.0192) (xy 41.656 -52.1716) (xy 43.3832 -52.1716) (xy 43.7134 -51.8414) (xy 43.7134 -51.2318)
				(xy 43.9293 -51.0159) (xy 44.9834 -51.0159) (xy 45.1485 -51.181) (xy 46.3169 -51.181) (xy 47.0789 -51.943)
				(xy 48.1584 -51.943) (xy 48.3108 -52.0954) (xy 48.3108 -52.4129) (xy 48.4759 -52.578) (xy 48.6664 -52.578)
				(xy 48.8442 -52.4002) (xy 48.8442 -51.2953) (xy 48.387 -50.8381) (xy 48.387 -48.641) (xy 48.26 -48.514)
			)
		)
		(polygon
			(pts
				(xy 48.2346 -51.2699) (xy 47.9806 -51.2699) (xy 47.9806 -51.5239) (xy 48.2346 -51.5239)
			)
		)
		(polygon
			(pts
				(xy 47.7266 -51.2699) (xy 47.4726 -51.2699) (xy 47.4726 -51.5239) (xy 47.7266 -51.5239)
			)
		)
		(polygon
			(pts
				(xy 42.9133 -51.0032) (xy 42.6593 -51.0032) (xy 42.6593 -51.2572) (xy 42.9133 -51.2572)
			)
		)
		(polygon
			(pts
				(xy 46.5582 -50.5968) (xy 46.3042 -50.5968) (xy 46.3042 -50.8508) (xy 46.5582 -50.8508)
			)
		)
		(polygon
			(pts
				(xy 46.0502 -50.5968) (xy 45.5422 -50.5968) (xy 45.5422 -50.8508) (xy 46.0502 -50.8508)
			)
		)
		(polygon
			(pts
				(xy 47.5869 -50.546) (xy 47.3329 -50.546) (xy 47.3329 -50.8) (xy 47.5869 -50.8)
			)
		)
		(polygon
			(pts
				(xy 42.164 -50.0126) (xy 41.91 -50.0126) (xy 41.91 -50.2666) (xy 42.164 -50.2666) (xy 42.164 -50.3174)
				(xy 42.418 -50.3174) (xy 42.418 -50.0634) (xy 42.164 -50.0634)
			)
		)
		(polygon
			(pts
				(xy 47.5869 -49.53) (xy 47.3329 -49.53) (xy 47.3329 -49.784) (xy 47.5869 -49.784)
			)
		)
		(polygon
			(pts
				(xy 48.0314 -49.276) (xy 47.7774 -49.276) (xy 47.7774 -49.53) (xy 48.0314 -49.53)
			)
		)
		(polygon
			(pts
				(xy 48.0314 -48.768) (xy 47.7774 -48.768) (xy 47.7774 -49.022) (xy 48.0314 -49.022)
			)
		)
	)
	(zone
		(net "P1V0")
		(layer "F.Cu")
		(hatch none 0.5)
		(connect_pads
			(clearance 0.5)
		)
		(min_thickness 0.25)
		(fill yes
			(thermal_gap 0.5)
			(thermal_bridge_width 0.5)
			(island_removal_mode 0)
		)
		(polygon
			(pts
				(xy 98.552 -42.942002) (xy 98.425 -43.069002) (xy 98.425 -43.323002) (xy 98.429572 -43.327828) (xy 98.425 -43.3324)
				(xy 98.425 -44.085002) (xy 99.06 -44.720002) (xy 99.8982 -44.720002) (xy 100.422202 -44.196) (xy 101.9556 -44.196)
				(xy 102.41788 -43.73372) (xy 102.41788 -43.48988) (xy 101.870002 -42.942002) (xy 100.203 -42.942002)
				(xy 100.076 -43.069002) (xy 99.695 -43.069002) (xy 99.568 -42.942002)
			)
		)
	)
	(zone
		(layer "F.Cu")
		(hatch none 0.5)
		(connect_pads
			(clearance 0)
		)
		(min_thickness 0.25)
		(keepout
			(tracks allowed)
			(vias allowed)
			(pads allowed)
			(copperpour allowed)
			(footprints not_allowed)
		)
		(placement
			(enabled no)
			(sheetname "")
		)
		(fill
			(thermal_gap 0.5)
			(thermal_bridge_width 0.5)
			(island_removal_mode 0)
		)
		(polygon
			(pts
				(xy 122.599958 -73.799954) (xy 122.599958 -69.600064) (xy 118.599966 -69.600064) (xy 118.599966 -73.799954)
			)
		)
	)
	(zone
		(layer "F.Cu")
		(hatch none 0.5)
		(connect_pads
			(clearance 0)
		)
		(min_thickness 0.25)
		(keepout
			(tracks not_allowed)
			(vias allowed)
			(pads allowed)
			(copperpour not_allowed)
			(footprints allowed)
		)
		(placement
			(enabled no)
			(sheetname "")
		)
		(fill
			(thermal_gap 0.5)
			(thermal_bridge_width 0.5)
			(island_removal_mode 0)
		)
		(polygon
			(pts
				(arc
					(start 14.844522 -46.953424)
					(mid 15.270866 -46.64392)
					(end 14.961362 -47.070264)
				)
				(xy 14.91615 -47.115476) (xy 14.91615 -47.21606)
				(arc
					(start 15.082266 -47.21606)
					(mid 15.465806 -46.83252)
					(end 15.082266 -46.44898)
				)
				(arc
					(start 14.153134 -46.44898)
					(mid 13.76934 -46.832393)
					(end 14.15288 -47.21606)
				)
				(xy 14.40815 -47.21606) (xy 14.40815 -47.20463)
				(arc
					(start 14.273784 -47.070264)
					(mid 13.96428 -46.64392)
					(end 14.390624 -46.953424)
				)
				(xy 14.52499 -47.08779) (xy 14.57325 -47.13605) (xy 14.57325 -47.20463) (xy 14.57325 -47.21606)
				(xy 14.75105 -47.21606) (xy 14.75105 -47.115476) (xy 14.75105 -47.046896) (xy 14.79931 -46.998636)
			)
		)
	)
	(zone
		(layer "F.Cu")
		(hatch none 0.5)
		(connect_pads
			(clearance 0)
		)
		(min_thickness 0.25)
		(keepout
			(tracks not_allowed)
			(vias allowed)
			(pads allowed)
			(copperpour not_allowed)
			(footprints allowed)
		)
		(placement
			(enabled no)
			(sheetname "")
		)
		(fill
			(thermal_gap 0.5)
			(thermal_bridge_width 0.5)
			(island_removal_mode 0)
		)
		(polygon
			(pts
				(arc
					(start 86.443058 -53.20792)
					(mid 86.103968 -52.85613)
					(end 85.752178 -53.19522)
				)
				(arc
					(start 85.741764 -53.758592)
					(mid 86.080727 -54.110638)
					(end 86.432644 -53.771546)
				)
				(xy 86.435692 -53.6067) (xy 86.335616 -53.6067)
				(arc
					(start 86.287356 -53.654706)
					(mid 85.925543 -53.926857)
					(end 86.197694 -53.565044)
				)
				(xy 86.2457 -53.516784) (xy 86.282784 -53.4797) (xy 86.335616 -53.4797) (xy 86.437978 -53.4797)
				(xy 86.439502 -53.4035) (xy 86.262464 -53.4035) (xy 86.209632 -53.4035)
				(arc
					(start 86.208108 -53.401722)
					(mid 85.92279 -53.054247)
					(end 86.313518 -53.2765)
				)
				(xy 86.441788 -53.2765)
			)
		)
	)
	(zone
		(net "GND")
		(layer "F.Cu")
		(hatch none 0.5)
		(connect_pads
			(clearance 0.5)
		)
		(min_thickness 0.25)
		(fill yes
			(thermal_gap 0.5)
			(thermal_bridge_width 0.5)
			(island_removal_mode 0)
		)
		(polygon
			(pts
				(xy 198.12 -0.762) (xy 197.866 -1.016) (xy 197.866 -3.683) (xy 197.739 -3.81) (xy 197.739 -4.318)
				(xy 197.866 -4.445) (xy 198.12 -4.445) (xy 198.247 -4.572) (xy 198.247 -5.08) (xy 198.374 -5.207)
				(xy 204.724 -5.207) (xy 206.883 -7.366) (xy 206.883 -26.797) (xy 205.232 -28.448) (xy 205.232 -32.385)
				(xy 205.105 -32.512) (xy 205.105 -33.782) (xy 204.978 -33.909) (xy 204.47 -33.909) (xy 204.343 -34.036)
				(xy 204.343 -34.417) (xy 204.47 -34.544) (xy 204.978 -34.544) (xy 205.232 -34.798) (xy 205.232 -35.56)
				(xy 205.105 -35.687) (xy 197.993 -35.687) (xy 197.612 -36.068) (xy 197.612 -37.084) (xy 197.739 -37.211)
				(xy 198.882 -37.211) (xy 199.009 -37.338) (xy 200.025 -37.338) (xy 200.152 -37.465) (xy 200.152 -38.354)
				(xy 200.279 -38.481) (xy 204.343 -38.481) (xy 205.105 -39.243) (xy 205.867 -39.243) (xy 206.248 -39.624)
				(xy 206.248 -44.831) (xy 205.486 -45.593) (xy 205.486 -50.673) (xy 203.708 -52.451) (xy 203.708 -59.436)
				(xy 202.8444 -60.2996) (xy 202.8444 -63.1444) (xy 204.0001 -64.3001) (xy 204.0001 -69.4309) (xy 203.708 -69.723)
				(xy 198.12 -69.723) (xy 197.231 -68.834) (xy 197.231 -64.135) (xy 196.3801 -63.2841) (xy 196.3801 -59.4487)
				(xy 196.9008 -58.928) (xy 198.0692 -58.928) (xy 198.1962 -58.801) (xy 198.1962 -47.117) (xy 196.977 -45.8978)
				(xy 196.977 -41.021) (xy 194.945 -38.989) (xy 193.04 -38.989) (xy 192.024 -40.005) (xy 190.5 -40.005)
				(xy 190.246 -39.751) (xy 190.246 -39.243) (xy 190.119 -39.116) (xy 189.865 -39.116) (xy 189.738 -39.243)
				(xy 189.738 -40.64) (xy 189.484 -40.894) (xy 189.484 -42.418) (xy 189.357 -42.545) (xy 187.833 -42.545)
				(xy 187.452 -42.164) (xy 187.452 -40.132) (xy 187.325 -40.005) (xy 184.531 -40.005) (xy 184.277 -40.259)
				(xy 184.277 -41.402) (xy 186.055 -43.18) (xy 186.944 -43.18) (xy 188.087 -44.323) (xy 188.087 -45.72)
				(xy 188.214 -45.847) (xy 188.722 -45.847) (xy 188.849 -45.974) (xy 188.849 -48.26) (xy 188.976 -48.387)
				(xy 189.484 -48.387) (xy 189.611 -48.514) (xy 189.611 -50.292) (xy 189.103 -50.8) (xy 187.833 -50.8)
				(xy 187.706 -50.927) (xy 187.706 -52.705) (xy 185.547 -54.864) (xy 184.023 -54.864) (xy 183.896 -54.991)
				(xy 183.896 -55.372) (xy 184.023 -55.499) (xy 184.912 -55.499) (xy 186.309 -56.896) (xy 186.309 -58.42)
				(xy 187.579 -59.69) (xy 188.341 -59.69) (xy 188.849 -60.198) (xy 189.611 -60.198) (xy 191.135 -61.722)
				(xy 191.135 -64.135) (xy 193.294 -66.294) (xy 193.294 -68.6816) (xy 197.6374 -73.025) (xy 208.915 -73.025)
				(xy 209.169 -72.771) (xy 209.169 -1.016) (xy 208.915 -0.762)
			)
		)
		(polygon
			(pts
				(xy 205.1431 -66.5734) (xy 204.8891 -66.5734) (xy 204.8891 -67.0814) (xy 205.1431 -67.0814)
			)
		)
		(polygon
			(pts
				(xy 205.1431 -65.5574) (xy 204.8891 -65.5574) (xy 204.8891 -65.8114) (xy 205.1431 -65.8114)
			)
		)
		(polygon
			(pts
				(xy 189.484 -59.5884) (xy 189.23 -59.5884) (xy 189.23 -59.8424) (xy 189.484 -59.8424)
			)
		)
		(polygon
			(pts
				(xy 188.976 -59.5884) (xy 188.722 -59.5884) (xy 188.722 -59.8424) (xy 188.976 -59.8424)
			)
		)
		(polygon
			(pts
				(xy 188.595 -58.7629) (xy 188.341 -58.7629) (xy 188.341 -59.0169) (xy 188.595 -59.0169)
			)
		)
		(polygon
			(pts
				(xy 187.579 -58.7629) (xy 187.325 -58.7629) (xy 187.325 -59.0169) (xy 187.579 -59.0169)
			)
		)
		(polygon
			(pts
				(xy 188.468 -51.2572) (xy 188.214 -51.2572) (xy 188.214 -51.5112) (xy 188.468 -51.5112)
			)
		)
		(polygon
			(pts
				(xy 189.484 -47.7774) (xy 189.23 -47.7774) (xy 189.23 -48.0314) (xy 189.484 -48.0314)
			)
		)
		(polygon
			(pts
				(xy 188.722 -45.1358) (xy 188.468 -45.1358) (xy 188.468 -45.3898) (xy 188.722 -45.3898)
			)
		)
		(polygon
			(pts
				(xy 186.69 -42.5704) (xy 186.436 -42.5704) (xy 186.436 -42.8244) (xy 186.69 -42.8244)
			)
		)
		(polygon
			(pts
				(xy 192.024 -40.4622) (xy 191.77 -40.4622) (xy 191.77 -40.7162) (xy 192.024 -40.7162)
			)
		)
		(polygon
			(pts
				(xy 191.516 -40.4622) (xy 191.008 -40.4622) (xy 191.008 -40.7162) (xy 191.516 -40.7162)
			)
		)
		(polygon
			(pts
				(xy 186.309 -40.4622) (xy 185.801 -40.4622) (xy 185.801 -40.7162) (xy 186.309 -40.7162)
			)
		)
		(polygon
			(pts
				(xy 185.547 -40.4622) (xy 185.039 -40.4622) (xy 185.039 -40.7162) (xy 185.547 -40.7162)
			)
		)
		(polygon
			(pts
				(xy 184.785 -40.4622) (xy 184.531 -40.4622) (xy 184.531 -40.7162) (xy 184.785 -40.7162)
			)
		)
		(polygon
			(pts
				(xy 190.4492 -40.386) (xy 190.1952 -40.386) (xy 190.1952 -40.64) (xy 190.4492 -40.64) (xy 190.5 -40.7162)
				(xy 190.754 -40.7162) (xy 190.754 -40.4622) (xy 190.5 -40.4622)
			)
		)
		(polygon
			(pts
				(xy 187.071 -40.3606) (xy 186.817 -40.3606) (xy 186.817 -40.4622) (xy 186.563 -40.4622) (xy 186.563 -40.7162)
				(xy 186.817 -40.7162) (xy 186.817 -40.6146) (xy 187.071 -40.6146)
			)
		)
		(polygon
			(pts
				(xy 194.818 -39.6621) (xy 194.564 -39.6621) (xy 194.564 -39.9161) (xy 194.818 -39.9161)
			)
		)
		(polygon
			(pts
				(xy 193.802 -39.6621) (xy 193.548 -39.6621) (xy 193.548 -39.9161) (xy 193.802 -39.9161)
			)
		)
		(polygon
			(pts
				(xy 198.374 -36.4998) (xy 198.12 -36.4998) (xy 198.12 -36.7538) (xy 198.374 -36.7538)
			)
		)
		(polygon
			(pts
				(xy 204.978 -36.0426) (xy 204.724 -36.0426) (xy 204.724 -36.2966) (xy 204.978 -36.2966)
			)
		)
		(polygon
			(pts
				(xy 204.47 -36.0426) (xy 204.216 -36.0426) (xy 204.216 -36.2966) (xy 204.47 -36.2966)
			)
		)
		(polygon
			(pts
				(xy 198.9582 -4.445) (xy 198.7042 -4.445) (xy 198.7042 -4.699) (xy 198.9582 -4.699)
			)
		)
		(polygon
			(pts
				(xy 198.3486 -3.683) (xy 198.0946 -3.683) (xy 198.0946 -3.937) (xy 198.3486 -3.937)
			)
		)
		(polygon
			(pts
				(xy 198.9201 -3.429) (xy 198.6661 -3.429) (xy 198.6661 -3.683) (xy 198.9201 -3.683)
			)
		)
		(polygon
			(pts
				(xy 198.9201 -2.159) (xy 198.6661 -2.159) (xy 198.6661 -2.667) (xy 198.9201 -2.667)
			)
		)
		(polygon
			(pts
				(xy 198.9201 -1.143) (xy 198.6661 -1.143) (xy 198.6661 -1.397) (xy 198.9201 -1.397)
			)
		)
	)
	(zone
		(layer "F.Cu")
		(hatch none 0.5)
		(connect_pads
			(clearance 0)
		)
		(min_thickness 0.25)
		(keepout
			(tracks not_allowed)
			(vias allowed)
			(pads allowed)
			(copperpour not_allowed)
			(footprints allowed)
		)
		(placement
			(enabled no)
			(sheetname "")
		)
		(fill
			(thermal_gap 0.5)
			(thermal_bridge_width 0.5)
			(island_removal_mode 0)
		)
		(polygon
			(pts
				(arc
					(start 83.389216 -10.02919)
					(mid 83.005422 -10.412603)
					(end 83.388962 -10.79627)
				)
				(arc
					(start 84.310474 -10.79627)
					(mid 84.694014 -10.41273)
					(end 84.310474 -10.02919)
				)
				(xy 84.103718 -10.02919) (xy 84.103718 -10.089134)
				(arc
					(start 84.18957 -10.174986)
					(mid 84.499074 -10.60133)
					(end 84.07273 -10.291826)
				)
				(xy 83.986878 -10.205974) (xy 83.938618 -10.157714) (xy 83.938618 -10.089134) (xy 83.938618 -10.02919)
				(xy 83.760818 -10.02919) (xy 83.760818 -10.089134) (xy 83.760818 -10.157714) (xy 83.712558 -10.205974)
				(arc
					(start 83.626706 -10.291826)
					(mid 83.200362 -10.60133)
					(end 83.509866 -10.174986)
				)
				(xy 83.595718 -10.089134) (xy 83.595718 -10.02919)
			)
		)
	)
	(zone
		(net "PVCCP")
		(layer "F.Cu")
		(hatch none 0.5)
		(connect_pads
			(clearance 0.5)
		)
		(min_thickness 0.25)
		(fill yes
			(thermal_gap 0.5)
			(thermal_bridge_width 0.5)
			(island_removal_mode 0)
		)
		(polygon
			(pts
				(xy 100.447348 -37.082476) (xy 100.170488 -37.359336) (xy 99.367848 -37.359336) (xy 99.116388 -37.610796)
				(xy 99.116388 -41.032176) (xy 99.456748 -41.372536) (xy 101.645466 -41.372536) (xy 101.727 -41.291002)
				(xy 101.981 -41.291002) (xy 102.489 -40.783002) (xy 102.489 -40.781986) (xy 102.616 -40.654986)
				(xy 106.554016 -40.654986) (xy 106.68 -40.529002) (xy 109.22 -40.529002) (xy 109.420406 -40.328596)
				(xy 109.995208 -40.328596) (xy 110.005368 -40.318436) (xy 110.157768 -40.470836) (xy 110.157768 -40.815768)
				(xy 110.236 -40.894) (xy 110.49 -40.894) (xy 110.617 -40.767) (xy 110.617 -40.513) (xy 110.853728 -40.276272)
				(xy 111.015272 -40.276272) (xy 111.034068 -40.257476) (xy 112.139476 -40.257476) (xy 113.792 -41.91)
				(xy 116.586 -41.91) (xy 116.713 -41.783) (xy 116.713 -38.989) (xy 116.586 -38.862) (xy 111.76 -38.862)
				(xy 111.747046 -38.874954) (xy 111.493046 -38.874954) (xy 111.351568 -38.733476) (xy 111.351568 -38.634416)
				(xy 111.059468 -38.342316) (xy 110.795308 -38.342316) (xy 110.1852 -37.732208) (xy 109.284008 -37.732208)
				(xy 109.015784 -38.000432) (xy 107.414568 -38.000432) (xy 107.061 -38.354) (xy 106.68 -38.354) (xy 106.426 -38.1)
				(xy 105.918 -38.1) (xy 105.664 -38.354) (xy 103.577644 -38.354) (xy 103.221028 -37.997384) (xy 102.744016 -37.997384)
				(xy 102.613968 -37.867336) (xy 102.613968 -37.283136) (xy 102.413308 -37.082476)
			)
		)
	)
	(zone
		(layer "F.Cu")
		(hatch none 0.5)
		(connect_pads
			(clearance 0)
		)
		(min_thickness 0.25)
		(keepout
			(tracks allowed)
			(vias allowed)
			(pads allowed)
			(copperpour allowed)
			(footprints allowed)
		)
		(placement
			(enabled no)
			(sheetname "")
		)
		(fill
			(thermal_gap 0.5)
			(thermal_bridge_width 0.5)
			(island_removal_mode 0)
		)
		(polygon
			(pts
				(xy 148.0312 -24.0792) (xy 148.0312 -22.3774) (xy 148.8186 -22.3774) (xy 148.8186 -24.0792)
			)
		)
	)
	(zone
		(layer "F.Cu")
		(hatch none 0.5)
		(connect_pads
			(clearance 0)
		)
		(min_thickness 0.25)
		(keepout
			(tracks not_allowed)
			(vias allowed)
			(pads allowed)
			(copperpour not_allowed)
			(footprints allowed)
		)
		(placement
			(enabled no)
			(sheetname "")
		)
		(fill
			(thermal_gap 0.5)
			(thermal_bridge_width 0.5)
			(island_removal_mode 0)
		)
		(polygon
			(pts
				(arc
					(start 84.348828 -59.595258)
					(mid 84.354625 -59.108766)
					(end 83.868006 -59.106054)
				)
				(arc
					(start 83.309968 -59.661806)
					(mid 83.308952 -60.146946)
					(end 83.794092 -60.147962)
				)
				(xy 83.874864 -60.067444) (xy 83.794854 -59.987434)
				(arc
					(start 83.765136 -59.987434)
					(mid 83.323494 -59.904884)
					(end 83.765136 -59.822334)
				)
				(xy 83.794854 -59.822334) (xy 83.863434 -59.822334) (xy 83.911694 -59.870594) (xy 83.991958 -59.950858)
				(xy 84.072476 -59.870594) (xy 84.117942 -59.825382) (xy 84.114894 -59.822334) (xy 84.075778 -59.783218)
				(xy 84.027518 -59.734958) (xy 84.027518 -59.666378)
				(arc
					(start 84.027518 -59.562238)
					(mid 84.110068 -59.120596)
					(end 84.192618 -59.562238)
				)
				(xy 84.192618 -59.666378) (xy 84.234782 -59.708796)
			)
		)
	)
	(zone
		(layer "F.Cu")
		(hatch none 0.5)
		(connect_pads
			(clearance 0)
		)
		(min_thickness 0.25)
		(keepout
			(tracks allowed)
			(vias allowed)
			(pads allowed)
			(copperpour allowed)
			(footprints not_allowed)
		)
		(placement
			(enabled no)
			(sheetname "")
		)
		(fill
			(thermal_gap 0.5)
			(thermal_bridge_width 0.5)
			(island_removal_mode 0)
		)
		(polygon
			(pts
				(xy 158.83001 -19.899884) (xy 158.83001 -31.170118) (xy 161.980118 -31.170118) (xy 161.980118 -19.899884)
			)
		)
	)
	(zone
		(net "P12V")
		(layer "F.Cu")
		(hatch none 0.5)
		(connect_pads
			(clearance 0.5)
		)
		(min_thickness 0.25)
		(fill yes
			(thermal_gap 0.5)
			(thermal_bridge_width 0.5)
			(island_removal_mode 0)
		)
		(polygon
			(pts
				(xy 1.016 -29.083) (xy 0.889 -29.21) (xy 0.889 -32.639) (xy 1.143 -32.893) (xy 3.81 -32.893) (xy 4.318 -32.385)
				(xy 5.461 -32.385) (xy 5.588 -32.258) (xy 5.588 -29.21) (xy 5.461 -29.083)
			)
		)
		(polygon
			(pts
				(xy 4.699 -31.0769) (xy 4.445 -31.0769) (xy 4.445 -31.3309) (xy 4.699 -31.3309)
			)
		)
	)
	(zone
		(layer "F.Cu")
		(hatch none 0.5)
		(connect_pads
			(clearance 0)
		)
		(min_thickness 0.25)
		(keepout
			(tracks not_allowed)
			(vias allowed)
			(pads allowed)
			(copperpour not_allowed)
			(footprints allowed)
		)
		(placement
			(enabled no)
			(sheetname "")
		)
		(fill
			(thermal_gap 0.5)
			(thermal_bridge_width 0.5)
			(island_removal_mode 0)
		)
		(polygon
			(pts
				(arc
					(start 27.408378 -9.867138)
					(mid 27.024838 -10.250678)
					(end 27.408378 -10.634218)
				)
				(arc
					(start 28.327604 -10.634218)
					(mid 28.711398 -10.250805)
					(end 28.327858 -9.867138)
				)
				(xy 28.10383 -9.867138) (xy 28.10383 -9.90981)
				(arc
					(start 28.206954 -10.012934)
					(mid 28.516458 -10.439278)
					(end 28.090114 -10.129774)
				)
				(xy 27.98699 -10.02665) (xy 27.93873 -9.97839) (xy 27.93873 -9.90981) (xy 27.93873 -9.867138) (xy 27.76093 -9.867138)
				(xy 27.76093 -9.946386) (xy 27.76093 -10.014966) (xy 27.71267 -10.063226)
				(arc
					(start 27.646122 -10.129774)
					(mid 27.219778 -10.439278)
					(end 27.529282 -10.012934)
				)
				(xy 27.59583 -9.946386) (xy 27.59583 -9.867138)
			)
		)
	)
	(zone
		(layer "F.Cu")
		(hatch none 0.5)
		(connect_pads
			(clearance 0)
		)
		(min_thickness 0.25)
		(keepout
			(tracks allowed)
			(vias allowed)
			(pads allowed)
			(copperpour allowed)
			(footprints not_allowed)
		)
		(placement
			(enabled no)
			(sheetname "")
		)
		(fill
			(thermal_gap 0.5)
			(thermal_bridge_width 0.5)
			(island_removal_mode 0)
		)
		(polygon
			(pts
				(xy 92.16009 -11.619992) (xy 20.699984 -11.619992) (xy 20.699984 -69.600064)
				(arc
					(start 48.810418 -69.600064)
					(mid 50.850038 -68.800027)
					(end 52.889658 -69.600064)
				)
				(xy 56.799988 -69.600064) (xy 56.799988 -63.699898) (xy 58.09996 -63.699898) (xy 58.09996 -69.600064)
				(xy 68.039996 -69.600064) (xy 68.039996 -64.200024) (xy 58.475118 -64.200024) (xy 58.475118 -14.200124)
				(xy 92.16009 -14.200124)
			)
		)
	)
	(zone
		(layer "F.Cu")
		(hatch none 0.5)
		(connect_pads
			(clearance 0)
		)
		(min_thickness 0.25)
		(keepout
			(tracks allowed)
			(vias allowed)
			(pads allowed)
			(copperpour allowed)
			(footprints allowed)
		)
		(placement
			(enabled no)
			(sheetname "")
		)
		(fill
			(thermal_gap 0.5)
			(thermal_bridge_width 0.5)
			(island_removal_mode 0)
		)
		(polygon
			(pts
				(xy 142.5702 -47.244) (xy 140.462 -47.244) (xy 140.462 -44.323) (xy 142.5702 -44.323)
			)
		)
	)
	(zone
		(net "GND")
		(layer "F.Cu")
		(hatch none 0.5)
		(connect_pads
			(clearance 0.5)
		)
		(min_thickness 0.25)
		(fill yes
			(thermal_gap 0.5)
			(thermal_bridge_width 0.5)
			(island_removal_mode 0)
		)
		(polygon
			(pts
				(xy 34.417 -66.802) (xy 34.29 -66.929) (xy 34.29 -69.342) (xy 34.544 -69.596) (xy 34.798 -69.596)
				(xy 35.179 -69.215) (xy 35.179 -68.453) (xy 35.941 -67.691) (xy 35.941 -66.929) (xy 35.814 -66.802)
			)
		)
		(polygon
			(pts
				(xy 35.0012 -67.945) (xy 34.7472 -67.945) (xy 34.7472 -68.199) (xy 35.0012 -68.199)
			)
		)
	)
	(zone
		(net "PV_VTT_DDR_B")
		(layer "F.Cu")
		(hatch none 0.5)
		(connect_pads
			(clearance 0.5)
		)
		(min_thickness 0.25)
		(fill yes
			(thermal_gap 0.5)
			(thermal_bridge_width 0.5)
			(island_removal_mode 0)
		)
		(polygon
			(pts
				(xy 191.643 -8.89) (xy 191.516 -9.017) (xy 191.516 -10.795) (xy 191.262 -11.049) (xy 186.436 -11.049)
				(xy 185.293 -12.192) (xy 185.293 -15.621) (xy 185.42 -15.748) (xy 185.42 -16.256) (xy 185.674 -16.51)
				(xy 186.944 -16.51) (xy 187.579 -15.875) (xy 190.373 -15.875) (xy 190.627 -15.621) (xy 190.627 -15.24)
				(xy 193.294 -12.573) (xy 193.294 -9.144) (xy 193.04 -8.89)
			)
		)
		(polygon
			(pts
				(xy 186.2201 -15.367) (xy 185.9661 -15.367) (xy 185.9661 -15.621) (xy 186.2201 -15.621)
			)
		)
		(polygon
			(pts
				(xy 190.5 -14.9479) (xy 190.246 -14.9479) (xy 190.246 -15.2019) (xy 190.5 -15.2019)
			)
		)
		(polygon
			(pts
				(xy 189.484 -14.9479) (xy 188.976 -14.9479) (xy 188.976 -15.2019) (xy 189.484 -15.2019)
			)
		)
		(polygon
			(pts
				(xy 188.214 -14.9479) (xy 187.96 -14.9479) (xy 187.96 -15.2019) (xy 188.214 -15.2019)
			)
		)
		(polygon
			(pts
				(xy 186.2201 -14.097) (xy 185.9661 -14.097) (xy 185.9661 -14.605) (xy 186.2201 -14.605)
			)
		)
		(polygon
			(pts
				(xy 186.2201 -13.081) (xy 185.9661 -13.081) (xy 185.9661 -13.335) (xy 186.2201 -13.335)
			)
		)
	)
	(zone
		(layer "F.Cu")
		(hatch none 0.5)
		(connect_pads
			(clearance 0)
		)
		(min_thickness 0.25)
		(keepout
			(tracks allowed)
			(vias allowed)
			(pads allowed)
			(copperpour allowed)
			(footprints allowed)
		)
		(placement
			(enabled no)
			(sheetname "")
		)
		(fill
			(thermal_gap 0.5)
			(thermal_bridge_width 0.5)
			(island_removal_mode 0)
		)
		(polygon
			(pts
				(xy 190.373 -4.446778) (xy 190.373 -0.128778) (xy 197.612 -0.128778) (xy 197.612 -4.446778)
			)
		)
	)
	(zone
		(net "P3V3_STBY_VIN")
		(layer "F.Cu")
		(hatch none 0.5)
		(connect_pads
			(clearance 0.5)
		)
		(min_thickness 0.25)
		(fill yes
			(thermal_gap 0.5)
			(thermal_bridge_width 0.5)
			(island_removal_mode 0)
		)
		(polygon
			(pts
				(xy 6.096 -36.322) (xy 5.842 -36.576) (xy 5.842 -41.402) (xy 6.096 -41.656) (xy 8.763 -41.656) (xy 9.398 -41.021)
				(xy 9.398 -39.751) (xy 9.144 -39.497) (xy 9.144 -36.449) (xy 9.017 -36.322)
			)
		)
		(polygon
			(pts
				(xy 9.0424 -40.259) (xy 8.7884 -40.259) (xy 8.7884 -40.513) (xy 9.0424 -40.513)
			)
		)
		(polygon
			(pts
				(xy 7.1501 -40.2209) (xy 6.8961 -40.2209) (xy 6.8961 -40.4749) (xy 7.1501 -40.4749)
			)
		)
		(polygon
			(pts
				(xy 9.0424 -39.751) (xy 8.7884 -39.751) (xy 8.7884 -40.005) (xy 9.0424 -40.005)
			)
		)
		(polygon
			(pts
				(xy 7.1501 -38.8747) (xy 6.8961 -38.8747) (xy 6.8961 -39.1287) (xy 7.1501 -39.1287)
			)
		)
	)
	(zone
		(layer "F.Cu")
		(hatch none 0.5)
		(connect_pads
			(clearance 0)
		)
		(min_thickness 0.25)
		(keepout
			(tracks not_allowed)
			(vias allowed)
			(pads allowed)
			(copperpour not_allowed)
			(footprints allowed)
		)
		(placement
			(enabled no)
			(sheetname "")
		)
		(fill
			(thermal_gap 0.5)
			(thermal_bridge_width 0.5)
			(island_removal_mode 0)
		)
		(polygon
			(pts
				(arc
					(start 101.734366 -61.66993)
					(mid 101.189299 -61.660676)
					(end 101.185472 -62.20587)
				)
				(arc
					(start 101.795072 -62.817756)
					(mid 102.337616 -62.818772)
					(end 102.338632 -62.276228)
				)
				(xy 102.143052 -62.079886)
				(arc
					(start 102.143052 -62.291468)
					(mid 102.066852 -62.813636)
					(end 101.990652 -62.291468)
				)
				(xy 101.990652 -62.014862) (xy 102.03434 -61.97092) (xy 101.962712 -61.899038) (xy 101.85019 -62.011306)
				(arc
					(start 101.712776 -62.011306)
					(mid 101.190608 -61.935106)
					(end 101.712776 -61.858906)
				)
				(xy 101.787198 -61.858906) (xy 101.855016 -61.791088)
			)
		)
	)
	(zone
		(layer "F.Cu")
		(hatch none 0.5)
		(connect_pads
			(clearance 0)
		)
		(min_thickness 0.25)
		(keepout
			(tracks not_allowed)
			(vias allowed)
			(pads allowed)
			(copperpour not_allowed)
			(footprints allowed)
		)
		(placement
			(enabled no)
			(sheetname "")
		)
		(fill
			(thermal_gap 0.5)
			(thermal_bridge_width 0.5)
			(island_removal_mode 0)
		)
		(polygon
			(pts
				(xy 49.53635 -13.4366)
				(arc
					(start 49.53635 -13.564108)
					(mid 49.4538 -14.084195)
					(end 49.37125 -13.564108)
				)
				(arc
					(start 49.37125 -13.445744)
					(mid 49.075161 -13.859122)
					(end 49.4538 -14.1986)
				)
				(arc
					(start 50.2158 -14.1986)
					(mid 50.59453 -13.859132)
					(end 50.29835 -13.445744)
				)
				(arc
					(start 50.29835 -13.564108)
					(mid 50.2158 -14.084195)
					(end 50.13325 -13.564108)
				)
				(xy 50.13325 -13.4366)
			)
		)
	)
	(zone
		(net "P1V8_STBY_LDO_IN2")
		(layer "F.Cu")
		(hatch none 0.5)
		(connect_pads
			(clearance 0.5)
		)
		(min_thickness 0.25)
		(fill yes
			(thermal_gap 0.5)
			(thermal_bridge_width 0.5)
			(island_removal_mode 0)
		)
		(polygon
			(pts
				(xy 168.148 -22.606) (xy 168.021 -22.733) (xy 168.021 -25.4) (xy 168.148 -25.527) (xy 171.704 -25.527)
				(xy 171.831 -25.4) (xy 171.831 -22.733) (xy 171.704 -22.606)
			)
		)
		(polygon
			(pts
				(xy 169.0751 -23.495) (xy 168.8211 -23.495) (xy 168.8211 -23.749) (xy 169.0751 -23.749)
			)
		)
	)
	(zone
		(layer "F.Cu")
		(hatch none 0.5)
		(connect_pads
			(clearance 0)
		)
		(min_thickness 0.25)
		(keepout
			(tracks allowed)
			(vias allowed)
			(pads allowed)
			(copperpour allowed)
			(footprints allowed)
		)
		(placement
			(enabled no)
			(sheetname "")
		)
		(fill
			(thermal_gap 0.5)
			(thermal_bridge_width 0.5)
			(island_removal_mode 0)
		)
		(polygon
			(pts
				(xy 153.035 -38.5826) (xy 153.035 -37.973) (xy 153.8224 -37.973) (xy 153.8224 -38.5826)
			)
		)
	)
	(zone
		(layer "F.Cu")
		(hatch none 0.5)
		(connect_pads
			(clearance 0)
		)
		(min_thickness 0.25)
		(keepout
			(tracks allowed)
			(vias allowed)
			(pads allowed)
			(copperpour allowed)
			(footprints allowed)
		)
		(placement
			(enabled no)
			(sheetname "")
		)
		(fill
			(thermal_gap 0.5)
			(thermal_bridge_width 0.5)
			(island_removal_mode 0)
		)
		(polygon
			(pts
				(xy 34.5186 -32.385) (xy 34.5186 -26.1112) (xy 37.0078 -26.1112) (xy 37.0078 -32.385)
			)
		)
	)
	(zone
		(net "PVCCP")
		(layer "F.Cu")
		(hatch none 0.5)
		(connect_pads
			(clearance 0.5)
		)
		(min_thickness 0.25)
		(fill yes
			(thermal_gap 0.5)
			(thermal_bridge_width 0.5)
			(island_removal_mode 0)
		)
		(polygon
			(pts
				(xy 53.213 -56.388) (xy 52.959 -56.642) (xy 52.959 -62.865) (xy 53.34 -63.246) (xy 56.896 -63.246)
				(xy 57.15 -63.5) (xy 66.167 -63.5) (xy 66.294 -63.373) (xy 66.294 -62.357) (xy 65.786 -61.849) (xy 65.786 -60.198)
				(xy 66.167 -59.817) (xy 66.167 -57.023) (xy 66.04 -56.896) (xy 56.261 -56.896) (xy 55.753 -56.388)
			)
		)
		(polygon
			(pts
				(xy 65.405 -57.5691) (xy 65.151 -57.5691) (xy 65.151 -57.8231) (xy 65.405 -57.8231)
			)
		)
		(polygon
			(pts
				(xy 64.389 -57.5691) (xy 64.135 -57.5691) (xy 64.135 -57.8231) (xy 64.389 -57.8231)
			)
		)
	)
	(zone
		(layer "F.Cu")
		(hatch none 0.5)
		(connect_pads
			(clearance 0)
		)
		(min_thickness 0.25)
		(keepout
			(tracks not_allowed)
			(vias allowed)
			(pads allowed)
			(copperpour not_allowed)
			(footprints allowed)
		)
		(placement
			(enabled no)
			(sheetname "")
		)
		(fill
			(thermal_gap 0.5)
			(thermal_bridge_width 0.5)
			(island_removal_mode 0)
		)
		(polygon
			(pts
				(arc
					(start 88.405208 -53.085238)
					(mid 88.085297 -53.131155)
					(end 87.943436 -53.421534)
				)
				(xy 87.940896 -53.421534) (xy 87.95893 -53.98008)
				(arc
					(start 87.96147 -53.98008)
					(mid 88.317832 -54.31409)
					(end 88.651842 -53.957728)
				)
				(xy 88.654382 -53.957728) (xy 88.646762 -53.718714)
				(arc
					(start 88.506808 -53.858414)
					(mid 88.144995 -54.130565)
					(end 88.417146 -53.768752)
				)
				(xy 88.608408 -53.577236)
				(arc
					(start 88.608408 -53.279802)
					(mid 88.576059 -53.218817)
					(end 88.532208 -53.165502)
				)
				(xy 88.532208 -53.196236) (xy 88.532208 -53.249068) (xy 88.495124 -53.286152)
				(arc
					(start 88.48598 -53.295042)
					(mid 88.130496 -53.575531)
					(end 88.394032 -53.207412)
				)
				(xy 88.405208 -53.196236)
			)
		)
	)
	(zone
		(layer "F.Cu")
		(hatch none 0.5)
		(connect_pads
			(clearance 0)
		)
		(min_thickness 0.25)
		(keepout
			(tracks allowed)
			(vias allowed)
			(pads allowed)
			(copperpour allowed)
			(footprints allowed)
		)
		(placement
			(enabled no)
			(sheetname "")
		)
		(fill
			(thermal_gap 0.5)
			(thermal_bridge_width 0.5)
			(island_removal_mode 0)
		)
		(polygon
			(pts
				(xy 54.36616 -53.213) (xy 54.36616 -48.26) (xy 59.4614 -48.26) (xy 59.4614 -53.213)
			)
		)
	)
	(zone
		(net "PV_VDDR")
		(layer "F.Cu")
		(hatch none 0.5)
		(connect_pads
			(clearance 0.5)
		)
		(min_thickness 0.25)
		(fill yes
			(thermal_gap 0.5)
			(thermal_bridge_width 0.5)
			(island_removal_mode 0)
		)
		(polygon
			(pts
				(xy 134.747 -57.531) (xy 134.239 -58.039) (xy 133.223 -58.039) (xy 133.096 -58.166) (xy 133.096 -60.325)
				(xy 133.223 -60.452) (xy 133.985 -60.452) (xy 134.747 -59.69) (xy 135.128 -59.69) (xy 135.382 -59.436)
				(xy 135.382 -58.293) (xy 135.255 -58.166) (xy 135.255 -57.658) (xy 135.128 -57.531)
			)
		)
		(polygon
			(pts
				(xy 134.0231 -59.055) (xy 133.7691 -59.055) (xy 133.7691 -59.563) (xy 134.0231 -59.563)
			)
		)
		(polygon
			(pts
				(xy 134.874 -58.9788) (xy 134.62 -58.9788) (xy 134.62 -59.2328) (xy 134.874 -59.2328)
			)
		)
	)
	(zone
		(net "PV_VDDR")
		(layer "F.Cu")
		(hatch none 0.5)
		(connect_pads
			(clearance 0.5)
		)
		(min_thickness 0.25)
		(fill yes
			(thermal_gap 0.5)
			(thermal_bridge_width 0.5)
			(island_removal_mode 0)
		)
		(polygon
			(pts
				(xy 199.0852 -47.2948) (xy 198.628 -47.752) (xy 198.628 -59.0804) (xy 198.3994 -59.309) (xy 197.2818 -59.309)
				(xy 196.8754 -59.7154) (xy 196.8754 -63.2714) (xy 197.612 -64.008) (xy 197.612 -68.58) (xy 198.374 -69.342)
				(xy 203.581 -69.342) (xy 203.6826 -69.2404) (xy 203.6826 -64.516) (xy 202.4634 -63.2968) (xy 202.4634 -60.0456)
				(xy 203.327 -59.182) (xy 203.327 -52.3748) (xy 204.724 -50.9778) (xy 204.724 -47.7266) (xy 204.2922 -47.2948)
			)
		)
		(polygon
			(pts
				(xy 203.0349 -67.8434) (xy 202.7809 -67.8434) (xy 202.7809 -68.3514) (xy 203.0349 -68.3514)
			)
		)
		(polygon
			(pts
				(xy 203.0349 -66.5734) (xy 202.7809 -66.5734) (xy 202.7809 -67.0814) (xy 203.0349 -67.0814)
			)
		)
		(polygon
			(pts
				(xy 203.0349 -65.5574) (xy 202.7809 -65.5574) (xy 202.7809 -65.8114) (xy 203.0349 -65.8114)
			)
		)
	)
	(zone
		(layer "F.Cu")
		(hatch none 0.5)
		(connect_pads
			(clearance 0)
		)
		(min_thickness 0.25)
		(keepout
			(tracks not_allowed)
			(vias allowed)
			(pads allowed)
			(copperpour not_allowed)
			(footprints allowed)
		)
		(placement
			(enabled no)
			(sheetname "")
		)
		(fill
			(thermal_gap 0.5)
			(thermal_bridge_width 0.5)
			(island_removal_mode 0)
		)
		(polygon
			(pts
				(arc
					(start 13.5001 -19.60499)
					(mid 11.60018 -21.50491)
					(end 9.700006 -19.60499)
				)
				(arc
					(start 9.700006 -19.60499)
					(mid 11.60018 -17.704816)
					(end 13.5001 -19.60499)
				)
			)
		)
	)
	(zone
		(layer "F.Cu")
		(hatch none 0.5)
		(connect_pads
			(clearance 0)
		)
		(min_thickness 0.25)
		(keepout
			(tracks allowed)
			(vias allowed)
			(pads allowed)
			(copperpour allowed)
			(footprints allowed)
		)
		(placement
			(enabled no)
			(sheetname "")
		)
		(fill
			(thermal_gap 0.5)
			(thermal_bridge_width 0.5)
			(island_removal_mode 0)
		)
		(polygon
			(pts
				(xy 72.2757 -60.6044) (xy 70.815708 -60.6044) (xy 70.815708 -58.211212) (xy 72.2757 -58.211212)
			)
		)
	)
	(zone
		(layer "F.Cu")
		(hatch none 0.5)
		(connect_pads
			(clearance 0)
		)
		(min_thickness 0.25)
		(keepout
			(tracks not_allowed)
			(vias allowed)
			(pads allowed)
			(copperpour not_allowed)
			(footprints allowed)
		)
		(placement
			(enabled no)
			(sheetname "")
		)
		(fill
			(thermal_gap 0.5)
			(thermal_bridge_width 0.5)
			(island_removal_mode 0)
		)
		(polygon
			(pts
				(arc
					(start 13.5001 -43.805094)
					(mid 11.60018 -45.705014)
					(end 9.700006 -43.805094)
				)
				(arc
					(start 9.700006 -43.805094)
					(mid 11.60018 -41.90492)
					(end 13.5001 -43.805094)
				)
			)
		)
	)
	(zone
		(net "P3V3_STBY")
		(layer "F.Cu")
		(hatch none 0.5)
		(connect_pads
			(clearance 0.5)
		)
		(min_thickness 0.25)
		(fill yes
			(thermal_gap 0.5)
			(thermal_bridge_width 0.5)
			(island_removal_mode 0)
		)
		(polygon
			(pts
				(xy 60.96 -19.177) (xy 60.579 -19.558) (xy 60.579 -20.574) (xy 60.96 -20.955) (xy 62.484 -20.955)
				(xy 63.246 -21.717) (xy 64.643 -21.717) (xy 67.056 -24.13) (xy 72.39 -24.13) (xy 73.025 -23.495)
				(xy 73.66 -23.495) (xy 74.422 -24.257) (xy 75.311 -24.257) (xy 75.819 -23.749) (xy 75.819 -22.86)
				(xy 75.311 -22.352) (xy 74.295 -22.352) (xy 73.787 -21.844) (xy 71.501 -21.844) (xy 71.12 -21.463)
				(xy 69.596 -21.463) (xy 68.8975 -22.1615) (xy 67.2465 -22.1615) (xy 65.532 -20.447) (xy 63.5 -20.447)
				(xy 62.23 -19.177)
			)
		)
	)
	(zone
		(net "P12V")
		(layer "F.Cu")
		(hatch none 0.5)
		(connect_pads
			(clearance 0.5)
		)
		(min_thickness 0.25)
		(fill yes
			(thermal_gap 0.5)
			(thermal_bridge_width 0.5)
			(island_removal_mode 0)
		)
		(polygon
			(pts
				(xy 15.748 -8.763) (xy 15.494 -9.017) (xy 15.494 -14.859) (xy 15.748 -15.113) (xy 16.764 -15.113)
				(xy 17.907 -13.97) (xy 19.431 -13.97) (xy 19.558 -13.843) (xy 19.558 -11.557) (xy 18.2245 -10.2235)
				(xy 16.5735 -10.2235) (xy 16.383 -10.033) (xy 16.383 -9.144) (xy 16.51 -9.017) (xy 16.51 -8.89)
				(xy 16.383 -8.763)
			)
		)
	)
	(zone
		(net "P1V2_STBY_LDO_OUT1")
		(layer "F.Cu")
		(hatch none 0.5)
		(connect_pads
			(clearance 0.5)
		)
		(min_thickness 0.25)
		(fill yes
			(thermal_gap 0.5)
			(thermal_bridge_width 0.5)
			(island_removal_mode 0)
		)
		(polygon
			(pts
				(xy 176.276 -30.861) (xy 174.117 -33.02) (xy 168.148 -33.02) (xy 168.021 -33.147) (xy 168.021 -35.814)
				(xy 168.148 -35.941) (xy 168.91 -35.941) (xy 169.037 -35.814) (xy 169.037 -35.306) (xy 169.672 -34.671)
				(xy 174.498 -34.671) (xy 175.387 -35.56) (xy 177.165 -35.56) (xy 177.292 -35.433) (xy 177.292 -30.988)
				(xy 177.165 -30.861)
			)
		)
		(polygon
			(pts
				(xy 169.0751 -34.798) (xy 168.8211 -34.798) (xy 168.8211 -35.052) (xy 169.0751 -35.052)
			)
		)
	)
	(zone
		(layer "F.Cu")
		(hatch none 0.5)
		(connect_pads
			(clearance 0)
		)
		(min_thickness 0.25)
		(keepout
			(tracks allowed)
			(vias allowed)
			(pads allowed)
			(copperpour allowed)
			(footprints allowed)
		)
		(placement
			(enabled no)
			(sheetname "")
		)
		(fill
			(thermal_gap 0.5)
			(thermal_bridge_width 0.5)
			(island_removal_mode 0)
		)
		(polygon
			(pts
				(xy 183.896 -21.59) (xy 183.896 -15.621) (xy 187.833 -15.621) (xy 187.833 -21.59)
			)
		)
	)
	(zone
		(layer "F.Cu")
		(hatch none 0.5)
		(connect_pads
			(clearance 0)
		)
		(min_thickness 0.25)
		(keepout
			(tracks allowed)
			(vias allowed)
			(pads allowed)
			(copperpour allowed)
			(footprints allowed)
		)
		(placement
			(enabled no)
			(sheetname "")
		)
		(fill
			(thermal_gap 0.5)
			(thermal_bridge_width 0.5)
			(island_removal_mode 0)
		)
		(polygon
			(pts
				(xy 116.078 -66.04) (xy 116.078 -60.833) (xy 127.635 -60.833) (xy 127.635 -66.04)
			)
		)
	)
	(zone
		(net "P3V3")
		(layer "F.Cu")
		(hatch none 0.5)
		(connect_pads
			(clearance 0.5)
		)
		(min_thickness 0.25)
		(fill yes
			(thermal_gap 0.5)
			(thermal_bridge_width 0.5)
			(island_removal_mode 0)
		)
		(polygon
			(pts
				(xy 12.573 -64.008) (xy 12.446 -64.135) (xy 12.446 -68.707) (xy 12.573 -68.834) (xy 14.224 -68.834)
				(xy 14.351 -68.961) (xy 14.351 -69.469) (xy 14.478 -69.596) (xy 14.859 -69.596) (xy 14.986 -69.469)
				(xy 14.986 -68.961) (xy 15.113 -68.834) (xy 15.621 -68.834) (xy 15.748 -68.707) (xy 15.748 -67.564)
				(xy 14.986 -66.802) (xy 14.986 -65.024) (xy 14.859 -64.897) (xy 14.351 -64.897) (xy 13.462 -64.008)
			)
		)
		(polygon
			(pts
				(xy 14.2748 -68.1228) (xy 14.0208 -68.1228) (xy 14.0208 -68.3768) (xy 14.2748 -68.3768)
			)
		)
		(polygon
			(pts
				(xy 13.7668 -68.1228) (xy 13.5128 -68.1228) (xy 13.5128 -68.3768) (xy 13.7668 -68.3768)
			)
		)
		(polygon
			(pts
				(xy 15.2908 -68.072) (xy 15.0368 -68.072) (xy 15.0368 -68.326) (xy 15.2908 -68.326)
			)
		)
	)
	(zone
		(layer "F.Cu")
		(hatch none 0.5)
		(connect_pads
			(clearance 0)
		)
		(min_thickness 0.25)
		(keepout
			(tracks allowed)
			(vias allowed)
			(pads allowed)
			(copperpour allowed)
			(footprints allowed)
		)
		(placement
			(enabled no)
			(sheetname "")
		)
		(fill
			(thermal_gap 0.5)
			(thermal_bridge_width 0.5)
			(island_removal_mode 0)
		)
		(polygon
			(pts
				(xy 72.3646 -64.477392) (xy 70.971918 -64.477392) (xy 70.971918 -62.744604) (xy 72.3646 -62.744604)
			)
		)
	)
	(zone
		(net "P1V0_STBY")
		(layer "F.Cu")
		(hatch none 0.5)
		(connect_pads
			(clearance 0.5)
		)
		(min_thickness 0.25)
		(fill yes
			(thermal_gap 0.5)
			(thermal_bridge_width 0.5)
			(island_removal_mode 0)
		)
		(polygon
			(pts
				(xy 63.246 -50.292) (xy 62.992 -50.546) (xy 62.992 -50.8) (xy 64.262 -52.07) (xy 64.262 -53.086)
				(xy 64.389 -53.213) (xy 65.532 -53.213) (xy 65.659 -53.086) (xy 65.659 -51.054) (xy 64.897 -50.292)
			)
		)
		(polygon
			(pts
				(xy 65.1891 -51.943) (xy 64.9351 -51.943) (xy 64.9351 -52.197) (xy 65.1891 -52.197)
			)
		)
	)
	(zone
		(layer "F.Cu")
		(hatch none 0.5)
		(connect_pads
			(clearance 0)
		)
		(min_thickness 0.25)
		(keepout
			(tracks not_allowed)
			(vias allowed)
			(pads allowed)
			(copperpour not_allowed)
			(footprints allowed)
		)
		(placement
			(enabled no)
			(sheetname "")
		)
		(fill
			(thermal_gap 0.5)
			(thermal_bridge_width 0.5)
			(island_removal_mode 0)
		)
		(polygon
			(pts
				(arc
					(start 38.65372 -29.337254)
					(mid 38.270307 -28.95346)
					(end 37.88664 -29.337)
				)
				(xy 37.88664 -29.53385) (xy 37.95649 -29.53385)
				(arc
					(start 38.032436 -29.457904)
					(mid 38.45878 -29.1484)
					(end 38.149276 -29.574744)
				)
				(xy 38.07333 -29.65069) (xy 38.02507 -29.69895) (xy 37.95649 -29.69895) (xy 37.88664 -29.69895)
				(xy 37.88664 -29.87675) (xy 37.99459 -29.87675) (xy 38.06317 -29.87675) (xy 38.11143 -29.92501)
				(arc
					(start 38.149276 -29.962856)
					(mid 38.45878 -30.3892)
					(end 38.032436 -30.079696)
				)
				(xy 37.99459 -30.04185) (xy 37.88664 -30.04185)
				(arc
					(start 37.88664 -30.2006)
					(mid 38.27018 -30.58414)
					(end 38.65372 -30.2006)
				)
			)
		)
	)
	(zone
		(layer "F.Cu")
		(hatch none 0.5)
		(connect_pads
			(clearance 0)
		)
		(min_thickness 0.25)
		(keepout
			(tracks not_allowed)
			(vias allowed)
			(pads allowed)
			(copperpour not_allowed)
			(footprints allowed)
		)
		(placement
			(enabled no)
			(sheetname "")
		)
		(fill
			(thermal_gap 0.5)
			(thermal_bridge_width 0.5)
			(island_removal_mode 0)
		)
		(polygon
			(pts
				(arc
					(start 52.30495 -13.730224)
					(mid 52.065637 -14.198899)
					(end 52.13985 -13.6779)
				)
				(arc
					(start 52.13985 -13.56106)
					(mid 51.762621 -13.947775)
					(end 52.1462 -14.32814)
				)
				(arc
					(start 53.009546 -14.32814)
					(mid 53.392258 -13.973384)
					(end 53.06695 -13.565378)
				)
				(arc
					(start 53.06695 -13.683996)
					(mid 53.037041 -14.209974)
					(end 52.90185 -13.70076)
				)
				(xy 52.90185 -13.56106) (xy 52.30495 -13.56106)
			)
		)
	)
	(zone
		(layer "F.Cu")
		(hatch none 0.5)
		(connect_pads
			(clearance 0)
		)
		(min_thickness 0.25)
		(keepout
			(tracks allowed)
			(vias allowed)
			(pads allowed)
			(copperpour allowed)
			(footprints allowed)
		)
		(placement
			(enabled no)
			(sheetname "")
		)
		(fill
			(thermal_gap 0.5)
			(thermal_bridge_width 0.5)
			(island_removal_mode 0)
		)
		(polygon
			(pts
				(xy 140.843 -24.2316) (xy 140.843 -23.622) (xy 141.6304 -23.622) (xy 141.6304 -24.2316)
			)
		)
	)
	(zone
		(layer "F.Cu")
		(hatch none 0.5)
		(connect_pads
			(clearance 0)
		)
		(min_thickness 0.25)
		(keepout
			(tracks allowed)
			(vias allowed)
			(pads allowed)
			(copperpour allowed)
			(footprints allowed)
		)
		(placement
			(enabled no)
			(sheetname "")
		)
		(fill
			(thermal_gap 0.5)
			(thermal_bridge_width 0.5)
			(island_removal_mode 0)
		)
		(polygon
			(pts
				(xy 7.874 -39.751) (xy 7.874 -36.449) (xy 7.493 -36.068) (xy 7.493 -32.512) (xy 7.874 -32.131) (xy 14.859 -32.131)
				(xy 14.859 -39.751)
			)
		)
	)
	(zone
		(net "P1V0_VIN")
		(layer "F.Cu")
		(hatch none 0.5)
		(connect_pads
			(clearance 0.5)
		)
		(min_thickness 0.25)
		(fill yes
			(thermal_gap 0.5)
			(thermal_bridge_width 0.5)
			(island_removal_mode 0)
		)
		(polygon
			(pts
				(xy 4.572 -25.654) (xy 4.318 -25.908) (xy 4.318 -28.321) (xy 4.572 -28.575) (xy 9.271 -28.575) (xy 9.525 -28.829)
				(xy 11.684 -28.829) (xy 12.065 -28.448) (xy 12.065 -25.781) (xy 11.938 -25.654)
			)
		)
		(polygon
			(pts
				(xy 10.6172 -27.8003) (xy 10.3632 -27.8003) (xy 10.3632 -28.0543) (xy 10.6172 -28.0543)
			)
		)
		(polygon
			(pts
				(xy 9.6012 -27.8003) (xy 9.3472 -27.8003) (xy 9.3472 -28.0543) (xy 9.6012 -28.0543)
			)
		)
		(polygon
			(pts
				(xy 7.2644 -26.4541) (xy 7.0104 -26.4541) (xy 7.0104 -26.7081) (xy 7.2644 -26.7081)
			)
		)
		(polygon
			(pts
				(xy 6.2484 -26.4541) (xy 5.9944 -26.4541) (xy 5.9944 -26.7081) (xy 6.2484 -26.7081)
			)
		)
	)
	(zone
		(net "P3V3_STBY_LL")
		(layer "F.Cu")
		(hatch none 0.5)
		(connect_pads
			(clearance 0.5)
		)
		(min_thickness 0.25)
		(fill yes
			(thermal_gap 0.5)
			(thermal_bridge_width 0.5)
			(island_removal_mode 0)
		)
		(polygon
			(pts
				(xy 17.018 -34.671) (xy 16.891 -34.798) (xy 16.891 -35.814) (xy 16.51 -36.195) (xy 13.081 -36.195)
				(xy 12.954 -36.322) (xy 12.954 -39.624) (xy 15.621 -42.291) (xy 17.399 -42.291) (xy 17.78 -42.672)
				(xy 17.78 -43.561) (xy 17.907 -43.688) (xy 18.669 -43.688) (xy 18.796 -43.561) (xy 18.796 -42.291)
				(xy 17.78 -41.275) (xy 17.78 -36.703) (xy 18.796 -35.687) (xy 18.796 -35.052) (xy 18.669 -34.925)
				(xy 18.034 -34.925) (xy 17.78 -34.671)
			)
		)
		(polygon
			(pts
				(xy 18.1102 -35.4711) (xy 17.8562 -35.4711) (xy 17.8562 -35.7251) (xy 18.1102 -35.7251) (xy 18.1356 -35.7378)
				(xy 18.3896 -35.7378) (xy 18.3896 -35.4838) (xy 18.1356 -35.4838)
			)
		)
	)
	(zone
		(net "GND")
		(layer "F.Cu")
		(hatch none 0.5)
		(connect_pads
			(clearance 0.5)
		)
		(min_thickness 0.25)
		(fill yes
			(thermal_gap 0.5)
			(thermal_bridge_width 0.5)
			(island_removal_mode 0)
		)
		(polygon
			(pts
				(xy 84.201 -13.716) (xy 83.566 -14.351) (xy 81.788 -14.351) (xy 81.661 -14.478) (xy 81.661 -14.732)
				(xy 81.28 -15.113) (xy 79.756 -15.113) (xy 79.375 -14.732) (xy 79.375 -14.478) (xy 79.248 -14.351)
				(xy 78.994 -14.351) (xy 78.867 -14.478) (xy 78.867 -14.732) (xy 78.486 -15.113) (xy 77.089 -15.113)
				(xy 76.835 -14.859) (xy 76.581 -14.859) (xy 74.803 -16.637) (xy 74.803 -16.764) (xy 75.311 -17.272)
				(xy 78.994 -17.272) (xy 80.264 -18.542) (xy 83.693 -18.542) (xy 83.947 -18.288) (xy 83.947 -16.129)
				(xy 85.217 -14.859) (xy 89.535 -14.859) (xy 90.17 -15.494) (xy 96.901 -15.494) (xy 97.409 -14.986)
				(xy 97.409 -14.351) (xy 97.282 -14.224) (xy 96.774 -14.224) (xy 96.647 -14.351) (xy 90.805 -14.351)
				(xy 90.17 -13.716)
			)
		)
		(polygon
			(pts
				(xy 97.028 -14.6812) (xy 96.774 -14.6812) (xy 96.774 -14.9352) (xy 97.028 -14.9352)
			)
		)
	)
	(zone
		(net "GND")
		(layer "F.Cu")
		(hatch none 0.5)
		(connect_pads
			(clearance 0.5)
		)
		(min_thickness 0.25)
		(fill yes
			(thermal_gap 0.5)
			(thermal_bridge_width 0.5)
			(island_removal_mode 0)
		)
		(polygon
			(pts
				(xy 19.304 -43.561) (xy 18.669 -44.196) (xy 18.669 -47.752) (xy 18.796 -47.879) (xy 19.685 -47.879)
				(xy 19.812 -47.752) (xy 19.812 -47.244) (xy 20.32 -46.736) (xy 32.512 -46.736) (xy 32.766 -46.482)
				(xy 32.766 -43.815) (xy 32.512 -43.561)
			)
		)
		(polygon
			(pts
				(xy 24.003 -44.2341) (xy 23.749 -44.2341) (xy 23.749 -44.4881) (xy 24.003 -44.4881)
			)
		)
		(polygon
			(pts
				(xy 22.987 -44.2341) (xy 22.733 -44.2341) (xy 22.733 -44.4881) (xy 22.987 -44.4881)
			)
		)
		(polygon
			(pts
				(xy 24.892 -43.7896) (xy 24.638 -43.7896) (xy 24.638 -44.0436) (xy 24.892 -44.0436)
			)
		)
		(polygon
			(pts
				(xy 24.384 -43.7896) (xy 24.13 -43.7896) (xy 24.13 -44.0436) (xy 24.384 -44.0436)
			)
		)
	)
	(zone
		(layer "F.Cu")
		(hatch none 0.5)
		(connect_pads
			(clearance 0)
		)
		(min_thickness 0.25)
		(keepout
			(tracks not_allowed)
			(vias allowed)
			(pads allowed)
			(copperpour not_allowed)
			(footprints allowed)
		)
		(placement
			(enabled no)
			(sheetname "")
		)
		(fill
			(thermal_gap 0.5)
			(thermal_bridge_width 0.5)
			(island_removal_mode 0)
		)
		(polygon
			(pts
				(arc
					(start 10.009886 -62.727078)
					(mid 9.662664 -62.356258)
					(end 9.25195 -62.65545)
				)
				(arc
					(start 9.373108 -62.65545)
					(mid 9.893195 -62.738)
					(end 9.373108 -62.82055)
				)
				(xy 9.242806 -62.82055) (xy 9.263634 -63.54445)
				(arc
					(start 9.398508 -63.54445)
					(mid 9.918595 -63.627)
					(end 9.398508 -63.70955)
				)
				(arc
					(start 9.27735 -63.70955)
					(mid 9.698947 -64.007753)
					(end 10.035286 -63.616078)
				)
				(xy 10.037826 -63.616078) (xy 10.012426 -62.727078)
			)
		)
	)
	(zone
		(net "GND")
		(layer "F.Cu")
		(hatch none 0.5)
		(connect_pads
			(clearance 0.5)
		)
		(min_thickness 0.25)
		(fill yes
			(thermal_gap 0.5)
			(thermal_bridge_width 0.5)
			(island_removal_mode 0)
		)
		(polygon
			(pts
				(xy 10.668 -31.75) (xy 10.033 -32.385) (xy 10.033 -33.02) (xy 9.398 -33.655) (xy 9.398 -39.37) (xy 9.652 -39.624)
				(xy 9.652 -41.275) (xy 9.017 -41.91) (xy 6.604 -41.91) (xy 6.477 -42.037) (xy 6.477 -43.18) (xy 6.731 -43.434)
				(xy 7.366 -43.434) (xy 7.62 -43.688) (xy 7.62 -45.212) (xy 7.747 -45.339) (xy 8.382 -45.339) (xy 9.525 -46.482)
				(xy 9.525 -46.99) (xy 9.652 -47.117) (xy 13.462 -47.117) (xy 16.002 -44.577) (xy 16.002 -42.926)
				(xy 15.875 -42.799) (xy 15.621 -42.799) (xy 12.7 -39.878) (xy 12.7 -33.782) (xy 11.303 -32.385)
				(xy 11.303 -31.877) (xy 11.176 -31.75)
			)
		)
		(polygon
			(pts
				(xy 10.287 -46.355) (xy 10.033 -46.355) (xy 10.033 -46.609) (xy 10.287 -46.609)
			)
		)
		(polygon
			(pts
				(xy 10.2616 -40.259) (xy 10.0076 -40.259) (xy 10.0076 -40.513) (xy 10.2616 -40.513)
			)
		)
		(polygon
			(pts
				(xy 10.2616 -39.751) (xy 10.0076 -39.751) (xy 10.0076 -40.005) (xy 10.2616 -40.005)
			)
		)
	)
	(zone
		(net "GND")
		(layer "F.Cu")
		(hatch none 0.5)
		(connect_pads
			(clearance 0.5)
		)
		(min_thickness 0.25)
		(fill yes
			(thermal_gap 0.5)
			(thermal_bridge_width 0.5)
			(island_removal_mode 0)
		)
		(polygon
			(pts
				(xy 118.236746 -0.762254) (xy 118.11 -0.889) (xy 118.11 -1.143) (xy 118.491 -1.524) (xy 119.126 -1.524)
				(xy 120.523 -2.921) (xy 126.619 -2.921) (xy 127 -2.54) (xy 127 -1.143254) (xy 126.619 -0.762254)
			)
		)
	)
	(zone
		(net "GND")
		(layer "F.Cu")
		(hatch none 0.5)
		(connect_pads
			(clearance 0.5)
		)
		(min_thickness 0.25)
		(fill yes
			(thermal_gap 0.5)
			(thermal_bridge_width 0.5)
			(island_removal_mode 0)
		)
		(polygon
			(pts
				(xy 94.7166 -47.1424) (xy 94.361 -47.498) (xy 94.361 -48.641) (xy 92.964 -50.038) (xy 92.964 -50.546)
				(xy 93.345 -50.927) (xy 93.345 -51.435) (xy 93.599 -51.689) (xy 93.599 -52.197) (xy 94.107 -52.705)
				(xy 94.361 -52.705) (xy 94.488 -52.578) (xy 94.488 -51.943) (xy 94.234 -51.689) (xy 94.234 -51.308)
				(xy 94.869 -50.673) (xy 94.869 -50.165) (xy 94.996 -50.038) (xy 95.377 -50.038) (xy 95.5548 -50.2158)
				(xy 95.5548 -50.7746) (xy 95.6564 -50.8762) (xy 95.8342 -50.8762) (xy 95.9358 -50.7746) (xy 95.9358 -50.2158)
				(xy 96.0882 -50.0634) (xy 96.3676 -50.0634) (xy 96.4946 -50.1904) (xy 96.4946 -50.6476) (xy 97.282 -51.435)
				(xy 97.282 -52.197) (xy 97.1042 -52.3748) (xy 97.1042 -52.7812) (xy 97.536 -53.213) (xy 97.79 -53.213)
				(xy 97.917 -53.086) (xy 97.917 -51.181) (xy 98.298 -50.8) (xy 99.187 -50.8) (xy 99.314 -50.673)
				(xy 99.822 -50.673) (xy 100.076 -50.927) (xy 100.457 -50.927) (xy 100.711 -50.673) (xy 101.092 -50.673)
				(xy 101.219 -50.8) (xy 101.219 -52.197) (xy 101.0412 -52.3748) (xy 101.0412 -52.8574) (xy 101.6508 -53.467)
				(xy 101.854 -53.467) (xy 102.108 -53.213) (xy 102.108 -52.324) (xy 101.727 -51.943) (xy 101.727 -51.054)
				(xy 101.981 -50.8) (xy 102.235 -50.8) (xy 102.743 -51.308) (xy 103.124 -51.308) (xy 103.886 -50.546)
				(xy 104.775 -50.546) (xy 105.029 -50.8) (xy 105.029 -51.054) (xy 105.156 -51.181) (xy 105.537 -51.181)
				(xy 105.664 -51.054) (xy 105.664 -50.165) (xy 105.283 -49.784) (xy 98.171 -49.784) (xy 97.79 -50.165)
				(xy 96.9518 -50.165) (xy 96.393 -49.6062) (xy 96.393 -47.4472) (xy 96.0882 -47.1424)
			)
		)
	)
	(zone
		(net "PV_VDDR")
		(layer "F.Cu")
		(hatch none 0.5)
		(connect_pads
			(clearance 0.5)
		)
		(min_thickness 0.25)
		(fill yes
			(thermal_gap 0.5)
			(thermal_bridge_width 0.5)
			(island_removal_mode 0)
		)
		(polygon
			(pts
				(xy 147.32 -59.436) (xy 147.066 -59.69) (xy 147.066 -60.6298) (xy 148.2852 -61.849) (xy 148.2852 -63.4492)
				(xy 148.3106 -63.4746) (xy 148.59 -63.4746) (xy 148.6154 -63.4492) (xy 148.6154 -61.6204) (xy 148.7678 -61.468)
				(xy 150.5712 -61.468) (xy 150.6728 -61.5696) (xy 150.6728 -63.4746) (xy 150.7236 -63.5254) (xy 150.9522 -63.5254)
				(xy 151.0284 -63.4492) (xy 151.0284 -61.595) (xy 151.1554 -61.468) (xy 153.0096 -61.468) (xy 153.0858 -61.5442)
				(xy 153.0858 -63.4492) (xy 153.1112 -63.4746) (xy 153.3652 -63.4746) (xy 153.416 -63.4238) (xy 153.416 -61.5442)
				(xy 153.4922 -61.468) (xy 154.7368 -61.468) (xy 154.8892 -61.6204) (xy 154.8892 -63.4238) (xy 154.9654 -63.5)
				(xy 155.1178 -63.5) (xy 155.194 -63.4238) (xy 155.194 -61.6458) (xy 155.3718 -61.468) (xy 157.1752 -61.468)
				(xy 157.2768 -61.5696) (xy 157.2768 -63.4238) (xy 157.353 -63.5) (xy 157.5308 -63.5) (xy 157.607 -63.4238)
				(xy 157.607 -61.6204) (xy 157.734 -61.4934) (xy 159.4866 -61.4934) (xy 159.6898 -61.6966) (xy 159.6898 -63.3984)
				(xy 159.766 -63.4746) (xy 159.9438 -63.4746) (xy 160.02 -63.3984) (xy 160.02 -61.6966) (xy 160.2232 -61.4934)
				(xy 161.798 -61.4934) (xy 162.0774 -61.7728) (xy 162.0774 -63.4238) (xy 162.1536 -63.5) (xy 162.3314 -63.5)
				(xy 162.4076 -63.4238) (xy 162.4076 -61.595) (xy 162.814 -61.1886) (xy 162.814 -59.563) (xy 162.687 -59.436)
			)
		)
		(polygon
			(pts
				(xy 153.3652 -60.1091) (xy 153.1112 -60.1091) (xy 153.1112 -60.3631) (xy 153.3652 -60.3631)
			)
		)
		(polygon
			(pts
				(xy 157.734 -59.7916) (xy 157.48 -59.7916) (xy 157.48 -60.0456) (xy 157.734 -60.0456)
			)
		)
		(polygon
			(pts
				(xy 157.226 -59.7916) (xy 156.972 -59.7916) (xy 156.972 -60.0456) (xy 157.226 -60.0456)
			)
		)
		(polygon
			(pts
				(xy 155.956 -59.7916) (xy 155.702 -59.7916) (xy 155.702 -60.0456) (xy 155.956 -60.0456)
			)
		)
		(polygon
			(pts
				(xy 155.448 -59.7916) (xy 154.9146 -59.7916) (xy 154.9146 -60.0456) (xy 155.448 -60.0456)
			)
		)
		(polygon
			(pts
				(xy 154.6606 -59.7916) (xy 154.4066 -59.7916) (xy 154.1272 -60.1091) (xy 154.1272 -60.3631) (xy 154.3812 -60.3631)
				(xy 154.6606 -60.0456)
			)
		)
		(polygon
			(pts
				(xy 152.146 -59.7916) (xy 151.892 -59.7916) (xy 151.892 -60.0456) (xy 152.146 -60.0456)
			)
		)
		(polygon
			(pts
				(xy 151.638 -59.7916) (xy 151.384 -59.7916) (xy 151.384 -60.0456) (xy 151.638 -60.0456)
			)
		)
	)
	(zone
		(layer "F.Cu")
		(hatch none 0.5)
		(connect_pads
			(clearance 0)
		)
		(min_thickness 0.25)
		(keepout
			(tracks not_allowed)
			(vias allowed)
			(pads allowed)
			(copperpour not_allowed)
			(footprints allowed)
		)
		(placement
			(enabled no)
			(sheetname "")
		)
		(fill
			(thermal_gap 0.5)
			(thermal_bridge_width 0.5)
			(island_removal_mode 0)
		)
		(polygon
			(pts
				(arc
					(start 67.34556 -9.90092)
					(mid 66.96202 -10.28446)
					(end 67.34556 -10.668)
				)
				(arc
					(start 68.302886 -10.668)
					(mid 68.68668 -10.284587)
					(end 68.30314 -9.90092)
				)
				(xy 68.07835 -9.90092) (xy 68.07835 -9.94283)
				(arc
					(start 68.182236 -10.046716)
					(mid 68.49174 -10.47306)
					(end 68.065396 -10.163556)
				)
				(xy 67.96151 -10.05967) (xy 67.91325 -10.01141) (xy 67.91325 -9.94283) (xy 67.91325 -9.90092) (xy 67.73545 -9.90092)
				(xy 67.73545 -9.94283) (xy 67.73545 -10.01141) (xy 67.68719 -10.05967)
				(arc
					(start 67.583304 -10.163556)
					(mid 67.15696 -10.47306)
					(end 67.466464 -10.046716)
				)
				(xy 67.57035 -9.94283) (xy 67.57035 -9.90092)
			)
		)
	)
	(zone
		(net "VR_PVDDR_A_VSW")
		(layer "F.Cu")
		(hatch none 0.5)
		(connect_pads
			(clearance 0.5)
		)
		(min_thickness 0.25)
		(fill yes
			(thermal_gap 0.5)
			(thermal_bridge_width 0.5)
			(island_removal_mode 0)
		)
		(polygon
			(pts
				(xy 200.279 -38.735) (xy 200.152 -38.862) (xy 200.152 -40.386) (xy 199.009 -41.529) (xy 199.009 -44.704)
				(xy 199.517 -45.212) (xy 204.47 -45.212) (xy 205.1685 -44.5135) (xy 205.1685 -39.8145) (xy 204.089 -38.735)
			)
		)
	)
	(zone
		(net "P12V")
		(layer "F.Cu")
		(hatch none 0.5)
		(connect_pads
			(clearance 0.5)
		)
		(min_thickness 0.25)
		(fill yes
			(thermal_gap 0.5)
			(thermal_bridge_width 0.5)
			(island_removal_mode 0)
		)
		(polygon
			(pts
				(xy 96.266 -9.271) (xy 96.012 -9.525) (xy 96.012 -9.906) (xy 95.631 -10.287) (xy 94.234 -10.287)
				(xy 93.98 -10.541) (xy 93.98 -13.462) (xy 94.234 -13.716) (xy 96.393 -13.716) (xy 96.52 -13.589)
				(xy 96.52 -12.827) (xy 97.79 -11.557) (xy 97.79 -9.525) (xy 97.536 -9.271)
			)
		)
	)
	(zone
		(layer "F.Cu")
		(hatch none 0.5)
		(connect_pads
			(clearance 0)
		)
		(min_thickness 0.25)
		(keepout
			(tracks allowed)
			(vias allowed)
			(pads allowed)
			(copperpour allowed)
			(footprints allowed)
		)
		(placement
			(enabled no)
			(sheetname "")
		)
		(fill
			(thermal_gap 0.5)
			(thermal_bridge_width 0.5)
			(island_removal_mode 0)
		)
		(polygon
			(pts
				(xy 35.6362 -24.638) (xy 35.6362 -19.685) (xy 36.6014 -19.685) (xy 36.6014 -24.638)
			)
		)
	)
	(zone
		(layer "F.Cu")
		(hatch none 0.5)
		(connect_pads
			(clearance 0)
		)
		(min_thickness 0.25)
		(keepout
			(tracks not_allowed)
			(vias allowed)
			(pads allowed)
			(copperpour not_allowed)
			(footprints allowed)
		)
		(placement
			(enabled no)
			(sheetname "")
		)
		(fill
			(thermal_gap 0.5)
			(thermal_bridge_width 0.5)
			(island_removal_mode 0)
		)
		(polygon
			(pts
				(arc
					(start 49.389284 -9.87679)
					(mid 49.00549 -10.260203)
					(end 49.38903 -10.64387)
				)
				(xy 49.5808 -10.64387) (xy 49.5808 -10.56894)
				(arc
					(start 49.509934 -10.498074)
					(mid 49.20043 -10.07173)
					(end 49.626774 -10.381234)
				)
				(xy 49.69764 -10.4521) (xy 49.7459 -10.50036) (xy 49.7459 -10.56894) (xy 49.7459 -10.64387) (xy 49.9237 -10.64387)
				(xy 49.9237 -10.598912) (xy 49.9237 -10.530332) (xy 49.97196 -10.482072)
				(arc
					(start 50.072798 -10.381234)
					(mid 50.499142 -10.07173)
					(end 50.189638 -10.498074)
				)
				(xy 50.0888 -10.598912) (xy 50.0888 -10.64387)
				(arc
					(start 50.310542 -10.64387)
					(mid 50.694082 -10.26033)
					(end 50.310542 -9.87679)
				)
			)
		)
	)
	(zone
		(layer "F.Cu")
		(hatch none 0.5)
		(connect_pads
			(clearance 0)
		)
		(min_thickness 0.25)
		(keepout
			(tracks allowed)
			(vias allowed)
			(pads allowed)
			(copperpour allowed)
			(footprints allowed)
		)
		(placement
			(enabled no)
			(sheetname "")
		)
		(fill
			(thermal_gap 0.5)
			(thermal_bridge_width 0.5)
			(island_removal_mode 0)
		)
		(polygon
			(pts
				(xy 185.166 -38.227) (xy 185.166 -30.099) (xy 193.167 -30.099) (xy 193.167 -38.227)
			)
		)
	)
	(zone
		(layer "F.Cu")
		(hatch none 0.5)
		(connect_pads
			(clearance 0)
		)
		(min_thickness 0.25)
		(keepout
			(tracks allowed)
			(vias allowed)
			(pads allowed)
			(copperpour allowed)
			(footprints not_allowed)
		)
		(placement
			(enabled no)
			(sheetname "")
		)
		(fill
			(thermal_gap 0.5)
			(thermal_bridge_width 0.5)
			(island_removal_mode 0)
		)
		(polygon
			(pts
				(xy 14.699996 -11.619992) (xy 14.699996 -69.600064) (xy 20.699984 -69.600064) (xy 20.699984 -11.619992)
			)
		)
	)
	(zone
		(net "P2V5_STBY_OUT")
		(layer "F.Cu")
		(hatch none 0.5)
		(connect_pads
			(clearance 0.5)
		)
		(min_thickness 0.25)
		(fill yes
			(thermal_gap 0.5)
			(thermal_bridge_width 0.5)
			(island_removal_mode 0)
		)
		(polygon
			(pts
				(xy 170.053 -38.354) (xy 169.926 -38.481) (xy 169.926 -39.497) (xy 170.053 -39.624) (xy 170.053 -41.148)
				(xy 170.18 -41.275) (xy 170.942 -41.275) (xy 171.196 -41.529) (xy 172.085 -41.529) (xy 172.212 -41.402)
				(xy 172.212 -40.767) (xy 172.085 -40.64) (xy 172.085 -38.862) (xy 171.577 -38.354)
			)
		)
		(polygon
			(pts
				(xy 170.7642 -40.259) (xy 170.5102 -40.259) (xy 170.5102 -40.513) (xy 170.4086 -40.513) (xy 170.4086 -40.767)
				(xy 170.6626 -40.767) (xy 170.6626 -40.513) (xy 170.7642 -40.513)
			)
		)
		(polygon
			(pts
				(xy 171.2849 -40.132) (xy 171.0309 -40.132) (xy 171.0309 -40.386) (xy 171.2849 -40.386)
			)
		)
		(polygon
			(pts
				(xy 170.8531 -39.37) (xy 170.5991 -39.37) (xy 170.5991 -39.624) (xy 170.5102 -39.751) (xy 170.5102 -40.005)
				(xy 170.7642 -40.005) (xy 170.7642 -39.751) (xy 170.8531 -39.624)
			)
		)
		(polygon
			(pts
				(xy 171.2849 -39.116) (xy 171.0309 -39.116) (xy 171.0309 -39.37) (xy 171.2849 -39.37)
			)
		)
	)
	(zone
		(layer "F.Cu")
		(hatch none 0.5)
		(connect_pads
			(clearance 0)
		)
		(min_thickness 0.25)
		(keepout
			(tracks not_allowed)
			(vias allowed)
			(pads allowed)
			(copperpour not_allowed)
			(footprints allowed)
		)
		(placement
			(enabled no)
			(sheetname "")
		)
		(fill
			(thermal_gap 0.5)
			(thermal_bridge_width 0.5)
			(island_removal_mode 0)
		)
		(polygon
			(pts
				(arc
					(start 77.849984 -71.799958)
					(mid 75.849988 -73.799954)
					(end 73.849992 -71.799958)
				)
				(arc
					(start 73.849992 -71.799958)
					(mid 75.849988 -69.799962)
					(end 77.849984 -71.799958)
				)
			)
		)
	)
	(zone
		(net "GND")
		(layer "F.Cu")
		(hatch none 0.5)
		(connect_pads
			(clearance 0.5)
		)
		(min_thickness 0.25)
		(fill yes
			(thermal_gap 0.5)
			(thermal_bridge_width 0.5)
			(island_removal_mode 0)
		)
		(polygon
			(pts
				(xy 1.143254 -49.911) (xy 0.762254 -50.292) (xy 0.762254 -59.563254) (xy 0.762 -59.563508) (xy 0.762 -72.771)
				(xy 1.016 -73.025) (xy 21.971 -73.025) (xy 22.225 -72.771) (xy 22.225 -71.247) (xy 23.622 -69.85)
				(xy 23.622 -68.453) (xy 23.495 -68.326) (xy 21.844 -68.326) (xy 21.717 -68.453) (xy 21.717 -69.215)
				(xy 21.082 -69.85) (xy 18.923 -69.85) (xy 17.78 -68.707) (xy 17.78 -68.072) (xy 18.161 -67.691)
				(xy 18.161 -67.437) (xy 18.034 -67.31) (xy 17.399 -67.31) (xy 17.145 -67.056) (xy 17.145 -65.278)
				(xy 17.399 -65.024) (xy 17.399 -64.135) (xy 17.272 -64.008) (xy 16.256 -64.008) (xy 16.129 -64.135)
				(xy 16.129 -64.77) (xy 16.002 -64.897) (xy 15.367 -64.897) (xy 15.24 -65.024) (xy 15.24 -66.675)
				(xy 16.764 -68.199) (xy 16.764 -68.961) (xy 17.526 -69.723) (xy 17.526 -70.104) (xy 17.272 -70.358)
				(xy 14.732 -70.358) (xy 14.097 -69.723) (xy 14.097 -69.088) (xy 13.97 -68.961) (xy 12.319 -68.961)
				(xy 12.065 -68.707) (xy 12.065 -64.262) (xy 11.811 -64.008) (xy 10.795 -64.008) (xy 10.541 -63.754)
				(xy 10.287 -63.754) (xy 10.16 -63.881) (xy 10.16 -65.786) (xy 9.906 -66.04) (xy 6.604 -66.04) (xy 4.953 -67.691)
				(xy 4.953 -68.58) (xy 4.572 -68.961) (xy 4.064 -68.961) (xy 3.683 -68.58) (xy 3.683 -67.818) (xy 3.429 -67.564)
				(xy 2.413 -67.564) (xy 2.286 -67.691) (xy 1.778 -67.691) (xy 1.524 -67.437) (xy 1.524 -65.913) (xy 1.651 -65.786)
				(xy 2.286 -65.786) (xy 2.413 -65.913) (xy 2.794 -65.913) (xy 2.921 -65.786) (xy 2.921 -64.643) (xy 2.794 -64.516)
				(xy 2.413 -64.516) (xy 2.286 -64.643) (xy 1.651 -64.643) (xy 1.524 -64.516) (xy 1.524 -62.865) (xy 1.651 -62.738)
				(xy 2.159 -62.738) (xy 2.413 -62.992) (xy 2.667 -62.992) (xy 2.921 -62.738) (xy 2.921 -61.595) (xy 2.794 -61.468)
				(xy 2.413 -61.468) (xy 2.286 -61.595) (xy 1.651 -61.595) (xy 1.524 -61.468) (xy 1.524 -59.817) (xy 1.651 -59.69)
				(xy 2.54 -59.69) (xy 2.794 -59.436) (xy 2.794 -58.42) (xy 3.429 -57.785) (xy 4.572 -57.785) (xy 7.239 -55.118)
				(xy 9.779 -55.118) (xy 10.16 -55.499) (xy 10.16 -57.15) (xy 10.287 -57.277) (xy 10.668 -57.277)
				(xy 12.446 -55.499) (xy 12.446 -54.864) (xy 12.192 -54.61) (xy 8.636 -54.61) (xy 8.382 -54.356)
				(xy 8.382 -52.705) (xy 8.0645 -52.3875) (xy 6.2865 -52.3875) (xy 5.588 -53.086) (xy 5.588 -53.467)
				(xy 5.334 -53.721) (xy 4.572 -53.721) (xy 3.937 -53.086) (xy 3.937 -50.165) (xy 3.683 -49.911)
			)
		)
		(polygon
			(pts
				(xy 13.7668 -69.342) (xy 13.5128 -69.342) (xy 13.5128 -69.596) (xy 13.7668 -69.596)
			)
		)
		(polygon
			(pts
				(xy 16.9926 -64.3128) (xy 16.7386 -64.3128) (xy 16.4846 -64.4906) (xy 16.4846 -64.7446) (xy 16.7386 -64.7446)
				(xy 16.9926 -64.5668)
			)
		)
		(polygon
			(pts
				(xy 12.0904 -55.372) (xy 11.8364 -55.372) (xy 11.8364 -55.626) (xy 12.0904 -55.626)
			)
		)
		(polygon
			(pts
				(xy 12.0904 -54.864) (xy 11.8364 -54.864) (xy 11.8364 -55.118) (xy 12.0904 -55.118)
			)
		)
		(polygon
			(pts
				(xy 6.604 -53.4924) (xy 6.35 -53.4924) (xy 6.35 -53.7464) (xy 6.604 -53.7464)
			)
		)
	)
	(zone
		(layer "F.Cu")
		(hatch none 0.5)
		(connect_pads
			(clearance 0)
		)
		(min_thickness 0.25)
		(keepout
			(tracks allowed)
			(vias allowed)
			(pads allowed)
			(copperpour allowed)
			(footprints not_allowed)
		)
		(placement
			(enabled no)
			(sheetname "")
		)
		(fill
			(thermal_gap 0.5)
			(thermal_bridge_width 0.5)
			(island_removal_mode 0)
		)
		(polygon
			(pts
				(xy 126.000002 -36.139882) (xy 126.000002 -9.240012) (xy 160.154874 -9.240012) (xy 160.154874 -19.899884)
				(xy 158.83001 -19.899884) (xy 158.83001 -31.170118) (xy 161.980118 -31.170118) (xy 161.980118 -19.899884)
				(xy 160.655 -19.899884) (xy 160.655 -9.240012) (xy 194.00012 -9.240012) (xy 194.00012 -36.139882)
				(xy 192.499996 -36.139882) (xy 192.499996 -63.799974) (xy 137.279888 -63.799974) (xy 137.279888 -51.660044)
				(xy 139.809982 -51.660044) (xy 139.809982 -47.649892) (xy 134.249922 -47.649892) (xy 134.249922 -51.660044)
				(xy 136.780016 -51.660044) (xy 136.780016 -63.799974) (xy 124.499878 -63.799974) (xy 124.499878 -36.139882)
			)
		)
	)
	(zone
		(layer "F.Cu")
		(hatch none 0.5)
		(connect_pads
			(clearance 0)
		)
		(min_thickness 0.25)
		(keepout
			(tracks not_allowed)
			(vias allowed)
			(pads allowed)
			(copperpour not_allowed)
			(footprints allowed)
		)
		(placement
			(enabled no)
			(sheetname "")
		)
		(fill
			(thermal_gap 0.5)
			(thermal_bridge_width 0.5)
			(island_removal_mode 0)
		)
		(polygon
			(pts
				(arc
					(start 10.009886 -59.171078)
					(mid 9.662664 -58.800258)
					(end 9.25195 -59.09945)
				)
				(arc
					(start 9.373108 -59.09945)
					(mid 9.893195 -59.182)
					(end 9.373108 -59.26455)
				)
				(xy 9.242806 -59.26455) (xy 9.263634 -59.98845)
				(arc
					(start 9.398508 -59.98845)
					(mid 9.918595 -60.071)
					(end 9.398508 -60.15355)
				)
				(arc
					(start 9.27735 -60.15355)
					(mid 9.698947 -60.451753)
					(end 10.035286 -60.060078)
				)
				(xy 10.037826 -60.060078) (xy 10.012426 -59.171078)
			)
		)
	)
	(zone
		(net "P3V3_STBY")
		(layer "F.Cu")
		(hatch none 0.5)
		(connect_pads
			(clearance 0.5)
		)
		(min_thickness 0.25)
		(fill yes
			(thermal_gap 0.5)
			(thermal_bridge_width 0.5)
			(island_removal_mode 0)
		)
		(polygon
			(pts
				(xy 28.702 -36.83) (xy 28.321 -37.211) (xy 28.321 -40.513) (xy 28.702 -40.894) (xy 28.702 -42.926)
				(xy 28.829 -43.053) (xy 31.2928 -43.053) (xy 31.4198 -42.926) (xy 31.4198 -40.259) (xy 30.8864 -39.7256)
				(xy 30.8864 -37.3634) (xy 30.353 -36.83)
			)
		)
	)
	(zone
		(net "P3V3_STBY")
		(layer "F.Cu")
		(hatch none 0.5)
		(connect_pads
			(clearance 0.5)
		)
		(min_thickness 0.25)
		(fill yes
			(thermal_gap 0.5)
			(thermal_bridge_width 0.5)
			(island_removal_mode 0)
		)
		(polygon
			(pts
				(xy 157.988 -51.562) (xy 157.353 -52.197) (xy 157.353 -53.34) (xy 158.496 -54.483) (xy 159.893 -54.483)
				(xy 160.02 -54.356) (xy 160.02 -52.07) (xy 159.639 -51.689) (xy 158.496 -51.689) (xy 158.369 -51.562)
			)
		)
		(polygon
			(pts
				(xy 157.9626 -52.959) (xy 157.7086 -52.959) (xy 157.7086 -53.213) (xy 157.9626 -53.213)
			)
		)
		(polygon
			(pts
				(xy 157.9626 -52.451) (xy 157.7086 -52.451) (xy 157.7086 -52.705) (xy 157.9626 -52.705)
			)
		)
	)
	(zone
		(layer "F.Cu")
		(hatch none 0.5)
		(connect_pads
			(clearance 0)
		)
		(min_thickness 0.25)
		(keepout
			(tracks not_allowed)
			(vias allowed)
			(pads allowed)
			(copperpour not_allowed)
			(footprints allowed)
		)
		(placement
			(enabled no)
			(sheetname "")
		)
		(fill
			(thermal_gap 0.5)
			(thermal_bridge_width 0.5)
			(island_removal_mode 0)
		)
		(polygon
			(pts
				(arc
					(start 87.528908 -54.284118)
					(mid 87.190326 -53.93182)
					(end 86.838028 -54.270402)
				)
				(arc
					(start 86.826852 -54.834028)
					(mid 87.165307 -55.186583)
					(end 87.517732 -54.847998)
				)
				(xy 87.520018 -54.737)
				(arc
					(start 87.375746 -54.737)
					(mid 87.008167 -55.000205)
					(end 87.282782 -54.640988)
				)
				(xy 87.313516 -54.61) (xy 87.366348 -54.61) (xy 87.522558 -54.61) (xy 87.524082 -54.5338) (xy 87.402924 -54.5338)
				(xy 87.350092 -54.5338) (xy 87.313008 -54.496716)
				(arc
					(start 87.293958 -54.477412)
					(mid 87.021807 -54.115599)
					(end 87.38362 -54.38775)
				)
				(xy 87.402924 -54.4068) (xy 87.526368 -54.4068)
			)
		)
	)
	(zone
		(layer "F.Cu")
		(hatch none 0.5)
		(connect_pads
			(clearance 0)
		)
		(min_thickness 0.25)
		(keepout
			(tracks allowed)
			(vias allowed)
			(pads allowed)
			(copperpour allowed)
			(footprints not_allowed)
		)
		(placement
			(enabled no)
			(sheetname "")
		)
		(fill
			(thermal_gap 0.5)
			(thermal_bridge_width 0.5)
			(island_removal_mode 0)
		)
		(polygon
			(pts
				(xy 58.475118 -64.200024) (xy 68.039996 -64.200024) (xy 68.039996 -64.630046) (xy 77.659992 -64.630046)
				(xy 77.659992 -69.600064) (xy 99.54006 -69.600064) (xy 99.54006 -64.200024) (xy 118.474998 -64.200024)
				(xy 118.474998 -13.770102) (xy 114.039904 -13.770102) (xy 114.039904 -9.230106) (xy 105.000044 -9.230106)
				(arc
					(start 105.000044 -10.700004)
					(mid 104.707151 -11.407109)
					(end 104.000046 -11.700002)
				)
				(arc
					(start 100.000054 -11.700002)
					(mid 99.292949 -11.407109)
					(end 99.000056 -10.700004)
				)
				(xy 92.16009 -10.700004) (xy 92.16009 -14.200124) (xy 58.475118 -14.200124)
			)
		)
	)
	(zone
		(net "GND")
		(layer "F.Cu")
		(hatch none 0.5)
		(connect_pads
			(clearance 0.5)
		)
		(min_thickness 0.25)
		(fill yes
			(thermal_gap 0.5)
			(thermal_bridge_width 0.5)
			(island_removal_mode 0)
		)
		(polygon
			(pts
				(xy 28.194 -47.498) (xy 28.067 -47.625) (xy 28.067 -48.133) (xy 28.702 -48.768) (xy 29.845 -48.768)
				(xy 30.226 -49.149) (xy 30.226 -52.2732) (xy 32.131 -54.1782) (xy 32.131 -54.61) (xy 32.385 -54.864)
				(xy 37.338 -54.864) (xy 37.846 -54.356) (xy 39.497 -54.356) (xy 40.386 -55.245) (xy 40.386 -60.325)
				(xy 40.513 -60.452) (xy 41.91 -60.452) (xy 42.037 -60.325) (xy 42.037 -59.309) (xy 42.164 -59.182)
				(xy 42.926 -59.182) (xy 43.053 -59.055) (xy 43.053 -54.356) (xy 42.799 -54.102) (xy 41.021 -54.102)
				(xy 40.64 -53.721) (xy 36.576 -53.721) (xy 32.893 -50.038) (xy 32.893 -48.26) (xy 32.131 -47.498)
			)
		)
		(polygon
			(pts
				(xy 28.7782 -48.006) (xy 28.5242 -48.006) (xy 28.5242 -48.26) (xy 28.7782 -48.26)
			)
		)
	)
	(zone
		(net "GND")
		(layer "F.Cu")
		(hatch none 0.5)
		(connect_pads
			(clearance 0.5)
		)
		(min_thickness 0.25)
		(fill yes
			(thermal_gap 0.5)
			(thermal_bridge_width 0.5)
			(island_removal_mode 0)
		)
		(polygon
			(pts
				(xy 133.477 -46.355) (xy 133.35 -46.482) (xy 133.35 -52.451) (xy 133.731 -52.832) (xy 137.033 -52.832)
				(xy 137.414 -52.451) (xy 137.414 -48.768) (xy 138.811 -47.371) (xy 138.811 -46.609) (xy 138.557 -46.355)
				(xy 138.303 -46.355) (xy 137.541 -47.117) (xy 134.747 -47.117) (xy 133.985 -46.355)
			)
		)
		(polygon
			(pts
				(xy 136.144 -52.2224) (xy 135.89 -52.2224) (xy 135.89 -52.4764) (xy 136.144 -52.4764)
			)
		)
		(polygon
			(pts
				(xy 135.636 -52.2224) (xy 135.382 -52.2224) (xy 135.382 -52.4764) (xy 135.636 -52.4764)
			)
		)
	)
	(zone
		(net "GND")
		(layer "F.Cu")
		(hatch none 0.5)
		(connect_pads
			(clearance 0.5)
		)
		(min_thickness 0.25)
		(fill yes
			(thermal_gap 0.5)
			(thermal_bridge_width 0.5)
			(island_removal_mode 0)
		)
		(polygon
			(pts
				(xy 112.014 -25.781) (xy 111.195358 -26.599642) (xy 111.017558 -26.599642) (xy 110.871 -26.7462)
				(xy 110.871 -26.8732) (xy 111.1758 -27.178) (xy 112.3442 -27.178) (xy 112.7252 -27.559) (xy 112.7252 -29.7434)
				(xy 113.5761 -30.5943) (xy 114.427 -29.7434) (xy 116.8146 -29.7434) (xy 117.221 -30.1498) (xy 117.221 -30.9626)
				(xy 118.237 -31.9786) (xy 118.237 -34.798) (xy 118.745 -35.306) (xy 118.745 -36.068) (xy 118.999 -36.322)
				(xy 123.317 -36.322) (xy 125.095 -38.1) (xy 125.095 -40.259) (xy 121.666 -43.688) (xy 121.666 -49.022)
				(xy 116.586 -54.102) (xy 116.586 -57.277) (xy 111.887 -61.976) (xy 111.887 -62.611) (xy 112.649 -63.373)
				(xy 112.649 -64.008) (xy 112.776 -64.135) (xy 114.173 -64.135) (xy 114.3 -64.262) (xy 114.3 -65.024)
				(xy 113.157 -66.167) (xy 113.157 -67.056) (xy 113.284 -67.183) (xy 116.205 -67.183) (xy 116.586 -66.802)
				(xy 116.586 -61.722) (xy 117.7925 -60.5155) (xy 117.856 -60.5155) (xy 118.4275 -59.944) (xy 126.873 -59.944)
				(xy 127.508 -59.309) (xy 127.508 -49.53) (xy 125.222 -47.244) (xy 125.222 -46.101) (xy 126.111 -45.212)
				(xy 126.111 -38.481) (xy 113.411 -25.781)
			)
		)
		(polygon
			(pts
				(xy 114.173 -63.5254) (xy 113.919 -63.5254) (xy 113.919 -63.7794) (xy 114.173 -63.7794)
			)
		)
		(polygon
			(pts
				(xy 113.3094 -63.4492) (xy 113.0554 -63.4492) (xy 113.0554 -63.7032) (xy 113.3094 -63.7032) (xy 113.411 -63.7794)
				(xy 113.665 -63.7794) (xy 113.665 -63.5254) (xy 113.411 -63.5254)
			)
		)
	)
	(zone
		(layer "F.Cu")
		(hatch none 0.5)
		(connect_pads
			(clearance 0)
		)
		(min_thickness 0.25)
		(keepout
			(tracks allowed)
			(vias allowed)
			(pads allowed)
			(copperpour allowed)
			(footprints not_allowed)
		)
		(placement
			(enabled no)
			(sheetname "")
		)
		(fill
			(thermal_gap 0.5)
			(thermal_bridge_width 0.5)
			(island_removal_mode 0)
		)
		(polygon
			(pts
				(arc
					(start 14.429994 -19.60499)
					(mid 11.60018 -16.775176)
					(end 8.770112 -19.60499)
				)
				(arc
					(start 8.770112 -19.60499)
					(mid 11.60018 -22.435058)
					(end 14.429994 -19.60499)
				)
			)
		)
	)
	(zone
		(net "PV_VTT_DDR_A")
		(layer "F.Cu")
		(hatch none 0.5)
		(connect_pads
			(clearance 0.5)
		)
		(min_thickness 0.25)
		(fill yes
			(thermal_gap 0.5)
			(thermal_bridge_width 0.5)
			(island_removal_mode 0)
		)
		(polygon
			(pts
				(xy 128.143 -56.642) (xy 128.016 -56.769) (xy 128.016 -57.658) (xy 128.143 -57.785) (xy 133.985 -57.785)
				(xy 134.239 -57.531) (xy 134.239 -57.15) (xy 133.731 -56.642)
			)
		)
		(polygon
			(pts
				(xy 133.35 -57.3151) (xy 133.096 -57.3151) (xy 133.096 -57.5691) (xy 133.35 -57.5691)
			)
		)
		(polygon
			(pts
				(xy 132.334 -57.3151) (xy 131.826 -57.3151) (xy 131.826 -57.5691) (xy 132.334 -57.5691)
			)
		)
		(polygon
			(pts
				(xy 131.064 -57.3151) (xy 130.556 -57.3151) (xy 130.556 -57.5691) (xy 131.064 -57.5691)
			)
		)
		(polygon
			(pts
				(xy 129.794 -57.3151) (xy 129.159 -57.3151) (xy 129.159 -57.5691) (xy 129.794 -57.5691)
			)
		)
	)
	(zone
		(net "P1V0_LX")
		(layer "F.Cu")
		(hatch none 0.5)
		(connect_pads
			(clearance 0.5)
		)
		(min_thickness 0.25)
		(fill yes
			(thermal_gap 0.5)
			(thermal_bridge_width 0.5)
			(island_removal_mode 0)
		)
		(polygon
			(pts
				(xy 19.431 -23.749) (xy 19.304 -23.876) (xy 19.304 -25.019) (xy 18.796 -25.527) (xy 15.875 -25.527)
				(xy 15.748 -25.654) (xy 15.748 -30.734) (xy 16.002 -30.988) (xy 20.32 -30.988) (xy 20.701 -30.607)
				(xy 20.701 -25.908) (xy 20.955 -25.654) (xy 20.955 -23.876) (xy 20.828 -23.749)
			)
		)
	)
	(zone
		(layer "F.Cu")
		(hatch none 0.5)
		(connect_pads
			(clearance 0)
		)
		(min_thickness 0.25)
		(keepout
			(tracks not_allowed)
			(vias allowed)
			(pads allowed)
			(copperpour not_allowed)
			(footprints allowed)
		)
		(placement
			(enabled no)
			(sheetname "")
		)
		(fill
			(thermal_gap 0.5)
			(thermal_bridge_width 0.5)
			(island_removal_mode 0)
		)
		(polygon
			(pts
				(arc
					(start 78.12024 -30.823154)
					(mid 77.762614 -31.150687)
					(end 78.090014 -31.508446)
				)
				(xy 78.307184 -31.517844)
				(arc
					(start 78.173072 -31.383986)
					(mid 77.962315 -30.98725)
					(end 78.302866 -31.280354)
				)
				(xy 78.551278 -31.528512)
				(arc
					(start 78.648814 -31.53283)
					(mid 78.718268 -31.528753)
					(end 78.785466 -31.510732)
				)
				(arc
					(start 78.69174 -31.417006)
					(mid 78.553184 -30.990378)
					(end 78.841854 -31.333694)
				)
				(arc
					(start 78.92288 -31.41472)
					(mid 78.978702 -31.054627)
					(end 78.678786 -30.847538)
				)
			)
		)
	)
	(zone
		(layer "F.Cu")
		(hatch none 0.5)
		(connect_pads
			(clearance 0)
		)
		(min_thickness 0.25)
		(keepout
			(tracks not_allowed)
			(vias allowed)
			(pads allowed)
			(copperpour not_allowed)
			(footprints allowed)
		)
		(placement
			(enabled no)
			(sheetname "")
		)
		(fill
			(thermal_gap 0.5)
			(thermal_bridge_width 0.5)
			(island_removal_mode 0)
		)
		(polygon
			(pts
				(arc
					(start 80.9117 -54.1274)
					(mid 80.5688 -53.7845)
					(end 80.2259 -54.1274)
				)
				(arc
					(start 80.2259 -54.685946)
					(mid 80.568673 -55.0291)
					(end 80.9117 -54.6862)
				)
				(xy 80.9117 -54.5846) (xy 80.778096 -54.5846)
				(arc
					(start 80.775048 -54.587648)
					(mid 80.407167 -54.847833)
					(end 80.667352 -54.479952)
				)
				(xy 80.715104 -54.4322) (xy 80.9117 -54.4322) (xy 80.9117 -54.356) (xy 80.689704 -54.356)
				(arc
					(start 80.667352 -54.333648)
					(mid 80.398824 -53.974564)
					(end 80.784446 -54.2036)
				)
				(xy 80.9117 -54.2036)
			)
		)
	)
	(zone
		(net "PV_VDDR")
		(layer "F.Cu")
		(hatch none 0.5)
		(connect_pads
			(clearance 0.5)
		)
		(min_thickness 0.25)
		(fill yes
			(thermal_gap 0.5)
			(thermal_bridge_width 0.5)
			(island_removal_mode 0)
		)
		(polygon
			(pts
				(xy 180.086 -14.986) (xy 179.959 -15.113) (xy 179.959 -16.256) (xy 180.086 -16.383) (xy 182.499 -16.383)
				(xy 183.007 -16.891) (xy 183.642 -16.891) (xy 183.896 -16.637) (xy 184.785 -16.637) (xy 185.039 -16.383)
				(xy 185.039 -16.002) (xy 184.912 -15.875) (xy 183.896 -15.875) (xy 183.642 -15.621) (xy 183.642 -15.113)
				(xy 183.515 -14.986)
			)
		)
		(polygon
			(pts
				(xy 182.626 -15.7861) (xy 182.118 -15.7861) (xy 182.118 -16.0401) (xy 182.626 -16.0401)
			)
		)
		(polygon
			(pts
				(xy 180.975 -15.6718) (xy 180.721 -15.6718) (xy 180.721 -15.9258) (xy 180.975 -15.9258) (xy 181.102 -16.0401)
				(xy 181.356 -16.0401) (xy 181.356 -15.7861) (xy 181.102 -15.7861)
			)
		)
		(polygon
			(pts
				(xy 180.467 -15.6718) (xy 180.213 -15.6718) (xy 180.213 -15.9258) (xy 180.467 -15.9258)
			)
		)
	)
	(zone
		(net "P3V3")
		(layer "F.Cu")
		(hatch none 0.5)
		(connect_pads
			(clearance 0.5)
		)
		(min_thickness 0.25)
		(fill yes
			(thermal_gap 0.5)
			(thermal_bridge_width 0.5)
			(island_removal_mode 0)
		)
		(polygon
			(pts
				(xy 51.7398 -38.8366) (xy 50.1142 -40.4622) (xy 50.1142 -41.5544) (xy 50.5968 -42.037) (xy 53.213 -42.037)
				(xy 53.467 -41.783) (xy 54.3814 -41.783) (xy 54.6354 -42.037) (xy 54.991 -42.037) (xy 55.118 -41.91)
				(xy 55.118 -41.529) (xy 54.9656 -41.3766) (xy 54.9656 -39.7002) (xy 54.8894 -39.624) (xy 54.102 -39.624)
				(xy 53.3146 -38.8366)
			)
		)
		(polygon
			(pts
				(xy 54.737 -41.4274) (xy 54.483 -41.4274) (xy 54.483 -41.6814) (xy 54.737 -41.6814)
			)
		)
		(polygon
			(pts
				(xy 54.6608 -40.005) (xy 54.4068 -40.005) (xy 54.4068 -40.259) (xy 54.6608 -40.259)
			)
		)
	)
	(zone
		(net "GND")
		(layer "F.Cu")
		(hatch none 0.5)
		(connect_pads
			(clearance 0.5)
		)
		(min_thickness 0.25)
		(fill yes
			(thermal_gap 0.5)
			(thermal_bridge_width 0.5)
			(island_removal_mode 0)
		)
		(polygon
			(pts
				(xy 1.016 -34.417) (xy 0.762 -34.671) (xy 0.762 -38.227) (xy 1.143 -38.608) (xy 5.207 -38.608) (xy 5.461 -38.354)
				(xy 5.461 -34.544) (xy 5.334 -34.417)
			)
		)
	)
	(zone
		(layer "F.Cu")
		(hatch none 0.5)
		(connect_pads
			(clearance 0)
		)
		(min_thickness 0.25)
		(keepout
			(tracks not_allowed)
			(vias allowed)
			(pads allowed)
			(copperpour not_allowed)
			(footprints allowed)
		)
		(placement
			(enabled no)
			(sheetname "")
		)
		(fill
			(thermal_gap 0.5)
			(thermal_bridge_width 0.5)
			(island_removal_mode 0)
		)
		(polygon
			(pts
				(arc
					(start 52.850034 -71.799958)
					(mid 50.850038 -73.799954)
					(end 48.850042 -71.799958)
				)
				(arc
					(start 48.850042 -71.799958)
					(mid 50.850038 -69.799962)
					(end 52.850034 -71.799958)
				)
			)
		)
	)
	(zone
		(layer "F.Cu")
		(hatch none 0.5)
		(connect_pads
			(clearance 0)
		)
		(min_thickness 0.25)
		(keepout
			(tracks allowed)
			(vias allowed)
			(pads allowed)
			(copperpour allowed)
			(footprints allowed)
		)
		(placement
			(enabled no)
			(sheetname "")
		)
		(fill
			(thermal_gap 0.5)
			(thermal_bridge_width 0.5)
			(island_removal_mode 0)
		)
		(polygon
			(pts
				(xy 152.6032 -33.0708) (xy 152.6032 -31.369) (xy 154.305 -31.369) (xy 154.305 -33.0708)
			)
		)
	)
	(zone
		(net "GND")
		(layer "F.Cu")
		(hatch none 0.5)
		(connect_pads
			(clearance 0.5)
		)
		(min_thickness 0.25)
		(fill yes
			(thermal_gap 0.5)
			(thermal_bridge_width 0.5)
			(island_removal_mode 0)
		)
		(polygon
			(pts
				(xy 128.27 -53.848) (xy 128.016 -54.102) (xy 128.016 -55.88) (xy 128.27 -56.134) (xy 131.826 -56.134)
				(xy 131.953 -56.007) (xy 131.953 -55.118) (xy 132.08 -54.991) (xy 132.334 -54.991) (xy 132.461 -54.864)
				(xy 132.461 -54.102) (xy 132.207 -53.848)
			)
		)
		(polygon
			(pts
				(xy 131.064 -55.2069) (xy 130.556 -55.2069) (xy 130.556 -55.4609) (xy 131.064 -55.4609)
			)
		)
		(polygon
			(pts
				(xy 129.794 -55.2069) (xy 129.159 -55.2069) (xy 129.159 -55.4609) (xy 129.794 -55.4609)
			)
		)
		(polygon
			(pts
				(xy 132.1054 -54.356) (xy 131.8514 -54.356) (xy 131.8514 -54.61) (xy 132.1054 -54.61)
			)
		)
	)
	(zone
		(layer "F.Cu")
		(hatch none 0.5)
		(connect_pads
			(clearance 0)
		)
		(min_thickness 0.25)
		(keepout
			(tracks allowed)
			(vias allowed)
			(pads allowed)
			(copperpour allowed)
			(footprints allowed)
		)
		(placement
			(enabled no)
			(sheetname "")
		)
		(fill
			(thermal_gap 0.5)
			(thermal_bridge_width 0.5)
			(island_removal_mode 0)
		)
		(polygon
			(pts
				(xy 131.953 -34.036) (xy 131.953 -33.02) (xy 133.477 -33.02) (xy 133.477 -34.036)
			)
		)
	)
	(zone
		(layer "F.Cu")
		(hatch none 0.5)
		(connect_pads
			(clearance 0)
		)
		(min_thickness 0.25)
		(keepout
			(tracks allowed)
			(vias allowed)
			(pads allowed)
			(copperpour allowed)
			(footprints not_allowed)
		)
		(placement
			(enabled no)
			(sheetname "")
		)
		(fill
			(thermal_gap 0.5)
			(thermal_bridge_width 0.5)
			(island_removal_mode 0)
		)
		(polygon
			(pts
				(arc
					(start 8.770112 -43.805094)
					(mid 11.60018 -40.975026)
					(end 14.429994 -43.805094)
				)
				(arc
					(start 14.429994 -43.805094)
					(mid 11.60018 -46.634908)
					(end 8.770112 -43.805094)
				)
			)
		)
	)
	(zone
		(layer "F.Cu")
		(hatch none 0.5)
		(connect_pads
			(clearance 0)
		)
		(min_thickness 0.25)
		(keepout
			(tracks not_allowed)
			(vias allowed)
			(pads allowed)
			(copperpour not_allowed)
			(footprints allowed)
		)
		(placement
			(enabled no)
			(sheetname "")
		)
		(fill
			(thermal_gap 0.5)
			(thermal_bridge_width 0.5)
			(island_removal_mode 0)
		)
		(polygon
			(pts
				(arc
					(start 9.2202 -52.908454)
					(mid 8.839327 -52.5272)
					(end 8.4582 -52.9082)
				)
				(arc
					(start 8.4582 -53.8988)
					(mid 8.8392 -54.2798)
					(end 9.2202 -53.8988)
				)
				(xy 9.2202 -53.6575) (xy 9.19734 -53.6575)
				(arc
					(start 9.076944 -53.777896)
					(mid 8.6506 -54.0874)
					(end 8.960104 -53.661056)
				)
				(xy 9.0805 -53.54066) (xy 9.12876 -53.4924) (xy 9.19734 -53.4924) (xy 9.2202 -53.4924) (xy 9.2202 -53.3146)
				(xy 9.19734 -53.3146) (xy 9.12876 -53.3146) (xy 9.0805 -53.26634)
				(arc
					(start 8.960104 -53.145944)
					(mid 8.6506 -52.7196)
					(end 9.076944 -53.029104)
				)
				(xy 9.19734 -53.1495) (xy 9.2202 -53.1495)
			)
		)
	)
	(zone
		(layer "F.Cu")
		(hatch none 0.5)
		(connect_pads
			(clearance 0)
		)
		(min_thickness 0.25)
		(keepout
			(tracks allowed)
			(vias allowed)
			(pads allowed)
			(copperpour allowed)
			(footprints not_allowed)
		)
		(placement
			(enabled no)
			(sheetname "")
		)
		(fill
			(thermal_gap 0.5)
			(thermal_bridge_width 0.5)
			(island_removal_mode 0)
		)
		(polygon
			(pts
				(arc
					(start 210.000088 -0.999998)
					(mid 209.707195 -0.292893)
					(end 209.00009 0)
				)
				(xy 206.000096 0) (xy 206.000096 -73.799954)
				(arc
					(start 209.00009 -73.799954)
					(mid 209.707195 -73.507061)
					(end 210.000088 -72.799956)
				)
			)
		)
	)
	(zone
		(net "P3V3_STBY")
		(layer "F.Cu")
		(hatch none 0.5)
		(connect_pads
			(clearance 0.5)
		)
		(min_thickness 0.25)
		(fill yes
			(thermal_gap 0.5)
			(thermal_bridge_width 0.5)
			(island_removal_mode 0)
		)
		(polygon
			(pts
				(xy 51.308 -51.054) (xy 51.054 -51.308) (xy 51.054 -51.943) (xy 50.927 -52.07) (xy 50.927 -52.578)
				(xy 50.9143 -52.5907) (xy 50.9143 -53.2765) (xy 49.911 -54.2798) (xy 49.911 -55.118) (xy 50.038 -55.245)
				(xy 50.8 -55.245) (xy 52.451 -53.594) (xy 52.451 -51.181) (xy 52.324 -51.054)
			)
		)
	)
	(zone
		(layer "F.Cu")
		(hatch none 0.5)
		(connect_pads
			(clearance 0)
		)
		(min_thickness 0.25)
		(keepout
			(tracks not_allowed)
			(vias allowed)
			(pads allowed)
			(copperpour not_allowed)
			(footprints allowed)
		)
		(placement
			(enabled no)
			(sheetname "")
		)
		(fill
			(thermal_gap 0.5)
			(thermal_bridge_width 0.5)
			(island_removal_mode 0)
		)
		(polygon
			(pts
				(arc
					(start 8.509 -50.622454)
					(mid 8.128127 -50.2412)
					(end 7.747 -50.6222)
				)
				(arc
					(start 7.747 -51.6128)
					(mid 8.128 -51.9938)
					(end 8.509 -51.6128)
				)
				(xy 8.509 -51.3715) (xy 8.48614 -51.3715)
				(arc
					(start 8.365744 -51.491896)
					(mid 7.9394 -51.8014)
					(end 8.248904 -51.375056)
				)
				(xy 8.3693 -51.25466) (xy 8.41756 -51.2064) (xy 8.48614 -51.2064) (xy 8.509 -51.2064) (xy 8.509 -51.0286)
				(xy 8.48614 -51.0286) (xy 8.41756 -51.0286) (xy 8.3693 -50.98034)
				(arc
					(start 8.248904 -50.859944)
					(mid 7.9394 -50.4336)
					(end 8.365744 -50.743104)
				)
				(xy 8.48614 -50.8635) (xy 8.509 -50.8635)
			)
		)
	)
	(zone
		(layers "F.Cu" "B.Cu")
		(hatch none 0.5)
		(connect_pads
			(clearance 0)
		)
		(min_thickness 0.25)
		(keepout
			(tracks not_allowed)
			(vias allowed)
			(pads allowed)
			(copperpour not_allowed)
			(footprints allowed)
		)
		(placement
			(enabled no)
			(sheetname "")
		)
		(fill yes
			(thermal_gap 0.5)
			(thermal_bridge_width 0.5)
			(island_removal_mode 0)
		)
		(polygon
			(pts
				(arc
					(start 3.8354 -61.707014)
					(mid 3.451987 -61.32322)
					(end 3.06832 -61.70676)
				)
				(arc
					(start 3.06832 -62.66434)
					(mid 3.45186 -63.04788)
					(end 3.8354 -62.66434)
				)
				(xy 3.8354 -62.43955) (xy 3.79349 -62.43955)
				(arc
					(start 3.689604 -62.543436)
					(mid 3.26326 -62.85294)
					(end 3.572764 -62.426596)
				)
				(xy 3.67665 -62.32271) (xy 3.72491 -62.27445) (xy 3.79349 -62.27445) (xy 3.8354 -62.27445) (xy 3.8354 -62.09665)
				(xy 3.79349 -62.09665) (xy 3.72491 -62.09665) (xy 3.67665 -62.04839)
				(arc
					(start 3.572764 -61.944504)
					(mid 3.26326 -61.51816)
					(end 3.689604 -61.827664)
				)
				(xy 3.79349 -61.93155) (xy 3.8354 -61.93155)
			)
		)
	)
	(zone
		(layers "F.Cu" "B.Cu")
		(hatch none 0.5)
		(connect_pads
			(clearance 0)
		)
		(min_thickness 0.25)
		(keepout
			(tracks not_allowed)
			(vias allowed)
			(pads allowed)
			(copperpour not_allowed)
			(footprints allowed)
		)
		(placement
			(enabled no)
			(sheetname "")
		)
		(fill yes
			(thermal_gap 0.5)
			(thermal_bridge_width 0.5)
			(island_removal_mode 0)
		)
		(polygon
			(pts
				(arc
					(start 3.7084 -58.706766)
					(mid 3.32486 -58.323226)
					(end 2.94132 -58.706766)
				)
				(arc
					(start 2.94132 -59.664092)
					(mid 3.324733 -60.047886)
					(end 3.7084 -59.664346)
				)
				(xy 3.7084 -59.439556) (xy 3.66649 -59.439556)
				(arc
					(start 3.562604 -59.543442)
					(mid 3.13626 -59.852946)
					(end 3.445764 -59.426602)
				)
				(xy 3.54965 -59.322716) (xy 3.59791 -59.274456) (xy 3.66649 -59.274456) (xy 3.7084 -59.274456) (xy 3.7084 -59.096656)
				(xy 3.66649 -59.096656) (xy 3.59791 -59.096656) (xy 3.54965 -59.048396)
				(arc
					(start 3.445764 -58.94451)
					(mid 3.13626 -58.518166)
					(end 3.562604 -58.82767)
				)
				(xy 3.66649 -58.931556) (xy 3.7084 -58.931556)
			)
		)
	)
	(zone
		(layers "F.Cu" "B.Cu")
		(hatch none 0.5)
		(connect_pads
			(clearance 0)
		)
		(min_thickness 0.25)
		(keepout
			(tracks not_allowed)
			(vias allowed)
			(pads allowed)
			(copperpour not_allowed)
			(footprints allowed)
		)
		(placement
			(enabled no)
			(sheetname "")
		)
		(fill yes
			(thermal_gap 0.5)
			(thermal_bridge_width 0.5)
			(island_removal_mode 0)
		)
		(polygon
			(pts
				(arc
					(start 2.31394 -66.221356)
					(mid 1.930527 -65.837562)
					(end 1.54686 -66.221102)
				)
				(arc
					(start 1.54686 -67.178682)
					(mid 1.9304 -67.562222)
					(end 2.31394 -67.178682)
				)
				(xy 2.31394 -66.953892) (xy 2.27203 -66.953892)
				(arc
					(start 2.168144 -67.057778)
					(mid 1.7418 -67.367282)
					(end 2.051304 -66.940938)
				)
				(xy 2.15519 -66.837052) (xy 2.20345 -66.788792) (xy 2.27203 -66.788792) (xy 2.31394 -66.788792)
				(xy 2.31394 -66.610992) (xy 2.27203 -66.610992) (xy 2.20345 -66.610992) (xy 2.15519 -66.562732)
				(arc
					(start 2.051304 -66.458846)
					(mid 1.7418 -66.032502)
					(end 2.168144 -66.342006)
				)
				(xy 2.27203 -66.445892) (xy 2.31394 -66.445892)
			)
		)
	)
	(zone
		(layers "F.Cu" "B.Cu")
		(hatch none 0.5)
		(connect_pads
			(clearance 0)
		)
		(min_thickness 0.25)
		(keepout
			(tracks not_allowed)
			(vias allowed)
			(pads allowed)
			(copperpour not_allowed)
			(footprints allowed)
		)
		(placement
			(enabled no)
			(sheetname "")
		)
		(fill yes
			(thermal_gap 0.5)
			(thermal_bridge_width 0.5)
			(island_removal_mode 0)
		)
		(polygon
			(pts
				(arc
					(start 2.31394 -60.221368)
					(mid 1.930527 -59.837574)
					(end 1.54686 -60.221114)
				)
				(arc
					(start 1.54686 -61.178694)
					(mid 1.9304 -61.562234)
					(end 2.31394 -61.178694)
				)
				(xy 2.31394 -60.953904) (xy 2.27203 -60.953904)
				(arc
					(start 2.168144 -61.05779)
					(mid 1.7418 -61.367294)
					(end 2.051304 -60.94095)
				)
				(xy 2.15519 -60.837064) (xy 2.20345 -60.788804) (xy 2.27203 -60.788804) (xy 2.31394 -60.788804)
				(xy 2.31394 -60.611004) (xy 2.27203 -60.611004) (xy 2.20345 -60.611004) (xy 2.15519 -60.562744)
				(arc
					(start 2.051304 -60.458858)
					(mid 1.7418 -60.032514)
					(end 2.168144 -60.342018)
				)
				(xy 2.27203 -60.445904) (xy 2.31394 -60.445904)
			)
		)
	)
	(zone
		(layers "F.Cu" "B.Cu")
		(hatch none 0.5)
		(connect_pads
			(clearance 0)
		)
		(min_thickness 0.25)
		(keepout
			(tracks not_allowed)
			(vias allowed)
			(pads allowed)
			(copperpour not_allowed)
			(footprints allowed)
		)
		(placement
			(enabled no)
			(sheetname "")
		)
		(fill yes
			(thermal_gap 0.5)
			(thermal_bridge_width 0.5)
			(island_removal_mode 0)
		)
		(polygon
			(pts
				(arc
					(start 3.8354 -64.707008)
					(mid 3.451987 -64.323214)
					(end 3.06832 -64.706754)
				)
				(arc
					(start 3.06832 -65.664334)
					(mid 3.45186 -66.047874)
					(end 3.8354 -65.664334)
				)
				(xy 3.8354 -65.439544) (xy 3.79349 -65.439544)
				(arc
					(start 3.689604 -65.54343)
					(mid 3.26326 -65.852934)
					(end 3.572764 -65.42659)
				)
				(xy 3.67665 -65.322704) (xy 3.72491 -65.274444) (xy 3.79349 -65.274444) (xy 3.8354 -65.274444) (xy 3.8354 -65.096644)
				(xy 3.79349 -65.096644) (xy 3.72491 -65.096644) (xy 3.67665 -65.048384)
				(arc
					(start 3.572764 -64.944498)
					(mid 3.26326 -64.518154)
					(end 3.689604 -64.827658)
				)
				(xy 3.79349 -64.931544) (xy 3.8354 -64.931544)
			)
		)
	)
	(zone
		(layers "F.Cu" "B.Cu")
		(hatch none 0.5)
		(connect_pads
			(clearance 0)
		)
		(min_thickness 0.25)
		(keepout
			(tracks not_allowed)
			(vias allowed)
			(pads allowed)
			(copperpour not_allowed)
			(footprints allowed)
		)
		(placement
			(enabled no)
			(sheetname "")
		)
		(fill yes
			(thermal_gap 0.5)
			(thermal_bridge_width 0.5)
			(island_removal_mode 0)
		)
		(polygon
			(pts
				(arc
					(start 2.31394 -63.221108)
					(mid 1.9304 -62.837568)
					(end 1.54686 -63.221108)
				)
				(arc
					(start 1.54686 -64.178434)
					(mid 1.930273 -64.562228)
					(end 2.31394 -64.178688)
				)
				(xy 2.31394 -63.953898) (xy 2.27203 -63.953898)
				(arc
					(start 2.168144 -64.057784)
					(mid 1.7418 -64.367288)
					(end 2.051304 -63.940944)
				)
				(xy 2.15519 -63.837058) (xy 2.20345 -63.788798) (xy 2.27203 -63.788798) (xy 2.31394 -63.788798)
				(xy 2.31394 -63.610998) (xy 2.27203 -63.610998) (xy 2.20345 -63.610998) (xy 2.15519 -63.562738)
				(arc
					(start 2.051304 -63.458852)
					(mid 1.7418 -63.032508)
					(end 2.168144 -63.342012)
				)
				(xy 2.27203 -63.445898) (xy 2.31394 -63.445898)
			)
		)
	)
	(zone
		(layers "F.Cu" "B.Cu" "In1.Cu" "In2.Cu" "In3.Cu" "In4.Cu" "In5.Cu" "In6.Cu"
			"In7.Cu" "In8.Cu" "In9.Cu" "In10.Cu"
		)
		(name "Route Keepin")
		(hatch none 0.5)
		(connect_pads
			(clearance 0)
		)
		(min_thickness 0.25)
		(keepout
			(tracks allowed)
			(vias allowed)
			(pads allowed)
			(copperpour allowed)
			(footprints allowed)
		)
		(placement
			(enabled no)
			(sheetname "")
		)
		(fill
			(thermal_gap 0.5)
			(thermal_bridge_width 0.5)
			(island_removal_mode 0)
		)
		(polygon
			(pts
				(arc
					(start 0.999998 -15.461996)
					(mid 0.831708 -15.531704)
					(end 0.762 -15.699994)
				)
				(arc
					(start 0.762 -72.799956)
					(mid 0.831708 -72.968246)
					(end 0.999998 -73.037954)
				)
				(arc
					(start 209.00009 -73.037954)
					(mid 209.16838 -72.968246)
					(end 209.238088 -72.799956)
				)
				(arc
					(start 209.238088 -0.999998)
					(mid 209.16838 -0.831708)
					(end 209.00009 -0.762)
				)
				(arc
					(start 106.000042 -0.762)
					(mid 105.831752 -0.831708)
					(end 105.762044 -0.999998)
				)
				(arc
					(start 105.762044 -10.700004)
					(mid 105.245967 -11.945925)
					(end 104.000046 -12.462002)
				)
				(arc
					(start 100.000054 -12.462002)
					(mid 98.754133 -11.945925)
					(end 98.238056 -10.700004)
				)
				(xy 98.238056 -4.862068) (xy 88.561926 -4.862068)
				(arc
					(start 88.561926 -10.150094)
					(mid 86.849966 -11.862054)
					(end 85.138006 -10.150094)
				)
				(xy 85.138006 -4.862068) (xy 15.461996 -4.862068)
				(arc
					(start 15.461996 -13.699998)
					(mid 14.945919 -14.945919)
					(end 13.699998 -15.461996)
				)
			)
		)
	)
	(zone
		(layers "F.Cu" "B.Cu" "In1.Cu" "In2.Cu" "In3.Cu" "In4.Cu" "In5.Cu" "In6.Cu"
			"In7.Cu" "In8.Cu" "In9.Cu" "In10.Cu"
		)
		(name "Package Keepin")
		(hatch none 0.5)
		(connect_pads
			(clearance 0)
		)
		(min_thickness 0.25)
		(keepout
			(tracks allowed)
			(vias allowed)
			(pads allowed)
			(copperpour allowed)
			(footprints allowed)
		)
		(placement
			(enabled no)
			(sheetname "")
		)
		(fill
			(thermal_gap 0.5)
			(thermal_bridge_width 0.5)
			(island_removal_mode 0)
		)
		(polygon
			(pts
				(xy 5.08 -19.779996) (xy 5.08 -68.719954) (xy 204.920088 -68.719954) (xy 204.920088 -5.08) (xy 110.080044 -5.08)
				(arc
					(start 110.080044 -10.700004)
					(mid 108.299254 -14.999212)
					(end 104.000046 -16.780002)
				)
				(arc
					(start 100.000054 -16.780002)
					(mid 95.700846 -14.999212)
					(end 93.920056 -10.700004)
				)
				(xy 93.920056 -9.180068) (xy 92.879926 -9.180068)
				(arc
					(start 92.879926 -10.150348)
					(mid 86.849966 -16.180054)
					(end 80.820006 -10.150348)
				)
				(xy 80.820006 -9.180068) (xy 19.779996 -9.180068)
				(arc
					(start 19.779996 -13.699998)
					(mid 17.999206 -17.999206)
					(end 13.699998 -19.779996)
				)
			)
		)
	)
	(zone
		(layers "F.Cu" "B.Cu" "In1.Cu" "In2.Cu" "In3.Cu" "In4.Cu" "In5.Cu" "In6.Cu"
			"In7.Cu" "In8.Cu" "In9.Cu" "In10.Cu"
		)
		(hatch none 0.5)
		(connect_pads
			(clearance 0)
		)
		(min_thickness 0.25)
		(keepout
			(tracks not_allowed)
			(vias allowed)
			(pads allowed)
			(copperpour not_allowed)
			(footprints allowed)
		)
		(placement
			(enabled no)
			(sheetname "")
		)
		(fill
			(thermal_gap 0.5)
			(thermal_bridge_width 0.5)
			(island_removal_mode 0)
		)
		(polygon
			(pts
				(arc
					(start 52.861972 -71.799958)
					(mid 48.838104 -71.799958)
					(end 52.861972 -71.799958)
				)
			)
		)
	)
	(zone
		(layers "F.Cu" "B.Cu" "In1.Cu" "In2.Cu" "In3.Cu" "In4.Cu" "In5.Cu" "In6.Cu"
			"In7.Cu" "In8.Cu" "In9.Cu" "In10.Cu"
		)
		(hatch none 0.5)
		(connect_pads
			(clearance 0)
		)
		(min_thickness 0.25)
		(keepout
			(tracks not_allowed)
			(vias allowed)
			(pads allowed)
			(copperpour not_allowed)
			(footprints allowed)
		)
		(placement
			(enabled no)
			(sheetname "")
		)
		(fill
			(thermal_gap 0.5)
			(thermal_bridge_width 0.5)
			(island_removal_mode 0)
		)
		(polygon
			(pts
				(arc
					(start 77.866748 -71.799958)
					(mid 73.833228 -71.799958)
					(end 77.866748 -71.799958)
				)
			)
		)
	)
	(zone
		(layers "F.Cu" "In2.Cu" "In4.Cu" "In7.Cu")
		(hatch none 0.5)
		(connect_pads
			(clearance 0)
		)
		(min_thickness 0.25)
		(keepout
			(tracks not_allowed)
			(vias allowed)
			(pads allowed)
			(copperpour not_allowed)
			(footprints allowed)
		)
		(placement
			(enabled no)
			(sheetname "")
		)
		(fill yes
			(thermal_gap 0.5)
			(thermal_bridge_width 0.5)
			(island_removal_mode 0)
		)
		(polygon
			(pts
				(arc
					(start 51.041554 -47.636938)
					(mid 50.660808 -47.253408)
					(end 50.274474 -47.63135)
				)
				(arc
					(start 50.262028 -48.49495)
					(mid 50.63998 -48.884078)
					(end 51.029108 -48.506126)
				)
				(xy 51.029108 -48.503078)
				(arc
					(start 50.912268 -48.503078)
					(mid 50.645568 -48.76725)
					(end 50.378868 -48.503078)
				)
				(arc
					(start 50.378868 -48.500538)
					(mid 50.645568 -48.233838)
					(end 50.912268 -48.500538)
				)
				(xy 51.029108 -48.500538) (xy 51.041554 -47.64278) (xy 51.041554 -47.639478)
				(arc
					(start 50.924714 -47.639478)
					(mid 50.658014 -47.90365)
					(end 50.391314 -47.639478)
				)
				(arc
					(start 50.391314 -47.636938)
					(mid 50.658014 -47.370238)
					(end 50.924714 -47.636938)
				)
			)
		)
	)
	(zone
		(layers "F.Cu" "In2.Cu" "In4.Cu" "In7.Cu")
		(hatch none 0.5)
		(connect_pads
			(clearance 0)
		)
		(min_thickness 0.25)
		(keepout
			(tracks not_allowed)
			(vias allowed)
			(pads allowed)
			(copperpour not_allowed)
			(footprints allowed)
		)
		(placement
			(enabled no)
			(sheetname "")
		)
		(fill yes
			(thermal_gap 0.5)
			(thermal_bridge_width 0.5)
			(island_removal_mode 0)
		)
		(polygon
			(pts
				(arc
					(start 82.296254 -13.56106)
					(mid 81.91246 -13.944473)
					(end 82.296 -14.32814)
				)
				(arc
					(start 83.1596 -14.32814)
					(mid 83.429904 -14.2167)
					(end 83.54314 -13.94714)
				)
				(arc
					(start 83.4263 -13.94714)
					(mid 83.1596 -14.211312)
					(end 82.8929 -13.94714)
				)
				(arc
					(start 82.5627 -13.94714)
					(mid 82.296 -14.211312)
					(end 82.0293 -13.94714)
				)
				(arc
					(start 82.0293 -13.9446)
					(mid 82.296 -13.6779)
					(end 82.5627 -13.9446)
				)
				(arc
					(start 82.8929 -13.9446)
					(mid 83.1596 -13.6779)
					(end 83.4263 -13.9446)
				)
				(arc
					(start 83.54314 -13.9446)
					(mid 83.430804 -13.673396)
					(end 83.1596 -13.56106)
				)
			)
		)
	)
	(zone
		(layers "F.Cu" "In2.Cu" "In4.Cu" "In9.Cu")
		(hatch none 0.5)
		(connect_pads
			(clearance 0)
		)
		(min_thickness 0.25)
		(keepout
			(tracks not_allowed)
			(vias allowed)
			(pads allowed)
			(copperpour not_allowed)
			(footprints allowed)
		)
		(placement
			(enabled no)
			(sheetname "")
		)
		(fill yes
			(thermal_gap 0.5)
			(thermal_bridge_width 0.5)
			(island_removal_mode 0)
		)
		(polygon
			(pts
				(arc
					(start 61.317378 -45.848016)
					(mid 60.910088 -45.489868)
					(end 60.551822 -45.897038)
				)
				(arc
					(start 60.607448 -46.75886)
					(mid 61.001282 -47.117871)
					(end 61.373766 -46.736762)
				)
				(arc
					(start 61.256926 -46.736762)
					(mid 60.990226 -47.000934)
					(end 60.723526 -46.736762)
				)
				(arc
					(start 60.723526 -46.734222)
					(mid 60.990226 -46.467522)
					(end 61.256926 -46.734222)
				)
				(xy 61.373766 -46.734222) (xy 61.373004 -46.709584) (xy 61.319156 -45.87494)
				(arc
					(start 61.2013 -45.87494)
					(mid 60.9346 -46.139112)
					(end 60.6679 -45.87494)
				)
				(arc
					(start 60.6679 -45.8724)
					(mid 60.9346 -45.6057)
					(end 61.2013 -45.8724)
				)
				(xy 61.318902 -45.8724)
			)
		)
	)
	(zone
		(layers "F.Cu" "In2.Cu" "In4.Cu" "In9.Cu")
		(hatch none 0.5)
		(connect_pads
			(clearance 0)
		)
		(min_thickness 0.25)
		(keepout
			(tracks not_allowed)
			(vias allowed)
			(pads allowed)
			(copperpour not_allowed)
			(footprints allowed)
		)
		(placement
			(enabled no)
			(sheetname "")
		)
		(fill yes
			(thermal_gap 0.5)
			(thermal_bridge_width 0.5)
			(island_removal_mode 0)
		)
		(polygon
			(pts
				(arc
					(start 65.786 -14.3002)
					(mid 65.405 -14.6812)
					(end 65.786 -15.0622)
				)
				(arc
					(start 66.547746 -15.0622)
					(mid 66.816418 -14.951594)
					(end 66.929 -14.68374)
				)
				(arc
					(start 66.8147 -14.68374)
					(mid 66.548 -14.947912)
					(end 66.2813 -14.68374)
				)
				(arc
					(start 66.0527 -14.68374)
					(mid 65.786 -14.947912)
					(end 65.5193 -14.68374)
				)
				(arc
					(start 65.5193 -14.6812)
					(mid 65.786 -14.4145)
					(end 66.0527 -14.6812)
				)
				(arc
					(start 66.2813 -14.6812)
					(mid 66.548 -14.4145)
					(end 66.8147 -14.6812)
				)
				(arc
					(start 66.929 -14.6812)
					(mid 66.817408 -14.411792)
					(end 66.548 -14.3002)
				)
			)
		)
	)
	(zone
		(layers "F.Cu" "In2.Cu" "In4.Cu" "In9.Cu")
		(hatch none 0.5)
		(connect_pads
			(clearance 0)
		)
		(min_thickness 0.25)
		(keepout
			(tracks not_allowed)
			(vias allowed)
			(pads allowed)
			(copperpour not_allowed)
			(footprints allowed)
		)
		(placement
			(enabled no)
			(sheetname "")
		)
		(fill yes
			(thermal_gap 0.5)
			(thermal_bridge_width 0.5)
			(island_removal_mode 0)
		)
		(polygon
			(pts
				(arc
					(start 53.535326 -28.897834)
					(mid 53.151786 -28.514294)
					(end 52.768246 -28.897834)
				)
				(arc
					(start 52.768246 -29.826966)
					(mid 53.150389 -30.210758)
					(end 53.535326 -29.82976)
				)
				(arc
					(start 53.418486 -29.82976)
					(mid 53.151786 -30.093932)
					(end 52.885086 -29.82976)
				)
				(arc
					(start 52.885086 -29.82722)
					(mid 53.151786 -29.56052)
					(end 53.418486 -29.82722)
				)
				(xy 53.535326 -29.82722) (xy 53.535326 -28.900374)
				(arc
					(start 53.418486 -28.900374)
					(mid 53.151786 -29.164546)
					(end 52.885086 -28.900374)
				)
				(arc
					(start 52.885086 -28.897834)
					(mid 53.151786 -28.631134)
					(end 53.418486 -28.897834)
				)
			)
		)
	)
	(zone
		(layers "F.Cu" "In2.Cu" "In7.Cu" "In9.Cu")
		(hatch none 0.5)
		(connect_pads
			(clearance 0)
		)
		(min_thickness 0.25)
		(keepout
			(tracks not_allowed)
			(vias allowed)
			(pads allowed)
			(copperpour not_allowed)
			(footprints allowed)
		)
		(placement
			(enabled no)
			(sheetname "")
		)
		(fill yes
			(thermal_gap 0.5)
			(thermal_bridge_width 0.5)
			(island_removal_mode 0)
		)
		(polygon
			(pts
				(arc
					(start 42.453814 -43.77182)
					(mid 42.07002 -44.155233)
					(end 42.45356 -44.5389)
				)
				(arc
					(start 43.41114 -44.5389)
					(mid 43.681444 -44.42746)
					(end 43.79468 -44.1579)
				)
				(arc
					(start 43.67784 -44.1579)
					(mid 43.41114 -44.422072)
					(end 43.14444 -44.1579)
				)
				(arc
					(start 42.72026 -44.1579)
					(mid 42.45356 -44.422072)
					(end 42.18686 -44.1579)
				)
				(arc
					(start 42.18686 -44.15536)
					(mid 42.45356 -43.88866)
					(end 42.72026 -44.15536)
				)
				(arc
					(start 43.14444 -44.15536)
					(mid 43.41114 -43.88866)
					(end 43.67784 -44.15536)
				)
				(arc
					(start 43.79468 -44.15536)
					(mid 43.682344 -43.884156)
					(end 43.41114 -43.77182)
				)
			)
		)
	)
	(zone
		(layers "F.Cu" "In2.Cu" "In7.Cu" "In9.Cu")
		(hatch none 0.5)
		(connect_pads
			(clearance 0)
		)
		(min_thickness 0.25)
		(keepout
			(tracks not_allowed)
			(vias allowed)
			(pads allowed)
			(copperpour not_allowed)
			(footprints allowed)
		)
		(placement
			(enabled no)
			(sheetname "")
		)
		(fill yes
			(thermal_gap 0.5)
			(thermal_bridge_width 0.5)
			(island_removal_mode 0)
		)
		(polygon
			(pts
				(arc
					(start 60.04179 -35.37966)
					(mid 59.65825 -34.99612)
					(end 59.27471 -35.37966)
				)
				(arc
					(start 59.27471 -36.33724)
					(mid 59.65698 -36.720778)
					(end 60.04179 -36.33978)
				)
				(arc
					(start 59.92495 -36.33978)
					(mid 59.65825 -36.603952)
					(end 59.39155 -36.33978)
				)
				(arc
					(start 59.39155 -36.33724)
					(mid 59.65825 -36.07054)
					(end 59.92495 -36.33724)
				)
				(xy 60.04179 -36.33724) (xy 60.04179 -35.3822)
				(arc
					(start 59.92495 -35.3822)
					(mid 59.65825 -35.646372)
					(end 59.39155 -35.3822)
				)
				(arc
					(start 59.39155 -35.37966)
					(mid 59.65825 -35.11296)
					(end 59.92495 -35.37966)
				)
			)
		)
	)
	(zone
		(layers "F.Cu" "In2.Cu" "In7.Cu" "In9.Cu")
		(hatch none 0.5)
		(connect_pads
			(clearance 0)
		)
		(min_thickness 0.25)
		(keepout
			(tracks not_allowed)
			(vias allowed)
			(pads allowed)
			(copperpour not_allowed)
			(footprints allowed)
		)
		(placement
			(enabled no)
			(sheetname "")
		)
		(fill yes
			(thermal_gap 0.5)
			(thermal_bridge_width 0.5)
			(island_removal_mode 0)
		)
		(polygon
			(pts
				(arc
					(start 49.692052 -37.74567)
					(mid 49.15027 -37.771832)
					(end 49.176432 -38.313614)
				)
				(arc
					(start 49.81321 -38.892226)
					(mid 50.226125 -38.962468)
					(end 50.4571 -38.61308)
				)
				(arc
					(start 50.34026 -38.61308)
					(mid 50.07356 -38.877252)
					(end 49.80686 -38.61308)
				)
				(arc
					(start 49.80686 -38.61054)
					(mid 50.07356 -38.34384)
					(end 50.34026 -38.61054)
				)
				(arc
					(start 50.4571 -38.61054)
					(mid 50.424261 -38.45526)
					(end 50.33137 -38.326568)
				)
				(xy 50.007266 -38.032182)
				(arc
					(start 49.700942 -38.032182)
					(mid 49.434242 -38.296354)
					(end 49.167542 -38.032182)
				)
				(arc
					(start 49.167542 -38.029642)
					(mid 49.434242 -37.762942)
					(end 49.700942 -38.029642)
				)
				(xy 50.004472 -38.029642)
			)
		)
	)
	(zone
		(layers "F.Cu" "In2.Cu" "In7.Cu" "In9.Cu")
		(hatch none 0.5)
		(connect_pads
			(clearance 0)
		)
		(min_thickness 0.25)
		(keepout
			(tracks not_allowed)
			(vias allowed)
			(pads allowed)
			(copperpour not_allowed)
			(footprints allowed)
		)
		(placement
			(enabled no)
			(sheetname "")
		)
		(fill yes
			(thermal_gap 0.5)
			(thermal_bridge_width 0.5)
			(island_removal_mode 0)
		)
		(polygon
			(pts
				(arc
					(start 45.007276 -43.53306)
					(mid 44.615103 -43.907837)
					(end 44.98975 -44.30014)
				)
				(arc
					(start 45.947838 -44.32173)
					(mid 46.231408 -44.205751)
					(end 46.339506 -43.91914)
				)
				(arc
					(start 46.222412 -43.91914)
					(mid 45.956474 -44.204809)
					(end 45.690536 -43.91914)
				)
				(arc
					(start 45.265086 -43.91914)
					(mid 44.998386 -44.183312)
					(end 44.731686 -43.91914)
				)
				(arc
					(start 44.731686 -43.9166)
					(mid 44.998386 -43.6499)
					(end 45.265086 -43.9166)
				)
				(arc
					(start 45.690536 -43.9166)
					(mid 45.956474 -43.671377)
					(end 46.222412 -43.9166)
				)
				(arc
					(start 46.339506 -43.9166)
					(mid 46.223126 -43.662371)
					(end 45.96511 -43.55465)
				)
			)
		)
	)
	(zone
		(layers "F.Cu" "In2.Cu" "In7.Cu" "In9.Cu")
		(hatch none 0.5)
		(connect_pads
			(clearance 0)
		)
		(min_thickness 0.25)
		(keepout
			(tracks not_allowed)
			(vias allowed)
			(pads allowed)
			(copperpour not_allowed)
			(footprints allowed)
		)
		(placement
			(enabled no)
			(sheetname "")
		)
		(fill yes
			(thermal_gap 0.5)
			(thermal_bridge_width 0.5)
			(island_removal_mode 0)
		)
		(polygon
			(pts
				(arc
					(start 51.2826 -33.70326)
					(mid 50.898806 -34.086673)
					(end 51.282346 -34.47034)
				)
				(arc
					(start 52.16652 -34.47034)
					(mid 52.436824 -34.3589)
					(end 52.55006 -34.08934)
				)
				(arc
					(start 52.43322 -34.08934)
					(mid 52.16652 -34.353512)
					(end 51.89982 -34.08934)
				)
				(arc
					(start 51.549046 -34.08934)
					(mid 51.282346 -34.353512)
					(end 51.015646 -34.08934)
				)
				(arc
					(start 51.015646 -34.0868)
					(mid 51.282346 -33.8201)
					(end 51.549046 -34.0868)
				)
				(arc
					(start 51.89982 -34.0868)
					(mid 52.16652 -33.8201)
					(end 52.43322 -34.0868)
				)
				(arc
					(start 52.55006 -34.0868)
					(mid 52.437724 -33.815596)
					(end 52.16652 -33.70326)
				)
			)
		)
	)
	(zone
		(layers "F.Cu" "In4.Cu")
		(hatch none 0.5)
		(connect_pads
			(clearance 0)
		)
		(min_thickness 0.25)
		(keepout
			(tracks not_allowed)
			(vias allowed)
			(pads allowed)
			(copperpour not_allowed)
			(footprints allowed)
		)
		(placement
			(enabled no)
			(sheetname "")
		)
		(fill yes
			(thermal_gap 0.5)
			(thermal_bridge_width 0.5)
			(island_removal_mode 0)
		)
		(polygon
			(pts
				(xy 78.404466 -30.240224) (xy 78.511146 -30.238954) (xy 78.508352 -30.236414) (xy 78.471268 -30.19933)
				(xy 78.471268 -30.146498)
				(arc
					(start 78.471268 -30.115256)
					(mid 78.535799 -29.667201)
					(end 78.598268 -30.11551)
				)
				(xy 78.598268 -30.146498)
				(arc
					(start 78.664816 -30.2133)
					(mid 78.871401 -29.827927)
					(end 78.531466 -29.5529)
				)
				(arc
					(start 77.972666 -29.55925)
					(mid 77.633576 -29.90596)
					(end 77.980286 -30.24505)
				)
				(xy 78.226666 -30.242256)
				(arc
					(start 78.086966 -30.102302)
					(mid 77.814815 -29.740489)
					(end 78.176628 -30.01264)
				)
			)
		)
	)
	(zone
		(layers "F.Cu" "In4.Cu" "In7.Cu" "In9.Cu")
		(hatch none 0.5)
		(connect_pads
			(clearance 0)
		)
		(min_thickness 0.25)
		(keepout
			(tracks not_allowed)
			(vias allowed)
			(pads allowed)
			(copperpour not_allowed)
			(footprints allowed)
		)
		(placement
			(enabled no)
			(sheetname "")
		)
		(fill yes
			(thermal_gap 0.5)
			(thermal_bridge_width 0.5)
			(island_removal_mode 0)
		)
		(polygon
			(pts
				(arc
					(start 20.09521 -15.105126)
					(mid 19.71167 -15.488666)
					(end 20.09521 -15.872206)
				)
				(arc
					(start 21.052536 -15.872206)
					(mid 21.323004 -15.760856)
					(end 21.43633 -15.491206)
				)
				(arc
					(start 21.31949 -15.491206)
					(mid 21.05279 -15.755378)
					(end 20.78609 -15.491206)
				)
				(arc
					(start 20.36191 -15.491206)
					(mid 20.09521 -15.755378)
					(end 19.82851 -15.491206)
				)
				(arc
					(start 19.82851 -15.488666)
					(mid 20.09521 -15.221966)
					(end 20.36191 -15.488666)
				)
				(arc
					(start 20.78609 -15.488666)
					(mid 21.05279 -15.221966)
					(end 21.31949 -15.488666)
				)
				(arc
					(start 21.43633 -15.488666)
					(mid 21.323994 -15.217462)
					(end 21.05279 -15.105126)
				)
			)
		)
	)
	(zone
		(layers "F.Cu" "In4.Cu" "In7.Cu" "In9.Cu")
		(hatch none 0.5)
		(connect_pads
			(clearance 0)
		)
		(min_thickness 0.25)
		(keepout
			(tracks not_allowed)
			(vias allowed)
			(pads allowed)
			(copperpour not_allowed)
			(footprints allowed)
		)
		(placement
			(enabled no)
			(sheetname "")
		)
		(fill yes
			(thermal_gap 0.5)
			(thermal_bridge_width 0.5)
			(island_removal_mode 0)
		)
		(polygon
			(pts
				(arc
					(start 39.443914 -11.9634)
					(mid 39.06012 -12.346813)
					(end 39.44366 -12.73048)
				)
				(arc
					(start 40.40124 -12.73048)
					(mid 40.671544 -12.61904)
					(end 40.78478 -12.34948)
				)
				(arc
					(start 40.66794 -12.34948)
					(mid 40.40124 -12.613652)
					(end 40.13454 -12.34948)
				)
				(arc
					(start 39.71036 -12.34948)
					(mid 39.44366 -12.613652)
					(end 39.17696 -12.34948)
				)
				(arc
					(start 39.17696 -12.34694)
					(mid 39.44366 -12.08024)
					(end 39.71036 -12.34694)
				)
				(arc
					(start 40.13454 -12.34694)
					(mid 40.40124 -12.08024)
					(end 40.66794 -12.34694)
				)
				(arc
					(start 40.78478 -12.34694)
					(mid 40.672444 -12.075736)
					(end 40.40124 -11.9634)
				)
			)
		)
	)
	(zone
		(layers "F.Cu" "In4.Cu" "In7.Cu" "In9.Cu")
		(hatch none 0.5)
		(connect_pads
			(clearance 0)
		)
		(min_thickness 0.25)
		(keepout
			(tracks not_allowed)
			(vias allowed)
			(pads allowed)
			(copperpour not_allowed)
			(footprints allowed)
		)
		(placement
			(enabled no)
			(sheetname "")
		)
		(fill yes
			(thermal_gap 0.5)
			(thermal_bridge_width 0.5)
			(island_removal_mode 0)
		)
		(polygon
			(pts
				(arc
					(start 68.072254 -14.22146)
					(mid 67.68846 -14.604873)
					(end 68.072 -14.98854)
				)
				(arc
					(start 68.834 -14.98854)
					(mid 69.104304 -14.8771)
					(end 69.21754 -14.60754)
				)
				(arc
					(start 69.1007 -14.60754)
					(mid 68.834 -14.871712)
					(end 68.5673 -14.60754)
				)
				(arc
					(start 68.3387 -14.60754)
					(mid 68.072 -14.871712)
					(end 67.8053 -14.60754)
				)
				(arc
					(start 67.8053 -14.605)
					(mid 68.072 -14.3383)
					(end 68.3387 -14.605)
				)
				(arc
					(start 68.5673 -14.605)
					(mid 68.834 -14.3383)
					(end 69.1007 -14.605)
				)
				(arc
					(start 69.21754 -14.605)
					(mid 69.105204 -14.333796)
					(end 68.834 -14.22146)
				)
			)
		)
	)
	(zone
		(layers "F.Cu" "In4.Cu" "In7.Cu" "In9.Cu")
		(hatch none 0.5)
		(connect_pads
			(clearance 0)
		)
		(min_thickness 0.25)
		(keepout
			(tracks not_allowed)
			(vias allowed)
			(pads allowed)
			(copperpour not_allowed)
			(footprints allowed)
		)
		(placement
			(enabled no)
			(sheetname "")
		)
		(fill yes
			(thermal_gap 0.5)
			(thermal_bridge_width 0.5)
			(island_removal_mode 0)
		)
		(polygon
			(pts
				(arc
					(start 21.666454 -13.43406)
					(mid 21.28266 -13.817473)
					(end 21.6662 -14.20114)
				)
				(arc
					(start 22.5298 -14.20114)
					(mid 22.800104 -14.0897)
					(end 22.91334 -13.82014)
				)
				(arc
					(start 22.7965 -13.82014)
					(mid 22.5298 -14.084312)
					(end 22.2631 -13.82014)
				)
				(arc
					(start 21.9329 -13.82014)
					(mid 21.6662 -14.084312)
					(end 21.3995 -13.82014)
				)
				(arc
					(start 21.3995 -13.8176)
					(mid 21.6662 -13.5509)
					(end 21.9329 -13.8176)
				)
				(arc
					(start 22.2631 -13.8176)
					(mid 22.5298 -13.5509)
					(end 22.7965 -13.8176)
				)
				(arc
					(start 22.91334 -13.8176)
					(mid 22.801004 -13.546396)
					(end 22.5298 -13.43406)
				)
			)
		)
	)
	(zone
		(layers "F.Cu" "In4.Cu" "In7.Cu" "In9.Cu")
		(hatch none 0.5)
		(connect_pads
			(clearance 0)
		)
		(min_thickness 0.25)
		(keepout
			(tracks not_allowed)
			(vias allowed)
			(pads allowed)
			(copperpour not_allowed)
			(footprints allowed)
		)
		(placement
			(enabled no)
			(sheetname "")
		)
		(fill yes
			(thermal_gap 0.5)
			(thermal_bridge_width 0.5)
			(island_removal_mode 0)
		)
		(polygon
			(pts
				(arc
					(start 47.46371 -13.4112)
					(mid 47.08271 -13.7922)
					(end 47.46371 -14.1732)
				)
				(arc
					(start 48.183546 -14.1732)
					(mid 48.452218 -14.062594)
					(end 48.5648 -13.79474)
				)
				(arc
					(start 48.4505 -13.79474)
					(mid 48.1838 -14.058912)
					(end 47.9171 -13.79474)
				)
				(arc
					(start 47.73041 -13.79474)
					(mid 47.46371 -14.058912)
					(end 47.19701 -13.79474)
				)
				(arc
					(start 47.19701 -13.7922)
					(mid 47.46371 -13.5255)
					(end 47.73041 -13.7922)
				)
				(arc
					(start 47.9171 -13.7922)
					(mid 48.1838 -13.5255)
					(end 48.4505 -13.7922)
				)
				(arc
					(start 48.5648 -13.7922)
					(mid 48.453208 -13.522792)
					(end 48.1838 -13.4112)
				)
			)
		)
	)
	(zone
		(layers "F.Cu" "In4.Cu" "In7.Cu" "In9.Cu")
		(hatch none 0.5)
		(connect_pads
			(clearance 0)
		)
		(min_thickness 0.25)
		(keepout
			(tracks not_allowed)
			(vias allowed)
			(pads allowed)
			(copperpour not_allowed)
			(footprints allowed)
		)
		(placement
			(enabled no)
			(sheetname "")
		)
		(fill yes
			(thermal_gap 0.5)
			(thermal_bridge_width 0.5)
			(island_removal_mode 0)
		)
		(polygon
			(pts
				(arc
					(start 61.40831 -9.867138)
					(mid 61.02477 -10.250678)
					(end 61.40831 -10.634218)
				)
				(arc
					(start 62.327536 -10.634218)
					(mid 62.598004 -10.522868)
					(end 62.71133 -10.253218)
				)
				(arc
					(start 62.59449 -10.253218)
					(mid 62.32779 -10.51739)
					(end 62.06109 -10.253218)
				)
				(arc
					(start 61.67501 -10.253218)
					(mid 61.40831 -10.51739)
					(end 61.14161 -10.253218)
				)
				(arc
					(start 61.14161 -10.250678)
					(mid 61.40831 -9.983978)
					(end 61.67501 -10.250678)
				)
				(arc
					(start 62.06109 -10.250678)
					(mid 62.32779 -9.983978)
					(end 62.59449 -10.250678)
				)
				(arc
					(start 62.71133 -10.250678)
					(mid 62.598994 -9.979474)
					(end 62.32779 -9.867138)
				)
			)
		)
	)
	(zone
		(layers "F.Cu" "In4.Cu" "In7.Cu" "In9.Cu")
		(hatch none 0.5)
		(connect_pads
			(clearance 0)
		)
		(min_thickness 0.25)
		(keepout
			(tracks not_allowed)
			(vias allowed)
			(pads allowed)
			(copperpour not_allowed)
			(footprints allowed)
		)
		(placement
			(enabled no)
			(sheetname "")
		)
		(fill yes
			(thermal_gap 0.5)
			(thermal_bridge_width 0.5)
			(island_removal_mode 0)
		)
		(polygon
			(pts
				(arc
					(start 37.41801 -13.43406)
					(mid 37.03447 -13.8176)
					(end 37.41801 -14.20114)
				)
				(arc
					(start 38.281356 -14.20114)
					(mid 38.551824 -14.08979)
					(end 38.66515 -13.82014)
				)
				(arc
					(start 38.54831 -13.82014)
					(mid 38.28161 -14.084312)
					(end 38.01491 -13.82014)
				)
				(arc
					(start 37.68471 -13.82014)
					(mid 37.41801 -14.084312)
					(end 37.15131 -13.82014)
				)
				(arc
					(start 37.15131 -13.8176)
					(mid 37.41801 -13.5509)
					(end 37.68471 -13.8176)
				)
				(arc
					(start 38.01491 -13.8176)
					(mid 38.28161 -13.5509)
					(end 38.54831 -13.8176)
				)
				(arc
					(start 38.66515 -13.8176)
					(mid 38.552814 -13.546396)
					(end 38.28161 -13.43406)
				)
			)
		)
	)
	(zone
		(layers "F.Cu" "In4.Cu" "In7.Cu" "In9.Cu")
		(hatch none 0.5)
		(connect_pads
			(clearance 0)
		)
		(min_thickness 0.25)
		(keepout
			(tracks not_allowed)
			(vias allowed)
			(pads allowed)
			(copperpour not_allowed)
			(footprints allowed)
		)
		(placement
			(enabled no)
			(sheetname "")
		)
		(fill yes
			(thermal_gap 0.5)
			(thermal_bridge_width 0.5)
			(island_removal_mode 0)
		)
		(polygon
			(pts
				(arc
					(start 45.466 -13.4366)
					(mid 45.085 -13.8176)
					(end 45.466 -14.1986)
				)
				(arc
					(start 46.176946 -14.1986)
					(mid 46.445618 -14.087994)
					(end 46.5582 -13.82014)
				)
				(arc
					(start 46.4439 -13.82014)
					(mid 46.1772 -14.084312)
					(end 45.9105 -13.82014)
				)
				(arc
					(start 45.7327 -13.82014)
					(mid 45.466 -14.084312)
					(end 45.1993 -13.82014)
				)
				(arc
					(start 45.1993 -13.8176)
					(mid 45.466 -13.5509)
					(end 45.7327 -13.8176)
				)
				(arc
					(start 45.9105 -13.8176)
					(mid 46.1772 -13.5509)
					(end 46.4439 -13.8176)
				)
				(arc
					(start 46.5582 -13.8176)
					(mid 46.446608 -13.548192)
					(end 46.1772 -13.4366)
				)
			)
		)
	)
	(zone
		(layers "F.Cu" "In4.Cu" "In7.Cu" "In9.Cu")
		(hatch none 0.5)
		(connect_pads
			(clearance 0)
		)
		(min_thickness 0.25)
		(keepout
			(tracks not_allowed)
			(vias allowed)
			(pads allowed)
			(copperpour not_allowed)
			(footprints allowed)
		)
		(placement
			(enabled no)
			(sheetname "")
		)
		(fill yes
			(thermal_gap 0.5)
			(thermal_bridge_width 0.5)
			(island_removal_mode 0)
		)
		(polygon
			(pts
				(arc
					(start 53.862478 -35.313112)
					(mid 53.749692 -35.04146)
					(end 53.477668 -34.929572)
				)
				(arc
					(start 52.52339 -34.93262)
					(mid 52.14112 -35.31743)
					(end 52.52593 -35.6997)
				)
				(arc
					(start 53.479954 -35.696652)
					(mid 53.749603 -35.584855)
					(end 53.862478 -35.315652)
				)
				(arc
					(start 53.745638 -35.315652)
					(mid 53.480462 -35.57982)
					(end 53.212238 -35.3187)
				)
				(arc
					(start 52.79136 -35.3187)
					(mid 52.52466 -35.582872)
					(end 52.25796 -35.3187)
				)
				(arc
					(start 52.25796 -35.31616)
					(mid 52.52466 -35.04946)
					(end 52.79136 -35.31616)
				)
				(xy 53.212238 -35.31616) (xy 53.212238 -35.315652)
				(arc
					(start 53.212238 -35.313112)
					(mid 53.478938 -35.046412)
					(end 53.745638 -35.313112)
				)
			)
		)
	)
	(zone
		(layers "F.Cu" "In4.Cu" "In7.Cu" "In9.Cu")
		(hatch none 0.5)
		(connect_pads
			(clearance 0)
		)
		(min_thickness 0.25)
		(keepout
			(tracks not_allowed)
			(vias allowed)
			(pads allowed)
			(copperpour not_allowed)
			(footprints allowed)
		)
		(placement
			(enabled no)
			(sheetname "")
		)
		(fill yes
			(thermal_gap 0.5)
			(thermal_bridge_width 0.5)
			(island_removal_mode 0)
		)
		(polygon
			(pts
				(arc
					(start 29.4132 -14.19606)
					(mid 29.02966 -14.5796)
					(end 29.4132 -14.96314)
				)
				(arc
					(start 30.276546 -14.96314)
					(mid 30.547014 -14.85179)
					(end 30.66034 -14.58214)
				)
				(arc
					(start 30.5435 -14.58214)
					(mid 30.2768 -14.846312)
					(end 30.0101 -14.58214)
				)
				(arc
					(start 29.6799 -14.58214)
					(mid 29.4132 -14.846312)
					(end 29.1465 -14.58214)
				)
				(arc
					(start 29.1465 -14.5796)
					(mid 29.4132 -14.3129)
					(end 29.6799 -14.5796)
				)
				(arc
					(start 30.0101 -14.5796)
					(mid 30.2768 -14.3129)
					(end 30.5435 -14.5796)
				)
				(arc
					(start 30.66034 -14.5796)
					(mid 30.548004 -14.308396)
					(end 30.2768 -14.19606)
				)
			)
		)
	)
	(zone
		(layers "F.Cu" "In4.Cu" "In7.Cu" "In9.Cu")
		(hatch none 0.5)
		(connect_pads
			(clearance 0)
		)
		(min_thickness 0.25)
		(keepout
			(tracks not_allowed)
			(vias allowed)
			(pads allowed)
			(copperpour not_allowed)
			(footprints allowed)
		)
		(placement
			(enabled no)
			(sheetname "")
		)
		(fill yes
			(thermal_gap 0.5)
			(thermal_bridge_width 0.5)
			(island_removal_mode 0)
		)
		(polygon
			(pts
				(arc
					(start 80.2132 -14.19606)
					(mid 79.82966 -14.5796)
					(end 80.2132 -14.96314)
				)
				(arc
					(start 81.076546 -14.96314)
					(mid 81.347014 -14.85179)
					(end 81.46034 -14.58214)
				)
				(arc
					(start 81.3435 -14.58214)
					(mid 81.0768 -14.846312)
					(end 80.8101 -14.58214)
				)
				(arc
					(start 80.4799 -14.58214)
					(mid 80.2132 -14.846312)
					(end 79.9465 -14.58214)
				)
				(arc
					(start 79.9465 -14.5796)
					(mid 80.2132 -14.3129)
					(end 80.4799 -14.5796)
				)
				(arc
					(start 80.8101 -14.5796)
					(mid 81.0768 -14.3129)
					(end 81.3435 -14.5796)
				)
				(arc
					(start 81.46034 -14.5796)
					(mid 81.348004 -14.308396)
					(end 81.0768 -14.19606)
				)
			)
		)
	)
	(zone
		(layers "F.Cu" "In4.Cu" "In7.Cu" "In9.Cu")
		(hatch none 0.5)
		(connect_pads
			(clearance 0)
		)
		(min_thickness 0.25)
		(keepout
			(tracks not_allowed)
			(vias allowed)
			(pads allowed)
			(copperpour not_allowed)
			(footprints allowed)
		)
		(placement
			(enabled no)
			(sheetname "")
		)
		(fill yes
			(thermal_gap 0.5)
			(thermal_bridge_width 0.5)
			(island_removal_mode 0)
		)
		(polygon
			(pts
				(arc
					(start 25.4127 -13.43406)
					(mid 25.02916 -13.8176)
					(end 25.4127 -14.20114)
				)
				(arc
					(start 26.276046 -14.20114)
					(mid 26.546514 -14.08979)
					(end 26.65984 -13.82014)
				)
				(arc
					(start 26.543 -13.82014)
					(mid 26.2763 -14.084312)
					(end 26.0096 -13.82014)
				)
				(arc
					(start 25.6794 -13.82014)
					(mid 25.4127 -14.084312)
					(end 25.146 -13.82014)
				)
				(arc
					(start 25.146 -13.8176)
					(mid 25.4127 -13.5509)
					(end 25.6794 -13.8176)
				)
				(arc
					(start 26.0096 -13.8176)
					(mid 26.2763 -13.5509)
					(end 26.543 -13.8176)
				)
				(arc
					(start 26.65984 -13.8176)
					(mid 26.547504 -13.546396)
					(end 26.2763 -13.43406)
				)
			)
		)
	)
	(zone
		(layers "F.Cu" "In4.Cu" "In7.Cu" "In9.Cu")
		(hatch none 0.5)
		(connect_pads
			(clearance 0)
		)
		(min_thickness 0.25)
		(keepout
			(tracks not_allowed)
			(vias allowed)
			(pads allowed)
			(copperpour not_allowed)
			(footprints allowed)
		)
		(placement
			(enabled no)
			(sheetname "")
		)
		(fill yes
			(thermal_gap 0.5)
			(thermal_bridge_width 0.5)
			(island_removal_mode 0)
		)
		(polygon
			(pts
				(arc
					(start 43.25366 -12.21486)
					(mid 42.87012 -12.5984)
					(end 43.25366 -12.98194)
				)
				(arc
					(start 44.210986 -12.98194)
					(mid 44.481454 -12.87059)
					(end 44.59478 -12.60094)
				)
				(arc
					(start 44.47794 -12.60094)
					(mid 44.21124 -12.865112)
					(end 43.94454 -12.60094)
				)
				(arc
					(start 43.52036 -12.60094)
					(mid 43.25366 -12.865112)
					(end 42.98696 -12.60094)
				)
				(arc
					(start 42.98696 -12.5984)
					(mid 43.25366 -12.3317)
					(end 43.52036 -12.5984)
				)
				(arc
					(start 43.94454 -12.5984)
					(mid 44.21124 -12.3317)
					(end 44.47794 -12.5984)
				)
				(arc
					(start 44.59478 -12.5984)
					(mid 44.482444 -12.327196)
					(end 44.21124 -12.21486)
				)
			)
		)
	)
	(zone
		(layers "F.Cu" "In4.Cu" "In7.Cu" "In9.Cu")
		(hatch none 0.5)
		(connect_pads
			(clearance 0)
		)
		(min_thickness 0.25)
		(keepout
			(tracks not_allowed)
			(vias allowed)
			(pads allowed)
			(copperpour not_allowed)
			(footprints allowed)
		)
		(placement
			(enabled no)
			(sheetname "")
		)
		(fill yes
			(thermal_gap 0.5)
			(thermal_bridge_width 0.5)
			(island_removal_mode 0)
		)
		(polygon
			(pts
				(arc
					(start 41.418002 -13.43406)
					(mid 41.034462 -13.8176)
					(end 41.418002 -14.20114)
				)
				(arc
					(start 42.281348 -14.20114)
					(mid 42.551816 -14.08979)
					(end 42.665142 -13.82014)
				)
				(arc
					(start 42.548302 -13.82014)
					(mid 42.281602 -14.084312)
					(end 42.014902 -13.82014)
				)
				(arc
					(start 41.684702 -13.82014)
					(mid 41.418002 -14.084312)
					(end 41.151302 -13.82014)
				)
				(arc
					(start 41.151302 -13.8176)
					(mid 41.418002 -13.5509)
					(end 41.684702 -13.8176)
				)
				(arc
					(start 42.014902 -13.8176)
					(mid 42.281602 -13.5509)
					(end 42.548302 -13.8176)
				)
				(arc
					(start 42.665142 -13.8176)
					(mid 42.552806 -13.546396)
					(end 42.281602 -13.43406)
				)
			)
		)
	)
	(zone
		(layers "F.Cu" "In4.Cu" "In7.Cu" "In9.Cu")
		(hatch none 0.5)
		(connect_pads
			(clearance 0)
		)
		(min_thickness 0.25)
		(keepout
			(tracks not_allowed)
			(vias allowed)
			(pads allowed)
			(copperpour not_allowed)
			(footprints allowed)
		)
		(placement
			(enabled no)
			(sheetname "")
		)
		(fill yes
			(thermal_gap 0.5)
			(thermal_bridge_width 0.5)
			(island_removal_mode 0)
		)
		(polygon
			(pts
				(arc
					(start 72.847454 -14.32306)
					(mid 72.46366 -14.706473)
					(end 72.8472 -15.09014)
				)
				(arc
					(start 73.7108 -15.09014)
					(mid 73.981104 -14.9787)
					(end 74.09434 -14.70914)
				)
				(arc
					(start 73.9775 -14.70914)
					(mid 73.7108 -14.973312)
					(end 73.4441 -14.70914)
				)
				(arc
					(start 73.1139 -14.70914)
					(mid 72.8472 -14.973312)
					(end 72.5805 -14.70914)
				)
				(arc
					(start 72.5805 -14.7066)
					(mid 72.8472 -14.4399)
					(end 73.1139 -14.7066)
				)
				(arc
					(start 73.4441 -14.7066)
					(mid 73.7108 -14.4399)
					(end 73.9775 -14.7066)
				)
				(arc
					(start 74.09434 -14.7066)
					(mid 73.982004 -14.435396)
					(end 73.7108 -14.32306)
				)
			)
		)
	)
	(zone
		(layers "F.Cu" "In4.Cu" "In7.Cu" "In9.Cu")
		(hatch none 0.5)
		(connect_pads
			(clearance 0)
		)
		(min_thickness 0.25)
		(keepout
			(tracks not_allowed)
			(vias allowed)
			(pads allowed)
			(copperpour not_allowed)
			(footprints allowed)
		)
		(placement
			(enabled no)
			(sheetname "")
		)
		(fill yes
			(thermal_gap 0.5)
			(thermal_bridge_width 0.5)
			(island_removal_mode 0)
		)
		(polygon
			(pts
				(arc
					(start 77.419454 -14.19606)
					(mid 77.03566 -14.579473)
					(end 77.4192 -14.96314)
				)
				(arc
					(start 78.2828 -14.96314)
					(mid 78.553104 -14.8517)
					(end 78.66634 -14.58214)
				)
				(arc
					(start 78.5495 -14.58214)
					(mid 78.2828 -14.846312)
					(end 78.0161 -14.58214)
				)
				(arc
					(start 77.6859 -14.58214)
					(mid 77.4192 -14.846312)
					(end 77.1525 -14.58214)
				)
				(arc
					(start 77.1525 -14.5796)
					(mid 77.4192 -14.3129)
					(end 77.6859 -14.5796)
				)
				(arc
					(start 78.0161 -14.5796)
					(mid 78.2828 -14.3129)
					(end 78.5495 -14.5796)
				)
				(arc
					(start 78.66634 -14.5796)
					(mid 78.554004 -14.308396)
					(end 78.2828 -14.19606)
				)
			)
		)
	)
	(zone
		(layers "F.Cu" "In4.Cu" "In7.Cu" "In9.Cu")
		(hatch none 0.5)
		(connect_pads
			(clearance 0)
		)
		(min_thickness 0.25)
		(keepout
			(tracks not_allowed)
			(vias allowed)
			(pads allowed)
			(copperpour not_allowed)
			(footprints allowed)
		)
		(placement
			(enabled no)
			(sheetname "")
		)
		(fill yes
			(thermal_gap 0.5)
			(thermal_bridge_width 0.5)
			(island_removal_mode 0)
		)
		(polygon
			(pts
				(arc
					(start 49.295304 -20.0279)
					(mid 48.91151 -20.411313)
					(end 49.29505 -20.79498)
				)
				(arc
					(start 50.25263 -20.79498)
					(mid 50.522934 -20.68354)
					(end 50.63617 -20.41398)
				)
				(arc
					(start 50.51933 -20.41398)
					(mid 50.25263 -20.678152)
					(end 49.98593 -20.41398)
				)
				(arc
					(start 49.56175 -20.41398)
					(mid 49.29505 -20.678152)
					(end 49.02835 -20.41398)
				)
				(arc
					(start 49.02835 -20.41144)
					(mid 49.29505 -20.14474)
					(end 49.56175 -20.41144)
				)
				(arc
					(start 49.98593 -20.41144)
					(mid 50.25263 -20.14474)
					(end 50.51933 -20.41144)
				)
				(arc
					(start 50.63617 -20.41144)
					(mid 50.523834 -20.140236)
					(end 50.25263 -20.0279)
				)
			)
		)
	)
	(zone
		(layers "F.Cu" "In4.Cu" "In7.Cu" "In9.Cu")
		(hatch none 0.5)
		(connect_pads
			(clearance 0)
		)
		(min_thickness 0.25)
		(keepout
			(tracks not_allowed)
			(vias allowed)
			(pads allowed)
			(copperpour not_allowed)
			(footprints allowed)
		)
		(placement
			(enabled no)
			(sheetname "")
		)
		(fill yes
			(thermal_gap 0.5)
			(thermal_bridge_width 0.5)
			(island_removal_mode 0)
		)
		(polygon
			(pts
				(arc
					(start 33.4264 -14.19606)
					(mid 33.04286 -14.5796)
					(end 33.4264 -14.96314)
				)
				(arc
					(start 34.289746 -14.96314)
					(mid 34.560214 -14.85179)
					(end 34.67354 -14.58214)
				)
				(arc
					(start 34.5567 -14.58214)
					(mid 34.29 -14.846312)
					(end 34.0233 -14.58214)
				)
				(arc
					(start 33.6931 -14.58214)
					(mid 33.4264 -14.846312)
					(end 33.1597 -14.58214)
				)
				(arc
					(start 33.1597 -14.5796)
					(mid 33.4264 -14.3129)
					(end 33.6931 -14.5796)
				)
				(arc
					(start 34.0233 -14.5796)
					(mid 34.29 -14.3129)
					(end 34.5567 -14.5796)
				)
				(arc
					(start 34.67354 -14.5796)
					(mid 34.561204 -14.308396)
					(end 34.29 -14.19606)
				)
			)
		)
	)
	(zone
		(layer "B.Cu")
		(hatch none 0.5)
		(connect_pads
			(clearance 0)
		)
		(min_thickness 0.25)
		(keepout
			(tracks allowed)
			(vias allowed)
			(pads allowed)
			(copperpour allowed)
			(footprints allowed)
		)
		(placement
			(enabled no)
			(sheetname "")
		)
		(fill
			(thermal_gap 0.5)
			(thermal_bridge_width 0.5)
			(island_removal_mode 0)
		)
		(polygon
			(pts
				(xy 2.4384 -69.1896) (xy 2.4384 -53.3908) (xy 6.6548 -53.3908) (xy 6.6548 -69.1896)
			)
		)
	)
	(zone
		(layer "B.Cu")
		(hatch none 0.5)
		(connect_pads
			(clearance 0)
		)
		(min_thickness 0.25)
		(keepout
			(tracks not_allowed)
			(vias allowed)
			(pads allowed)
			(copperpour not_allowed)
			(footprints allowed)
		)
		(placement
			(enabled no)
			(sheetname "")
		)
		(fill
			(thermal_gap 0.5)
			(thermal_bridge_width 0.5)
			(island_removal_mode 0)
		)
		(polygon
			(pts
				(arc
					(start 29.4132 -14.19606)
					(mid 29.02966 -14.5796)
					(end 29.4132 -14.96314)
				)
				(arc
					(start 30.276546 -14.96314)
					(mid 30.66034 -14.579727)
					(end 30.2768 -14.19606)
				)
				(xy 30.099 -14.19606) (xy 30.099 -14.28496)
				(arc
					(start 30.155896 -14.341856)
					(mid 30.4654 -14.7682)
					(end 30.039056 -14.458696)
				)
				(xy 29.98216 -14.4018) (xy 29.9339 -14.35354) (xy 29.9339 -14.28496) (xy 29.9339 -14.19606) (xy 29.7561 -14.19606)
				(xy 29.7561 -14.28496) (xy 29.7561 -14.35354) (xy 29.70784 -14.4018)
				(arc
					(start 29.650944 -14.458696)
					(mid 29.2246 -14.7682)
					(end 29.534104 -14.341856)
				)
				(xy 29.591 -14.28496) (xy 29.591 -14.19606)
			)
		)
	)
	(zone
		(layer "B.Cu")
		(hatch none 0.5)
		(connect_pads
			(clearance 0)
		)
		(min_thickness 0.25)
		(keepout
			(tracks allowed)
			(vias allowed)
			(pads allowed)
			(copperpour allowed)
			(footprints not_allowed)
		)
		(placement
			(enabled no)
			(sheetname "")
		)
		(fill
			(thermal_gap 0.5)
			(thermal_bridge_width 0.5)
			(island_removal_mode 0)
		)
		(polygon
			(pts
				(xy 3.999992 -69.600064) (xy 3.999992 -14.699996)
				(arc
					(start 0.999998 -14.699996)
					(mid 0.292893 -14.992889)
					(end 0 -15.699994)
				)
				(arc
					(start 0 -72.799956)
					(mid 0.292893 -73.507061)
					(end 0.999998 -73.799954)
				)
				(xy 122.599958 -73.799954) (xy 122.599958 -69.600064) (xy 112.100106 -69.600064) (xy 112.100106 -72.300084)
				(xy 99.000056 -72.300084) (xy 99.000056 -69.600064)
			)
		)
	)
	(zone
		(layer "B.Cu")
		(hatch none 0.5)
		(connect_pads
			(clearance 0)
		)
		(min_thickness 0.25)
		(keepout
			(tracks not_allowed)
			(vias allowed)
			(pads allowed)
			(copperpour not_allowed)
			(footprints allowed)
		)
		(placement
			(enabled no)
			(sheetname "")
		)
		(fill
			(thermal_gap 0.5)
			(thermal_bridge_width 0.5)
			(island_removal_mode 0)
		)
		(polygon
			(pts
				(arc
					(start 69.52234 -27.52344)
					(mid 69.140705 -27.138123)
					(end 68.75526 -27.51963)
				)
				(xy 68.754498 -27.69235) (xy 68.851018 -27.69235)
				(arc
					(start 68.901056 -27.642312)
					(mid 69.3274 -27.332808)
					(end 69.017896 -27.759152)
				)
				(xy 68.967858 -27.80919) (xy 68.919598 -27.85745) (xy 68.851018 -27.85745) (xy 68.753736 -27.85745)
				(xy 68.752974 -28.03525) (xy 68.813426 -28.03525) (xy 68.882006 -28.03525) (xy 68.930266 -28.08351)
				(arc
					(start 69.014086 -28.16733)
					(mid 69.32359 -28.593674)
					(end 68.897246 -28.28417)
				)
				(xy 68.813426 -28.20035) (xy 68.752212 -28.20035)
				(arc
					(start 68.75145 -28.403296)
					(mid 69.133212 -28.788614)
					(end 69.51853 -28.406852)
				)
				(xy 69.51853 -28.405074) (xy 69.51853 -28.403296) (xy 69.5198 -28.08351) (xy 69.520054 -28.03525)
				(xy 69.52107 -27.80919)
			)
		)
	)
	(zone
		(net "P1V0_VIN")
		(layer "B.Cu")
		(hatch none 0.5)
		(connect_pads
			(clearance 0.5)
		)
		(min_thickness 0.25)
		(fill yes
			(thermal_gap 0.5)
			(thermal_bridge_width 0.5)
			(island_removal_mode 0)
		)
		(polygon
			(pts
				(xy 6.477 -26.162) (xy 5.842 -26.797) (xy 5.842 -29.083) (xy 5.969 -29.21) (xy 10.287 -29.21) (xy 11.176 -28.321)
				(xy 11.176 -26.543) (xy 10.795 -26.162)
			)
		)
	)
	(zone
		(net "VR_P1V1_PVIN")
		(layer "B.Cu")
		(hatch none 0.5)
		(connect_pads
			(clearance 0.5)
		)
		(min_thickness 0.25)
		(fill yes
			(thermal_gap 0.5)
			(thermal_bridge_width 0.5)
			(island_removal_mode 0)
		)
		(polygon
			(pts
				(xy 87.884 -65.532) (xy 87.757 -65.659) (xy 87.757 -67.564) (xy 88.138 -67.945) (xy 88.138 -70.104)
				(xy 88.9 -70.866) (xy 95.631 -70.866) (xy 95.885 -70.612) (xy 95.885 -68.834) (xy 95.8342 -68.7832)
				(xy 94.9198 -68.7832) (xy 94.8944 -68.7578) (xy 94.8944 -68.58) (xy 94.7674 -68.453) (xy 93.726 -68.453)
				(xy 93.599 -68.326) (xy 89.662 -68.326) (xy 89.408 -68.072) (xy 89.408 -67.564) (xy 89.281 -67.437)
				(xy 88.519 -67.437) (xy 88.392 -67.31) (xy 88.392 -66.675) (xy 88.519 -66.548) (xy 88.519 -65.659)
				(xy 88.392 -65.532)
			)
		)
	)
	(zone
		(net "GND")
		(layer "B.Cu")
		(hatch none 0.5)
		(connect_pads
			(clearance 0.5)
		)
		(min_thickness 0.25)
		(fill yes
			(thermal_gap 0.5)
			(thermal_bridge_width 0.5)
			(island_removal_mode 0)
		)
		(polygon
			(pts
				(xy 99.568 -25.273) (xy 99.187 -25.654) (xy 99.187 -26.797) (xy 99.568 -27.178) (xy 100.965 -27.178)
				(xy 101.854 -26.289) (xy 102.997 -26.289) (xy 103.124 -26.416) (xy 103.124 -27.051) (xy 103.251 -27.178)
				(xy 107.442 -27.178) (xy 107.569 -27.051) (xy 107.569 -25.4) (xy 107.442 -25.273)
			)
		)
		(polygon
			(pts
				(xy 107.061 -26.584402) (xy 106.553 -26.584402) (xy 106.553 -26.838402) (xy 107.061 -26.838402)
			)
		)
		(polygon
			(pts
				(xy 106.299 -26.584402) (xy 105.791 -26.584402) (xy 105.791 -26.838402) (xy 106.299 -26.838402)
			)
		)
		(polygon
			(pts
				(xy 105.537 -26.584402) (xy 105.029 -26.584402) (xy 105.029 -26.838402) (xy 105.537 -26.838402)
			)
		)
		(polygon
			(pts
				(xy 104.775 -26.584402) (xy 104.267 -26.584402) (xy 104.267 -26.838402) (xy 104.775 -26.838402)
			)
		)
		(polygon
			(pts
				(xy 104.013 -26.584402) (xy 103.505 -26.584402) (xy 103.505 -26.838402) (xy 104.013 -26.838402)
			)
		)
		(polygon
			(pts
				(xy 99.820984 -26.584402) (xy 99.566984 -26.584402) (xy 99.566984 -26.838402) (xy 99.820984 -26.838402)
			)
		)
		(polygon
			(pts
				(xy 100.582984 -26.482802) (xy 100.328984 -26.482802) (xy 100.328984 -26.584402) (xy 100.074984 -26.584402)
				(xy 100.074984 -26.838402) (xy 100.328984 -26.838402) (xy 100.328984 -26.736802) (xy 100.582984 -26.736802)
			)
		)
	)
	(zone
		(layer "B.Cu")
		(hatch none 0.5)
		(connect_pads
			(clearance 0)
		)
		(min_thickness 0.25)
		(keepout
			(tracks allowed)
			(vias allowed)
			(pads allowed)
			(copperpour allowed)
			(footprints not_allowed)
		)
		(placement
			(enabled no)
			(sheetname "")
		)
		(fill
			(thermal_gap 0.5)
			(thermal_bridge_width 0.5)
			(island_removal_mode 0)
		)
		(polygon
			(pts
				(xy 9.400032 -46.630082)
				(arc
					(start 11.599926 -46.630082)
					(mid 13.597494 -45.802662)
					(end 14.424914 -43.805094)
				)
				(arc
					(start 14.424914 -19.630136)
					(mid 13.606444 -17.616253)
					(end 11.599926 -16.780002)
				)
				(xy 9.400032 -16.780002) (xy 9.400032 -26.604976) (xy 6.999986 -26.604976) (xy 6.999986 -36.805108)
				(xy 9.400032 -36.805108)
			)
		)
	)
	(zone
		(net "GND")
		(layer "B.Cu")
		(hatch none 0.5)
		(connect_pads
			(clearance 0.5)
		)
		(min_thickness 0.25)
		(fill yes
			(thermal_gap 0.5)
			(thermal_bridge_width 0.5)
			(island_removal_mode 0)
		)
		(polygon
			(pts
				(xy 119.253 -52.324) (xy 112.141 -59.436) (xy 112.141 -62.611) (xy 112.395 -62.865) (xy 117.094 -62.865)
				(xy 117.856 -63.627) (xy 118.618 -63.627) (xy 119.253 -62.992) (xy 119.253 -58.547) (xy 119.8245 -57.9755)
				(xy 124.1425 -57.9755) (xy 125.984 -56.134) (xy 134.112 -56.134) (xy 134.9375 -56.9595) (xy 139.7635 -56.9595)
				(xy 140.081 -56.642) (xy 140.081 -56.261) (xy 139.7 -55.88) (xy 139.7 -53.34) (xy 138.811 -52.451)
				(xy 131.826 -52.451) (xy 130.302 -53.975) (xy 129.286 -53.975) (xy 127.635 -52.324)
			)
		)
		(polygon
			(pts
				(xy 118.8974 -61.722) (xy 118.6434 -61.722) (xy 118.6434 -61.976) (xy 118.8974 -61.976)
			)
		)
		(polygon
			(pts
				(xy 118.8974 -61.214) (xy 118.6434 -61.214) (xy 118.6434 -61.468) (xy 118.8974 -61.468)
			)
		)
		(polygon
			(pts
				(xy 118.4529 -60.96) (xy 118.1989 -60.96) (xy 118.1989 -61.214) (xy 118.4529 -61.214)
			)
		)
		(polygon
			(pts
				(xy 118.4529 -59.563) (xy 118.1989 -59.563) (xy 118.1989 -60.198) (xy 118.4529 -60.198)
			)
		)
		(polygon
			(pts
				(xy 118.4529 -58.547) (xy 118.1989 -58.547) (xy 118.1989 -58.801) (xy 118.4529 -58.801)
			)
		)
		(polygon
			(pts
				(xy 133.35 -55.2069) (xy 133.096 -55.2069) (xy 133.096 -55.4609) (xy 133.35 -55.4609)
			)
		)
		(polygon
			(pts
				(xy 132.334 -55.2069) (xy 131.826 -55.2069) (xy 131.826 -55.4609) (xy 132.334 -55.4609)
			)
		)
		(polygon
			(pts
				(xy 131.064 -55.2069) (xy 130.556 -55.2069) (xy 130.556 -55.4609) (xy 131.064 -55.4609)
			)
		)
		(polygon
			(pts
				(xy 129.794 -55.2069) (xy 129.159 -55.2069) (xy 129.159 -55.4609) (xy 129.794 -55.4609)
			)
		)
		(polygon
			(pts
				(xy 128.397 -55.2069) (xy 128.143 -55.2069) (xy 128.143 -55.4609) (xy 128.397 -55.4609)
			)
		)
	)
	(zone
		(net "P3V3")
		(layer "B.Cu")
		(hatch none 0.5)
		(connect_pads
			(clearance 0.5)
		)
		(min_thickness 0.25)
		(fill yes
			(thermal_gap 0.5)
			(thermal_bridge_width 0.5)
			(island_removal_mode 0)
		)
		(polygon
			(pts
				(xy 12.4714 -63.627) (xy 12.3444 -63.754) (xy 12.3444 -65.2018) (xy 12.4206 -65.278) (xy 13.97 -65.278)
				(xy 14.224 -65.532) (xy 14.224 -66.929) (xy 14.097 -67.056) (xy 12.4714 -67.056) (xy 12.3571 -67.1703)
				(xy 12.3571 -68.7451) (xy 12.573 -68.961) (xy 13.843 -68.961) (xy 13.8557 -68.9483) (xy 14.6177 -68.9483)
				(xy 15.113 -68.453) (xy 15.113 -67.818) (xy 15.367 -67.564) (xy 15.621 -67.564) (xy 15.748 -67.437)
				(xy 15.748 -63.754) (xy 15.621 -63.627)
			)
		)
		(polygon
			(pts
				(xy 15.3924 -66.5988) (xy 15.1384 -66.5988) (xy 15.1384 -67.1322) (xy 15.3924 -67.1322)
			)
		)
		(polygon
			(pts
				(xy 15.3924 -66.0908) (xy 15.1384 -66.0908) (xy 15.1384 -66.3448) (xy 15.3924 -66.3448)
			)
		)
	)
	(zone
		(layer "B.Cu")
		(hatch none 0.5)
		(connect_pads
			(clearance 0)
		)
		(min_thickness 0.25)
		(keepout
			(tracks not_allowed)
			(vias allowed)
			(pads allowed)
			(copperpour not_allowed)
			(footprints allowed)
		)
		(placement
			(enabled no)
			(sheetname "")
		)
		(fill
			(thermal_gap 0.5)
			(thermal_bridge_width 0.5)
			(island_removal_mode 0)
		)
		(polygon
			(pts
				(xy 80.34655 -14.19606)
				(arc
					(start 80.34655 -14.348714)
					(mid 80.159134 -14.840871)
					(end 80.18145 -14.314678)
				)
				(arc
					(start 80.18145 -14.19733)
					(mid 79.829943 -14.595489)
					(end 80.2132 -14.96314)
				)
				(arc
					(start 81.076546 -14.96314)
					(mid 81.46026 -14.595614)
					(end 81.10855 -14.19733)
				)
				(arc
					(start 81.10855 -14.314678)
					(mid 81.130873 -14.840903)
					(end 80.94345 -14.348714)
				)
				(xy 80.94345 -14.19606)
			)
		)
	)
	(zone
		(net "P3V3")
		(layer "B.Cu")
		(hatch none 0.5)
		(connect_pads
			(clearance 0.5)
		)
		(min_thickness 0.25)
		(fill yes
			(thermal_gap 0.5)
			(thermal_bridge_width 0.5)
			(island_removal_mode 0)
		)
		(polygon
			(pts
				(xy 14.605 -48.26) (xy 14.478 -48.387) (xy 14.478 -49.276) (xy 14.224 -49.53) (xy 12.573 -49.53)
				(xy 12.3952 -49.7078) (xy 12.3952 -50.6984) (xy 12.4206 -50.7238) (xy 14.2748 -50.7238) (xy 14.605 -51.054)
				(xy 17.653 -51.054) (xy 18.288 -50.419) (xy 18.288 -48.895) (xy 17.653 -48.26)
			)
		)
		(polygon
			(pts
				(xy 16.891 -49.9999) (xy 16.383 -49.9999) (xy 16.383 -50.2539) (xy 16.891 -50.2539)
			)
		)
		(polygon
			(pts
				(xy 15.621 -49.9999) (xy 15.367 -49.9999) (xy 15.367 -50.2539) (xy 15.621 -50.2539)
			)
		)
		(polygon
			(pts
				(xy 17.526 -48.6156) (xy 17.272 -48.6156) (xy 17.272 -48.8696) (xy 17.526 -48.8696)
			)
		)
		(polygon
			(pts
				(xy 17.018 -48.6156) (xy 16.51 -48.6156) (xy 16.51 -48.8696) (xy 17.018 -48.8696)
			)
		)
		(polygon
			(pts
				(xy 16.256 -48.6156) (xy 15.748 -48.6156) (xy 15.748 -48.8696) (xy 16.256 -48.8696)
			)
		)
		(polygon
			(pts
				(xy 15.494 -48.6156) (xy 14.986 -48.6156) (xy 14.986 -48.8696) (xy 15.494 -48.8696)
			)
		)
	)
	(zone
		(net "P1V0")
		(layer "B.Cu")
		(hatch none 0.5)
		(connect_pads
			(clearance 0.5)
		)
		(min_thickness 0.25)
		(fill yes
			(thermal_gap 0.5)
			(thermal_bridge_width 0.5)
			(island_removal_mode 0)
		)
		(polygon
			(pts
				(xy 101.854 -42.688002) (xy 101.727 -42.815002) (xy 101.727 -43.053) (xy 101.464872 -43.315128)
				(xy 101.100128 -43.315128) (xy 101.092 -43.323002) (xy 99.7585 -43.323002) (xy 99.60102 -43.480482)
				(xy 99.60102 -43.87088) (xy 99.48672 -43.98518) (xy 99.13874 -43.98518) (xy 98.890836 -44.233084)
				(xy 98.890836 -44.550584) (xy 98.933 -44.593002) (xy 100.07092 -44.593002) (xy 100.196142 -44.46778)
				(xy 100.203 -44.46778) (xy 100.24364 -44.42714) (xy 100.24364 -44.1706) (xy 100.44684 -43.9674)
				(xy 102.36708 -43.9674) (xy 102.57282 -44.17314) (xy 102.57282 -44.86656) (xy 102.68712 -44.98086)
				(xy 103.15194 -44.98086) (xy 103.251 -44.8818) (xy 103.251 -43.815) (xy 103.013002 -43.577002) (xy 102.59314 -43.577002)
				(xy 102.235 -43.218862) (xy 102.235 -42.815002) (xy 102.108 -42.688002)
			)
		)
	)
	(zone
		(layer "B.Cu")
		(hatch none 0.5)
		(connect_pads
			(clearance 0)
		)
		(min_thickness 0.25)
		(keepout
			(tracks allowed)
			(vias allowed)
			(pads allowed)
			(copperpour allowed)
			(footprints allowed)
		)
		(placement
			(enabled no)
			(sheetname "")
		)
		(fill
			(thermal_gap 0.5)
			(thermal_bridge_width 0.5)
			(island_removal_mode 0)
		)
		(polygon
			(pts
				(xy 151.257 -50.038) (xy 151.257 -46.4312) (xy 155.8671 -46.4312) (xy 155.8671 -50.038)
			)
		)
	)
	(zone
		(layer "B.Cu")
		(hatch none 0.5)
		(connect_pads
			(clearance 0)
		)
		(min_thickness 0.25)
		(keepout
			(tracks allowed)
			(vias allowed)
			(pads allowed)
			(copperpour allowed)
			(footprints allowed)
		)
		(placement
			(enabled no)
			(sheetname "")
		)
		(fill
			(thermal_gap 0.5)
			(thermal_bridge_width 0.5)
			(island_removal_mode 0)
		)
		(polygon
			(pts
				(xy 190.373 -14.479778) (xy 190.373 -6.605778) (xy 195.834 -6.605778) (xy 195.834 -14.479778)
			)
		)
	)
	(zone
		(net "GND")
		(layer "B.Cu")
		(hatch none 0.5)
		(connect_pads
			(clearance 0.5)
		)
		(min_thickness 0.25)
		(fill yes
			(thermal_gap 0.5)
			(thermal_bridge_width 0.5)
			(island_removal_mode 0)
		)
		(polygon
			(pts
				(xy 47.879 -11.176) (xy 46.736 -12.319) (xy 46.736 -13.208) (xy 46.863 -13.335) (xy 48.387 -13.335)
				(xy 48.514 -13.462) (xy 49.022 -13.462) (xy 49.276 -13.208) (xy 50.419 -13.208) (xy 50.8 -13.589)
				(xy 50.8 -13.97) (xy 50.419 -14.351) (xy 48.895 -14.351) (xy 48.768 -14.478) (xy 48.768 -15.113)
				(xy 48.895 -15.24) (xy 50.038 -15.24) (xy 50.546 -15.748) (xy 50.546 -16.256) (xy 49.784 -17.018)
				(xy 49.784 -17.526) (xy 49.911 -17.653) (xy 50.165 -17.653) (xy 50.292 -17.526) (xy 50.292 -17.272)
				(xy 50.673 -16.891) (xy 52.324 -16.891) (xy 52.578 -17.145) (xy 52.578 -19.812) (xy 52.705 -19.939)
				(xy 53.213 -19.939) (xy 53.34 -19.812) (xy 53.34 -16.891) (xy 53.848 -16.383) (xy 53.848 -14.351)
				(xy 53.721 -14.224) (xy 53.34 -14.224) (xy 53.086 -14.478) (xy 51.943 -14.478) (xy 51.689 -14.224)
				(xy 51.689 -11.43) (xy 51.435 -11.176)
			)
		)
		(polygon
			(pts
				(xy 52.9844 -18.923) (xy 52.7304 -18.923) (xy 52.7304 -19.431) (xy 52.9844 -19.431)
			)
		)
		(polygon
			(pts
				(xy 52.9844 -18.161) (xy 52.7304 -18.161) (xy 52.7304 -18.669) (xy 52.9844 -18.669)
			)
		)
		(polygon
			(pts
				(xy 52.9844 -17.399) (xy 52.7304 -17.399) (xy 52.7304 -17.907) (xy 52.9844 -17.907)
			)
		)
		(polygon
			(pts
				(xy 52.9844 -16.891) (xy 52.7304 -16.891) (xy 52.7304 -17.145) (xy 52.9844 -17.145)
			)
		)
		(polygon
			(pts
				(xy 52.324 -16.2814) (xy 52.07 -16.2814) (xy 52.07 -16.5354) (xy 52.324 -16.5354)
			)
		)
		(polygon
			(pts
				(xy 51.816 -16.2814) (xy 51.308 -16.2814) (xy 51.308 -16.5354) (xy 51.816 -16.5354)
			)
		)
		(polygon
			(pts
				(xy 51.054 -16.2814) (xy 50.8 -16.2814) (xy 50.8 -16.5354) (xy 51.054 -16.5354)
			)
		)
		(polygon
			(pts
				(xy 49.4792 -14.732) (xy 49.2252 -14.732) (xy 49.2252 -14.986) (xy 49.4792 -14.986)
			)
		)
	)
	(zone
		(net "PV_VDDR")
		(layer "B.Cu")
		(hatch none 0.5)
		(connect_pads
			(clearance 0.5)
		)
		(min_thickness 0.25)
		(fill yes
			(thermal_gap 0.5)
			(thermal_bridge_width 0.5)
			(island_removal_mode 0)
		)
		(polygon
			(pts
				(xy 99.4664 -44.8564) (xy 99.3394 -44.9834) (xy 99.3394 -45.7708) (xy 98.933 -46.1772) (xy 98.933 -47.752)
				(xy 99.187 -48.006) (xy 99.553268 -48.006) (xy 99.553268 -48.00727) (xy 100.36556 -48.819562) (xy 100.36556 -51.169316)
				(xy 100.45954 -51.263296) (xy 105.095294 -51.263296) (xy 106.420666 -52.588668) (xy 108.706666 -52.588668)
				(xy 109.084872 -52.967128) (xy 110.100872 -52.967128) (xy 110.49 -52.578) (xy 110.49 -51.181) (xy 110.617 -51.054)
				(xy 110.617 -50.673) (xy 110.363 -50.419) (xy 110.363 -48.26) (xy 110.49 -48.133) (xy 110.49 -47.752)
				(xy 109.255814 -46.517814) (xy 108.112814 -46.517814) (xy 108.077 -46.482) (xy 107.509564 -46.482)
				(xy 107.503468 -46.488096) (xy 106.131868 -46.488096) (xy 106.014774 -46.371002) (xy 104.219502 -46.371002)
				(xy 103.01986 -45.17136) (xy 102.6541 -45.17136) (xy 102.54234 -45.28312) (xy 102.54234 -45.29074)
				(xy 102.36708 -45.466) (xy 101.5746 -45.466) (xy 101.2444 -45.7962) (xy 100.33 -45.7962) (xy 100.2284 -45.6946)
				(xy 100.2284 -44.958) (xy 100.1268 -44.8564)
			)
		)
		(polygon
			(pts
				(xy 107.823 -51.984402) (xy 107.569 -51.984402) (xy 107.569 -52.238402) (xy 107.823 -52.238402)
			)
		)
		(polygon
			(pts
				(xy 107.061 -51.9684) (xy 106.807 -51.9684) (xy 106.807 -52.2224) (xy 107.061 -52.2224) (xy 107.061 -52.238402)
				(xy 107.315 -52.238402) (xy 107.315 -51.984402) (xy 107.061 -51.984402)
			)
		)
		(polygon
			(pts
				(xy 106.553 -51.9684) (xy 106.299 -51.9684) (xy 106.299 -52.2224) (xy 106.553 -52.2224)
			)
		)
		(polygon
			(pts
				(xy 110.2614 -50.943002) (xy 110.0074 -50.943002) (xy 110.0074 -51.197002) (xy 110.2614 -51.197002)
			)
		)
		(polygon
			(pts
				(xy 103.886 -50.714402) (xy 103.378 -50.714402) (xy 103.378 -50.968402) (xy 103.886 -50.968402)
			)
		)
		(polygon
			(pts
				(xy 103.124 -50.714402) (xy 102.616 -50.714402) (xy 102.616 -50.968402) (xy 103.124 -50.968402)
			)
		)
		(polygon
			(pts
				(xy 102.362 -50.714402) (xy 101.854 -50.714402) (xy 101.854 -50.968402) (xy 102.362 -50.968402)
			)
		)
		(polygon
			(pts
				(xy 101.6 -50.714402) (xy 101.346 -50.714402) (xy 101.346 -50.968402) (xy 101.6 -50.968402)
			)
		)
		(polygon
			(pts
				(xy 101.13518 -50.191162) (xy 100.88118 -50.191162) (xy 100.711 -50.4698) (xy 100.711 -50.7238)
				(xy 100.965 -50.7238) (xy 101.13518 -50.445162)
			)
		)
		(polygon
			(pts
				(xy 107.351068 -46.843696) (xy 107.097068 -46.843696) (xy 107.097068 -47.097696) (xy 107.351068 -47.097696)
			)
		)
		(polygon
			(pts
				(xy 106.843068 -46.843696) (xy 106.589068 -46.843696) (xy 106.589068 -47.097696) (xy 106.843068 -47.097696)
			)
		)
	)
	(zone
		(layer "B.Cu")
		(hatch none 0.5)
		(connect_pads
			(clearance 0)
		)
		(min_thickness 0.25)
		(keepout
			(tracks not_allowed)
			(vias allowed)
			(pads allowed)
			(copperpour not_allowed)
			(footprints allowed)
		)
		(placement
			(enabled no)
			(sheetname "")
		)
		(fill
			(thermal_gap 0.5)
			(thermal_bridge_width 0.5)
			(island_removal_mode 0)
		)
		(polygon
			(pts
				(arc
					(start 49.295304 -20.0279)
					(mid 48.91151 -20.411313)
					(end 49.29505 -20.79498)
				)
				(arc
					(start 50.25263 -20.79498)
					(mid 50.63617 -20.41144)
					(end 50.25263 -20.0279)
				)
				(xy 50.02784 -20.0279) (xy 50.02784 -20.06981)
				(arc
					(start 50.131726 -20.173696)
					(mid 50.44123 -20.60004)
					(end 50.014886 -20.290536)
				)
				(xy 49.911 -20.18665) (xy 49.86274 -20.13839) (xy 49.86274 -20.06981) (xy 49.86274 -20.0279) (xy 49.68494 -20.0279)
				(xy 49.68494 -20.06981) (xy 49.68494 -20.13839) (xy 49.63668 -20.18665)
				(arc
					(start 49.532794 -20.290536)
					(mid 49.10645 -20.60004)
					(end 49.415954 -20.173696)
				)
				(xy 49.51984 -20.06981) (xy 49.51984 -20.0279)
			)
		)
	)
	(zone
		(layer "B.Cu")
		(hatch none 0.5)
		(connect_pads
			(clearance 0)
		)
		(min_thickness 0.25)
		(keepout
			(tracks not_allowed)
			(vias allowed)
			(pads allowed)
			(copperpour not_allowed)
			(footprints allowed)
		)
		(placement
			(enabled no)
			(sheetname "")
		)
		(fill
			(thermal_gap 0.5)
			(thermal_bridge_width 0.5)
			(island_removal_mode 0)
		)
		(polygon
			(pts
				(xy 45.54855 -13.4366)
				(arc
					(start 45.54855 -13.564108)
					(mid 45.466 -14.084195)
					(end 45.38345 -13.564108)
				)
				(arc
					(start 45.38345 -13.445744)
					(mid 45.087361 -13.859122)
					(end 45.466 -14.1986)
				)
				(arc
					(start 46.176946 -14.1986)
					(mid 46.552103 -13.885485)
					(end 46.31055 -13.46073)
				)
				(arc
					(start 46.31055 -13.586714)
					(mid 46.123134 -14.078871)
					(end 46.14545 -13.552678)
				)
				(xy 46.14545 -13.4366)
			)
		)
	)
	(zone
		(layer "B.Cu")
		(hatch none 0.5)
		(connect_pads
			(clearance 0)
		)
		(min_thickness 0.25)
		(keepout
			(tracks not_allowed)
			(vias allowed)
			(pads allowed)
			(copperpour not_allowed)
			(footprints allowed)
		)
		(placement
			(enabled no)
			(sheetname "")
		)
		(fill
			(thermal_gap 0.5)
			(thermal_bridge_width 0.5)
			(island_removal_mode 0)
		)
		(polygon
			(pts
				(xy 45.731684 -44.27982) (xy 45.731684 -44.316904)
				(arc
					(start 45.947838 -44.32173)
					(mid 46.340014 -43.946826)
					(end 45.96511 -43.55465)
				)
				(arc
					(start 45.007276 -43.53306)
					(mid 44.615103 -43.907837)
					(end 44.98975 -44.30014)
				)
				(xy 45.223684 -44.305474) (xy 45.223684 -44.258738)
				(arc
					(start 45.11929 -44.154344)
					(mid 44.809786 -43.728)
					(end 45.23613 -44.037504)
				)
				(xy 45.340524 -44.141898) (xy 45.388784 -44.190158) (xy 45.388784 -44.258738) (xy 45.388784 -44.30903)
				(xy 45.566584 -44.313094) (xy 45.566584 -44.27982) (xy 45.566584 -44.21124) (xy 45.614844 -44.16298)
				(arc
					(start 45.71873 -44.059094)
					(mid 46.145074 -43.74959)
					(end 45.83557 -44.175934)
				)
			)
		)
	)
	(zone
		(layer "B.Cu")
		(hatch none 0.5)
		(connect_pads
			(clearance 0)
		)
		(min_thickness 0.25)
		(keepout
			(tracks not_allowed)
			(vias allowed)
			(pads allowed)
			(copperpour not_allowed)
			(footprints allowed)
		)
		(placement
			(enabled no)
			(sheetname "")
		)
		(fill
			(thermal_gap 0.5)
			(thermal_bridge_width 0.5)
			(island_removal_mode 0)
		)
		(polygon
			(pts
				(arc
					(start 53.535326 -28.897834)
					(mid 53.151786 -28.514294)
					(end 52.768246 -28.897834)
				)
				(xy 52.768246 -29.11475) (xy 52.81803 -29.11475)
				(arc
					(start 52.914042 -29.018738)
					(mid 53.340386 -28.709234)
					(end 53.030882 -29.135578)
				)
				(xy 52.93487 -29.23159) (xy 52.88661 -29.27985) (xy 52.81803 -29.27985) (xy 52.768246 -29.27985)
				(xy 52.768246 -29.45765) (xy 52.830476 -29.45765) (xy 52.899056 -29.45765) (xy 52.947316 -29.50591)
				(arc
					(start 53.030882 -29.589476)
					(mid 53.340386 -30.01582)
					(end 52.914042 -29.706316)
				)
				(xy 52.830476 -29.62275) (xy 52.768246 -29.62275)
				(arc
					(start 52.768246 -29.826966)
					(mid 53.151659 -30.21076)
					(end 53.535326 -29.82722)
				)
			)
		)
	)
	(zone
		(net "TPS74801_P1V35_IN")
		(layer "B.Cu")
		(hatch none 0.5)
		(connect_pads
			(clearance 0.5)
		)
		(min_thickness 0.25)
		(fill yes
			(thermal_gap 0.5)
			(thermal_bridge_width 0.5)
			(island_removal_mode 0)
		)
		(polygon
			(pts
				(xy 80.137 -15.2146) (xy 79.502 -15.8496) (xy 78.486 -15.8496) (xy 78.105 -15.4686) (xy 77.47 -15.4686)
				(xy 77.216 -15.7226) (xy 77.216 -20.1676) (xy 77.343 -20.2946) (xy 77.978 -20.2946) (xy 78.359 -19.9136)
				(xy 78.359 -18.5166) (xy 78.5622 -18.3134) (xy 80.2132 -18.3134) (xy 80.264 -18.2626) (xy 80.264 -16.6116)
				(xy 80.645 -16.2306) (xy 81.026 -16.2306) (xy 81.153 -16.1036) (xy 81.153 -15.3416) (xy 81.026 -15.2146)
			)
		)
		(polygon
			(pts
				(xy 78.1431 -19.1008) (xy 77.8891 -19.1008) (xy 77.8891 -19.3548) (xy 78.1431 -19.3548)
			)
		)
		(polygon
			(pts
				(xy 79.248 -16.2306) (xy 78.994 -16.2306) (xy 78.994 -16.4846) (xy 79.248 -16.4846)
			)
		)
		(polygon
			(pts
				(xy 78.74 -16.2306) (xy 78.486 -16.2306) (xy 78.486 -16.4846) (xy 78.74 -16.4846)
			)
		)
	)
	(zone
		(net "GND")
		(layer "B.Cu")
		(hatch none 0.5)
		(connect_pads
			(clearance 0.5)
		)
		(min_thickness 0.25)
		(fill yes
			(thermal_gap 0.5)
			(thermal_bridge_width 0.5)
			(island_removal_mode 0)
		)
		(polygon
			(pts
				(xy 60.071 -46.863) (xy 58.42 -48.514) (xy 58.42 -50.419) (xy 59.69 -51.689) (xy 59.69 -53.086)
				(xy 55.245 -57.531) (xy 53.975 -57.531) (xy 52.324 -55.88) (xy 52.07 -55.88) (xy 51.816 -56.134)
				(xy 51.816 -56.388) (xy 52.959 -57.531) (xy 52.959 -59.69) (xy 52.451 -60.198) (xy 48.514 -60.198)
				(xy 47.9425 -59.6265) (xy 47.9425 -57.4675) (xy 46.482 -56.007) (xy 35.687 -56.007) (xy 35.306 -56.388)
				(xy 30.226 -56.388) (xy 28.956 -57.658) (xy 28.575 -57.658) (xy 27.94 -57.023) (xy 25.273 -57.023)
				(xy 25.146 -57.15) (xy 25.146 -57.404) (xy 24.892 -57.658) (xy 24.003 -56.769) (xy 23.368 -56.769)
				(xy 22.987 -56.388) (xy 21.463 -56.388) (xy 19.812 -54.737) (xy 19.812 -53.848) (xy 18.923 -52.959)
				(xy 18.161 -52.959) (xy 17.145 -53.975) (xy 14.478 -53.975) (xy 14.351 -54.102) (xy 14.351 -54.483)
				(xy 14.478 -54.61) (xy 16.637 -54.61) (xy 16.891 -54.864) (xy 16.891 -55.626) (xy 17.018 -55.753)
				(xy 18.542 -55.753) (xy 18.669 -55.626) (xy 19.177 -55.626) (xy 19.685 -56.134) (xy 19.685 -58.42)
				(xy 20.32 -59.055) (xy 20.32 -59.69) (xy 20.447 -59.817) (xy 21.082 -59.817) (xy 21.209 -59.944)
				(xy 21.209 -60.833) (xy 21.336 -60.96) (xy 22.733 -60.96) (xy 22.987 -61.214) (xy 22.987 -64.77)
				(xy 22.86 -64.897) (xy 22.225 -64.897) (xy 22.098 -65.024) (xy 22.098 -67.945) (xy 23.241 -69.088)
				(xy 29.591 -69.088) (xy 30.099 -69.596) (xy 34.798 -69.596) (xy 38.862 -65.532) (xy 38.862 -63.881)
				(xy 39.116 -63.627) (xy 42.545 -63.627) (xy 42.799 -63.881) (xy 42.799 -67.183) (xy 43.053 -67.437)
				(xy 63.246 -67.437) (xy 64.516 -66.167) (xy 64.516 -63.246) (xy 64.008 -62.738) (xy 57.15 -62.738)
				(xy 56.515 -62.103) (xy 56.515 -59.436) (xy 61.5315 -54.4195) (xy 61.5315 -49.7205) (xy 60.452 -48.641)
				(xy 60.452 -46.99) (xy 60.325 -46.863)
			)
		)
		(polygon
			(pts
				(xy 22.733 -65.3542) (xy 22.479 -65.3542) (xy 22.479 -65.6082) (xy 22.733 -65.6082)
			)
		)
		(polygon
			(pts
				(xy 26.7208 -64.897) (xy 26.4668 -64.897) (xy 26.4668 -65.151) (xy 26.7208 -65.151)
			)
		)
		(polygon
			(pts
				(xy 26.7208 -64.389) (xy 26.4668 -64.389) (xy 26.4668 -64.643) (xy 26.7208 -64.643)
			)
		)
		(polygon
			(pts
				(xy 22.7838 -60.2488) (xy 22.5298 -60.2488) (xy 22.5298 -60.5028) (xy 22.7838 -60.5028)
			)
		)
		(polygon
			(pts
				(xy 22.2758 -60.2488) (xy 22.0218 -60.2488) (xy 22.0218 -60.3504) (xy 21.7678 -60.3504) (xy 21.7678 -60.6044)
				(xy 22.0218 -60.6044) (xy 22.0218 -60.5028) (xy 22.2758 -60.5028)
			)
		)
		(polygon
			(pts
				(xy 21.082 -59.2074) (xy 20.828 -59.2074) (xy 20.828 -59.4614) (xy 21.082 -59.4614)
			)
		)
		(polygon
			(pts
				(xy 23.9522 -57.2262) (xy 23.6982 -57.2262) (xy 23.6982 -57.4802) (xy 23.9522 -57.4802)
			)
		)
		(polygon
			(pts
				(xy 23.1902 -57.1881) (xy 22.9362 -57.1881) (xy 22.9362 -57.4421) (xy 23.1902 -57.4421) (xy 23.1902 -57.4802)
				(xy 23.4442 -57.4802) (xy 23.4442 -57.2262) (xy 23.1902 -57.2262)
			)
		)
		(polygon
			(pts
				(xy 22.1742 -57.1881) (xy 21.9202 -57.1881) (xy 21.9202 -57.4421) (xy 22.1742 -57.4421)
			)
		)
	)
	(zone
		(layer "B.Cu")
		(hatch none 0.5)
		(connect_pads
			(clearance 0)
		)
		(min_thickness 0.25)
		(keepout
			(tracks not_allowed)
			(vias allowed)
			(pads allowed)
			(copperpour not_allowed)
			(footprints allowed)
		)
		(placement
			(enabled no)
			(sheetname "")
		)
		(fill
			(thermal_gap 0.5)
			(thermal_bridge_width 0.5)
			(island_removal_mode 0)
		)
		(polygon
			(pts
				(arc
					(start 33.4264 -14.19606)
					(mid 33.04286 -14.5796)
					(end 33.4264 -14.96314)
				)
				(arc
					(start 34.289746 -14.96314)
					(mid 34.67354 -14.579727)
					(end 34.29 -14.19606)
				)
				(xy 34.1122 -14.19606) (xy 34.1122 -14.28496)
				(arc
					(start 34.169096 -14.341856)
					(mid 34.4786 -14.7682)
					(end 34.052256 -14.458696)
				)
				(xy 33.99536 -14.4018) (xy 33.9471 -14.35354) (xy 33.9471 -14.28496) (xy 33.9471 -14.19606) (xy 33.7693 -14.19606)
				(xy 33.7693 -14.28496) (xy 33.7693 -14.35354) (xy 33.72104 -14.4018)
				(arc
					(start 33.664144 -14.458696)
					(mid 33.2378 -14.7682)
					(end 33.547304 -14.341856)
				)
				(xy 33.6042 -14.28496) (xy 33.6042 -14.19606)
			)
		)
	)
	(zone
		(layer "B.Cu")
		(hatch none 0.5)
		(connect_pads
			(clearance 0)
		)
		(min_thickness 0.25)
		(keepout
			(tracks not_allowed)
			(vias allowed)
			(pads allowed)
			(copperpour not_allowed)
			(footprints allowed)
		)
		(placement
			(enabled no)
			(sheetname "")
		)
		(fill
			(thermal_gap 0.5)
			(thermal_bridge_width 0.5)
			(island_removal_mode 0)
		)
		(polygon
			(pts
				(xy 68.15455 -14.22146)
				(arc
					(start 68.15455 -14.351508)
					(mid 68.072 -14.871595)
					(end 67.98945 -14.351508)
				)
				(arc
					(start 67.98945 -14.23035)
					(mid 67.690617 -14.646519)
					(end 68.072 -14.98854)
				)
				(arc
					(start 68.834 -14.98854)
					(mid 69.215287 -14.646508)
					(end 68.91655 -14.23035)
				)
				(arc
					(start 68.91655 -14.351508)
					(mid 68.834 -14.871595)
					(end 68.75145 -14.351508)
				)
				(xy 68.75145 -14.22146)
			)
		)
	)
	(zone
		(layer "B.Cu")
		(hatch none 0.5)
		(connect_pads
			(clearance 0)
		)
		(min_thickness 0.25)
		(keepout
			(tracks not_allowed)
			(vias allowed)
			(pads allowed)
			(copperpour not_allowed)
			(footprints allowed)
		)
		(placement
			(enabled no)
			(sheetname "")
		)
		(fill
			(thermal_gap 0.5)
			(thermal_bridge_width 0.5)
			(island_removal_mode 0)
		)
		(polygon
			(pts
				(xy 37.55136 -13.43406)
				(arc
					(start 37.55136 -13.586714)
					(mid 37.363944 -14.078871)
					(end 37.38626 -13.552678)
				)
				(arc
					(start 37.38626 -13.43533)
					(mid 37.034753 -13.833489)
					(end 37.41801 -14.20114)
				)
				(arc
					(start 38.281356 -14.20114)
					(mid 38.66507 -13.833614)
					(end 38.31336 -13.43533)
				)
				(arc
					(start 38.31336 -13.552678)
					(mid 38.335683 -14.078903)
					(end 38.14826 -13.586714)
				)
				(xy 38.14826 -13.43406)
			)
		)
	)
	(zone
		(net "PVDDR_VIN")
		(layer "B.Cu")
		(hatch none 0.5)
		(connect_pads
			(clearance 0.5)
		)
		(min_thickness 0.25)
		(fill yes
			(thermal_gap 0.5)
			(thermal_bridge_width 0.5)
			(island_removal_mode 0)
		)
		(polygon
			(pts
				(xy 198.628 -22.987) (xy 198.374 -23.241) (xy 198.374 -24.003) (xy 198.755 -24.384) (xy 201.041 -24.384)
				(xy 201.168 -24.511) (xy 201.168 -28.321) (xy 202.692 -29.845) (xy 204.343 -29.845) (xy 204.851 -29.337)
				(xy 204.851 -24.638) (xy 203.2 -22.987)
			)
		)
	)
	(zone
		(layer "B.Cu")
		(hatch none 0.5)
		(connect_pads
			(clearance 0)
		)
		(min_thickness 0.25)
		(keepout
			(tracks not_allowed)
			(vias allowed)
			(pads allowed)
			(copperpour not_allowed)
			(footprints allowed)
		)
		(placement
			(enabled no)
			(sheetname "")
		)
		(fill
			(thermal_gap 0.5)
			(thermal_bridge_width 0.5)
			(island_removal_mode 0)
		)
		(polygon
			(pts
				(arc
					(start 26.276046 -14.20114)
					(mid 26.65976 -13.833614)
					(end 26.30805 -13.43533)
				)
				(arc
					(start 26.30805 -13.552678)
					(mid 26.330373 -14.078903)
					(end 26.14295 -13.586714)
				)
				(xy 26.14295 -13.43406) (xy 25.54605 -13.43406)
				(arc
					(start 25.54605 -13.586714)
					(mid 25.358634 -14.078871)
					(end 25.38095 -13.552678)
				)
				(arc
					(start 25.38095 -13.43533)
					(mid 25.029443 -13.833489)
					(end 25.4127 -14.20114)
				)
			)
		)
	)
	(zone
		(layer "B.Cu")
		(hatch none 0.5)
		(connect_pads
			(clearance 0)
		)
		(min_thickness 0.25)
		(keepout
			(tracks not_allowed)
			(vias allowed)
			(pads allowed)
			(copperpour not_allowed)
			(footprints allowed)
		)
		(placement
			(enabled no)
			(sheetname "")
		)
		(fill
			(thermal_gap 0.5)
			(thermal_bridge_width 0.5)
			(island_removal_mode 0)
		)
		(polygon
			(pts
				(arc
					(start 48.850042 -71.799958)
					(mid 50.850038 -73.799954)
					(end 52.850034 -71.799958)
				)
				(arc
					(start 52.850034 -71.799958)
					(mid 50.850038 -69.799962)
					(end 48.850042 -71.799958)
				)
			)
		)
	)
	(zone
		(net "P12V")
		(layer "B.Cu")
		(hatch none 0.5)
		(connect_pads
			(clearance 0.5)
		)
		(min_thickness 0.25)
		(fill yes
			(thermal_gap 0.5)
			(thermal_bridge_width 0.5)
			(island_removal_mode 0)
		)
		(polygon
			(pts
				(xy 15.875 -10.668) (xy 15.621 -10.922) (xy 15.621 -15.24) (xy 15.875 -15.494) (xy 17.399 -15.494)
				(xy 19.05 -13.843) (xy 19.05 -12.065) (xy 18.796 -11.811) (xy 17.907 -11.811) (xy 16.764 -10.668)
			)
		)
	)
	(zone
		(net "PVNN")
		(layer "B.Cu")
		(hatch none 0.5)
		(connect_pads
			(clearance 0.5)
		)
		(min_thickness 0.25)
		(fill yes
			(thermal_gap 0.5)
			(thermal_bridge_width 0.5)
			(island_removal_mode 0)
		)
		(polygon
			(pts
				(xy 93.345 -36.83) (xy 93.218 -36.957) (xy 93.218 -37.338) (xy 93.345 -37.465) (xy 93.726 -37.465)
				(xy 93.853 -37.592) (xy 93.853 -38.735) (xy 92.2909 -40.2971) (xy 92.2909 -40.7543) (xy 92.3925 -40.8559)
				(xy 92.7481 -40.8559) (xy 92.9132 -41.021) (xy 92.9132 -41.5925) (xy 92.7608 -41.7449) (xy 92.5449 -41.7449)
				(xy 92.456 -41.8338) (xy 92.456 -42.164) (xy 92.583 -42.291) (xy 93.472 -42.291) (xy 93.726 -42.037)
				(xy 93.726 -41.783) (xy 93.98 -41.529) (xy 95.123 -41.529) (xy 95.377 -41.783) (xy 96.139 -41.783)
				(xy 96.52 -42.164) (xy 100.838 -42.164) (xy 100.965 -42.037) (xy 100.965 -41.783) (xy 100.838 -41.656)
				(xy 96.647 -41.656) (xy 96.266 -41.275) (xy 95.377 -41.275) (xy 94.2086 -40.1066) (xy 94.2086 -38.2905)
				(xy 94.5007 -37.9984) (xy 94.5007 -36.957) (xy 94.3737 -36.83)
			)
		)
		(polygon
			(pts
				(xy 92.9132 -40.2463) (xy 92.6592 -40.2463) (xy 92.6592 -40.5003) (xy 92.9132 -40.5003)
			)
		)
	)
	(zone
		(net "GND")
		(layer "B.Cu")
		(hatch none 0.5)
		(connect_pads
			(clearance 0.5)
		)
		(min_thickness 0.25)
		(fill yes
			(thermal_gap 0.5)
			(thermal_bridge_width 0.5)
			(island_removal_mode 0)
		)
		(polygon
			(pts
				(xy 41.23055 -38.37305) (xy 40.98925 -38.61435) (xy 40.98925 -38.95725) (xy 41.148 -39.116) (xy 42.926 -39.116)
				(xy 43.942 -40.132) (xy 43.942 -41.021) (xy 43.688 -41.275) (xy 43.688 -41.91) (xy 43.815 -42.037)
				(xy 46.355 -42.037) (xy 46.482 -41.91) (xy 47.371 -41.91) (xy 47.498 -41.783) (xy 47.498 -40.386)
				(xy 46.228 -39.116) (xy 44.45 -39.116) (xy 43.70705 -38.37305)
			)
		)
		(polygon
			(pts
				(xy 45.593 -41.4274) (xy 45.339 -41.4274) (xy 45.339 -41.6814) (xy 45.593 -41.6814)
			)
		)
		(polygon
			(pts
				(xy 44.831 -41.1099) (xy 44.577 -41.1099) (xy 44.577 -41.3639) (xy 44.831 -41.6814) (xy 45.085 -41.6814)
				(xy 45.085 -41.4274)
			)
		)
		(polygon
			(pts
				(xy 46.609 -40.9829) (xy 46.355 -40.9829) (xy 46.355 -41.2369) (xy 46.609 -41.2369)
			)
		)
	)
	(zone
		(layer "B.Cu")
		(hatch none 0.5)
		(connect_pads
			(clearance 0)
		)
		(min_thickness 0.25)
		(keepout
			(tracks not_allowed)
			(vias allowed)
			(pads allowed)
			(copperpour not_allowed)
			(footprints allowed)
		)
		(placement
			(enabled no)
			(sheetname "")
		)
		(fill
			(thermal_gap 0.5)
			(thermal_bridge_width 0.5)
			(island_removal_mode 0)
		)
		(polygon
			(pts
				(arc
					(start 73.849992 -71.799958)
					(mid 75.849988 -73.799954)
					(end 77.849984 -71.799958)
				)
				(arc
					(start 77.849984 -71.799958)
					(mid 75.849988 -69.799962)
					(end 73.849992 -71.799958)
				)
			)
		)
	)
	(zone
		(layer "B.Cu")
		(hatch none 0.5)
		(connect_pads
			(clearance 0)
		)
		(min_thickness 0.25)
		(keepout
			(tracks allowed)
			(vias allowed)
			(pads allowed)
			(copperpour allowed)
			(footprints allowed)
		)
		(placement
			(enabled no)
			(sheetname "")
		)
		(fill
			(thermal_gap 0.5)
			(thermal_bridge_width 0.5)
			(island_removal_mode 0)
		)
		(polygon
			(pts
				(xy 39.5986 -27.4574) (xy 39.5986 -24.5618) (xy 52.0446 -24.5618) (xy 52.0446 -27.4574)
			)
		)
	)
	(zone
		(net "GND")
		(layer "B.Cu")
		(hatch none 0.5)
		(connect_pads
			(clearance 0.5)
		)
		(min_thickness 0.25)
		(fill yes
			(thermal_gap 0.5)
			(thermal_bridge_width 0.5)
			(island_removal_mode 0)
		)
		(polygon
			(pts
				(xy 198.12 -0.762) (xy 197.866 -1.016) (xy 197.866 -3.429) (xy 197.993 -3.556) (xy 198.755 -3.556)
				(xy 200.152 -2.159) (xy 201.041 -2.159) (xy 201.422 -2.54) (xy 201.422 -4.191) (xy 198.501 -7.112)
				(xy 198.501 -10.668) (xy 193.802 -15.367) (xy 191.135 -15.367) (xy 191.008 -15.494) (xy 191.008 -16.002)
				(xy 190.5 -16.51) (xy 187.325 -16.51) (xy 187.198 -16.637) (xy 187.198 -17.145) (xy 186.944 -17.399)
				(xy 185.928 -17.399) (xy 184.912 -16.383) (xy 184.912 -12.954) (xy 185.166 -12.7) (xy 186.69 -12.7)
				(xy 186.944 -12.446) (xy 186.944 -11.43) (xy 186.69 -11.176) (xy 174.879 -11.176) (xy 172.974 -13.081)
				(xy 169.418 -13.081) (xy 169.037 -12.7) (xy 164.846 -12.7) (xy 164.338 -13.208) (xy 163.195 -13.208)
				(xy 162.56 -12.573) (xy 157.734 -12.573) (xy 157.226 -13.081) (xy 153.67 -13.081) (xy 151.765 -11.176)
				(xy 130.302 -11.176) (xy 130.048 -11.43) (xy 130.048 -13.716) (xy 129.794 -13.97) (xy 128.651 -13.97)
				(xy 127.127 -12.446) (xy 127.127 -2.413) (xy 126.619 -1.905) (xy 120.015 -1.905) (xy 119.761 -2.159)
				(xy 119.761 -2.667) (xy 121.158 -4.064) (xy 121.158 -9.144) (xy 122.936 -10.922) (xy 122.936 -12.065)
				(xy 120.269 -14.732) (xy 120.269 -21.082) (xy 121.285 -22.098) (xy 126.619 -22.098) (xy 127.381 -22.86)
				(xy 127.635 -22.86) (xy 127.762 -22.733) (xy 127.762 -21.971) (xy 127.762 -21.082) (xy 130.048 -18.796)
				(xy 130.937 -18.796) (xy 162.814 -18.796) (xy 165.354 -21.336) (xy 165.354 -25.273) (xy 167.64 -27.559)
				(xy 180.213 -27.559) (xy 184.658 -23.114) (xy 191.389 -23.114) (xy 197.358 -29.083) (xy 199.898 -29.083)
				(xy 200.406 -28.575) (xy 200.406 -25.019) (xy 200.279 -24.892) (xy 198.755 -24.892) (xy 197.993 -24.13)
				(xy 197.993 -22.86) (xy 200.4695 -20.3835) (xy 202.565 -20.3835) (xy 203.04125 -20.85975) (xy 203.04125 -22.19325)
				(xy 205.486 -24.638) (xy 205.486 -29.21) (xy 204.216 -30.48) (xy 204.216 -32.004) (xy 204.343 -32.131)
				(xy 206.248 -32.131) (xy 206.883 -32.766) (xy 206.883 -41.021) (xy 205.8162 -42.0878) (xy 204.4192 -42.0878)
				(xy 204.343 -42.164) (xy 204.343 -42.7736) (xy 203.835 -43.2816) (xy 203.3778 -43.2816) (xy 203.1746 -43.4848)
				(xy 203.1746 -44.4246) (xy 203.3016 -44.5516) (xy 204.8764 -44.5516) (xy 205.1304 -44.8056) (xy 205.1304 -46.5836)
				(xy 203.2 -48.514) (xy 203.2 -50.927) (xy 203.581 -51.308) (xy 203.581 -55.372) (xy 203.7588 -55.5498)
				(xy 203.7588 -67.0306) (xy 203.962 -67.2338) (xy 204.8002 -67.2338) (xy 205.867 -66.167) (xy 206.502 -66.167)
				(xy 207.01 -66.675) (xy 207.01 -71.501) (xy 206.375 -72.136) (xy 205.359 -72.136) (xy 205.232 -72.263)
				(xy 205.232 -72.898) (xy 205.359 -73.025) (xy 208.915 -73.025) (xy 209.169 -72.771) (xy 209.169 -1.143)
				(xy 208.788 -0.762)
			)
		)
		(polygon
			(pts
				(xy 204.8891 -65.7352) (xy 204.6351 -65.7352) (xy 204.6351 -66.294) (xy 204.8891 -66.294)
			)
		)
		(polygon
			(pts
				(xy 204.8891 -64.4652) (xy 204.6351 -64.4652) (xy 204.6351 -64.9732) (xy 204.8891 -64.9732)
			)
		)
		(polygon
			(pts
				(xy 204.8891 -63.4492) (xy 204.6351 -63.4492) (xy 204.6351 -63.7032) (xy 204.8891 -63.7032)
			)
		)
		(polygon
			(pts
				(xy 205.0542 -42.4688) (xy 204.8002 -42.4688) (xy 204.8002 -42.7228) (xy 205.0542 -42.7228)
			)
		)
		(polygon
			(pts
				(xy 204.8256 -30.988) (xy 204.5716 -30.988) (xy 204.5716 -31.623) (xy 204.8256 -31.623)
			)
		)
		(polygon
			(pts
				(xy 204.8256 -30.48) (xy 204.5716 -30.48) (xy 204.5716 -30.734) (xy 204.8256 -30.734)
			)
		)
		(polygon
			(pts
				(xy 187.071 -17.7546) (xy 186.817 -17.7546) (xy 186.817 -18.0086) (xy 187.071 -18.0086)
			)
		)
		(polygon
			(pts
				(xy 186.563 -17.7546) (xy 186.309 -17.7546) (xy 186.309 -18.0086) (xy 186.563 -18.0086)
			)
		)
		(polygon
			(pts
				(xy 190.5 -17.3101) (xy 190.246 -17.3101) (xy 190.246 -17.5641) (xy 190.5 -17.5641)
			)
		)
		(polygon
			(pts
				(xy 189.484 -17.3101) (xy 188.849 -17.3101) (xy 188.849 -17.5641) (xy 189.484 -17.5641)
			)
		)
		(polygon
			(pts
				(xy 188.087 -17.3101) (xy 187.833 -17.3101) (xy 187.833 -17.5641) (xy 188.087 -17.5641)
			)
		)
		(polygon
			(pts
				(xy 130.81 -15.914878) (xy 130.556 -15.914878) (xy 130.556 -16.168878) (xy 130.81 -16.168878)
			)
		)
		(polygon
			(pts
				(xy 129.794 -15.914878) (xy 129.54 -15.914878) (xy 129.54 -16.168878) (xy 129.794 -16.168878)
			)
		)
		(polygon
			(pts
				(xy 184.1119 -15.367) (xy 183.8579 -15.367) (xy 183.8579 -15.621) (xy 184.1119 -15.621)
			)
		)
		(polygon
			(pts
				(xy 131.699 -15.216378) (xy 131.445 -15.216378) (xy 131.445 -15.470378) (xy 131.699 -15.470378)
			)
		)
		(polygon
			(pts
				(xy 131.191 -15.216378) (xy 130.937 -15.216378) (xy 130.937 -15.470378) (xy 131.191 -15.470378)
			)
		)
		(polygon
			(pts
				(xy 164.5412 -14.162278) (xy 164.2872 -14.162278) (xy 164.2872 -14.416278) (xy 164.5412 -14.416278)
			)
		)
		(polygon
			(pts
				(xy 163.5252 -14.162278) (xy 163.2712 -14.162278) (xy 163.2712 -14.416278) (xy 163.5252 -14.416278)
			)
		)
		(polygon
			(pts
				(xy 184.1119 -14.097) (xy 183.8579 -14.097) (xy 183.8579 -14.605) (xy 184.1119 -14.605)
			)
		)
		(polygon
			(pts
				(xy 165.862 -13.501878) (xy 165.608 -13.501878) (xy 165.608 -13.755878) (xy 165.862 -13.755878)
			)
		)
		(polygon
			(pts
				(xy 164.846 -13.501878) (xy 164.592 -13.501878) (xy 164.592 -13.755878) (xy 164.846 -13.755878)
			)
		)
		(polygon
			(pts
				(xy 158.623 -13.501878) (xy 158.369 -13.501878) (xy 158.369 -13.755878) (xy 158.623 -13.755878)
			)
		)
		(polygon
			(pts
				(xy 157.607 -13.501878) (xy 157.353 -13.501878) (xy 157.353 -13.755878) (xy 157.607 -13.755878)
			)
		)
		(polygon
			(pts
				(xy 169.164 -13.082778) (xy 168.91 -13.082778) (xy 168.91 -13.336778) (xy 169.164 -13.336778)
			)
		)
		(polygon
			(pts
				(xy 168.656 -13.082778) (xy 168.148 -13.082778) (xy 168.148 -13.336778) (xy 168.656 -13.336778)
			)
		)
		(polygon
			(pts
				(xy 167.894 -13.082778) (xy 167.386 -13.082778) (xy 167.386 -13.336778) (xy 167.894 -13.336778)
			)
		)
		(polygon
			(pts
				(xy 167.132 -13.082778) (xy 166.878 -13.082778) (xy 166.878 -13.336778) (xy 167.132 -13.336778)
			)
		)
		(polygon
			(pts
				(xy 184.1119 -13.081) (xy 183.8579 -13.081) (xy 183.8579 -13.335) (xy 184.1119 -13.335)
			)
		)
		(polygon
			(pts
				(xy 162.0774 -12.930378) (xy 161.8234 -12.930378) (xy 161.8234 -13.184378) (xy 162.0774 -13.184378)
			)
		)
		(polygon
			(pts
				(xy 161.5694 -12.930378) (xy 160.9852 -12.930378) (xy 160.9852 -13.184378) (xy 161.5694 -13.184378)
			)
		)
		(polygon
			(pts
				(xy 160.7312 -12.930378) (xy 160.4772 -12.930378) (xy 160.4772 -13.184378) (xy 160.7312 -13.184378)
			)
		)
		(polygon
			(pts
				(xy 159.512 -12.930378) (xy 159.258 -12.930378) (xy 159.258 -13.184378) (xy 159.512 -13.184378)
			)
		)
		(polygon
			(pts
				(xy 158.623 -12.714478) (xy 158.369 -12.714478) (xy 158.369 -12.968478) (xy 158.75 -13.184378) (xy 159.004 -13.184378)
				(xy 159.004 -12.930378)
			)
		)
		(polygon
			(pts
				(xy 130.6576 -12.447778) (xy 130.4036 -12.447778) (xy 130.4036 -12.701778) (xy 130.6576 -12.701778)
			)
		)
		(polygon
			(pts
				(xy 131.1021 -12.193778) (xy 130.8481 -12.193778) (xy 130.8481 -12.447778) (xy 131.1021 -12.447778)
			)
		)
		(polygon
			(pts
				(xy 186.4868 -11.939778) (xy 186.2328 -11.939778) (xy 186.2328 -12.193778) (xy 186.4868 -12.193778)
			)
		)
		(polygon
			(pts
				(xy 186.4868 -11.431778) (xy 186.2328 -11.431778) (xy 186.2328 -11.685778) (xy 186.4868 -11.685778)
			)
		)
		(polygon
			(pts
				(xy 198.9201 -2.032) (xy 198.6661 -2.032) (xy 198.6661 -2.5908) (xy 198.9201 -2.5908)
			)
		)
		(polygon
			(pts
				(xy 198.9201 -1.016) (xy 198.6661 -1.016) (xy 198.6661 -1.27) (xy 198.9201 -1.27)
			)
		)
	)
	(zone
		(layer "B.Cu")
		(hatch none 0.5)
		(connect_pads
			(clearance 0)
		)
		(min_thickness 0.25)
		(keepout
			(tracks allowed)
			(vias allowed)
			(pads allowed)
			(copperpour allowed)
			(footprints not_allowed)
		)
		(placement
			(enabled no)
			(sheetname "")
		)
		(fill
			(thermal_gap 0.5)
			(thermal_bridge_width 0.5)
			(island_removal_mode 0)
		)
		(polygon
			(pts
				(xy 5.929884 -47.700946) (xy 5.929884 -69.600064) (xy 88.951054 -69.600064)
				(arc
					(start 88.951054 -61.700918)
					(mid 85.95106 -58.700924)
					(end 88.951054 -55.70093)
				)
				(xy 88.951054 -47.700946)
			)
		)
	)
	(zone
		(net "PV_VDDR")
		(layer "B.Cu")
		(hatch none 0.5)
		(connect_pads
			(clearance 0.5)
		)
		(min_thickness 0.25)
		(fill yes
			(thermal_gap 0.5)
			(thermal_bridge_width 0.5)
			(island_removal_mode 0)
		)
		(polygon
			(pts
				(xy 155.8544 -9.018778) (xy 155.7782 -9.094978) (xy 155.7782 -10.898378) (xy 155.6258 -11.050778)
				(xy 153.797 -11.050778) (xy 153.543 -11.304778) (xy 153.543 -12.447778) (xy 153.924 -12.828778)
				(xy 156.972 -12.828778) (xy 157.4546 -12.346178) (xy 162.7378 -12.346178) (xy 163.3474 -12.955778)
				(xy 164.2364 -12.955778) (xy 164.7444 -12.447778) (xy 169.164 -12.447778) (xy 169.545 -12.828778)
				(xy 172.72 -12.828778) (xy 172.847 -12.701778) (xy 172.847 -11.406378) (xy 172.72 -11.279378) (xy 170.0784 -11.279378)
				(xy 169.926 -11.126978) (xy 169.926 -9.145778) (xy 169.8244 -9.044178) (xy 169.672 -9.044178) (xy 169.5958 -9.120378)
				(xy 169.5958 -10.974578) (xy 169.3926 -11.177778) (xy 167.7162 -11.177778) (xy 167.4876 -10.949178)
				(xy 167.4876 -9.094978) (xy 167.4368 -9.044178) (xy 167.2336 -9.044178) (xy 167.1828 -9.094978)
				(xy 167.1828 -10.999978) (xy 167.005 -11.177778) (xy 165.3286 -11.177778) (xy 165.1 -10.949178)
				(xy 165.1 -9.171178) (xy 164.973 -9.044178) (xy 164.8714 -9.044178) (xy 164.7952 -9.120378) (xy 164.7952 -11.025378)
				(xy 164.6428 -11.177778) (xy 163.5252 -11.177778) (xy 163.322 -10.974578) (xy 163.322 -9.145778)
				(xy 163.2204 -9.044178) (xy 163.0426 -9.044178) (xy 162.9918 -9.094978) (xy 162.9918 -10.949178)
				(xy 162.7632 -11.177778) (xy 161.1122 -11.177778) (xy 160.909 -10.974578) (xy 160.909 -9.145778)
				(xy 160.782 -9.018778) (xy 160.655 -9.018778) (xy 160.5788 -9.094978) (xy 160.5788 -11.025378) (xy 160.4264 -11.177778)
				(xy 158.8008 -11.177778) (xy 158.5468 -10.923778) (xy 158.5468 -9.145778) (xy 158.4706 -9.069578)
				(xy 158.2166 -9.069578) (xy 158.1658 -9.120378) (xy 158.1658 -11.025378) (xy 158.0134 -11.177778)
				(xy 156.4894 -11.177778) (xy 156.1338 -10.822178) (xy 156.1338 -9.171178) (xy 155.9814 -9.018778)
			)
		)
		(polygon
			(pts
				(xy 164.5412 -12.054078) (xy 164.2872 -12.054078) (xy 164.2872 -12.308078) (xy 164.5412 -12.308078)
			)
		)
		(polygon
			(pts
				(xy 163.5252 -12.054078) (xy 163.2712 -12.054078) (xy 163.2712 -12.308078) (xy 163.5252 -12.308078)
			)
		)
		(polygon
			(pts
				(xy 169.164 -11.863578) (xy 168.91 -11.863578) (xy 168.91 -12.117578) (xy 169.164 -12.117578)
			)
		)
		(polygon
			(pts
				(xy 168.656 -11.863578) (xy 168.148 -11.863578) (xy 168.148 -12.117578) (xy 168.656 -12.117578)
			)
		)
		(polygon
			(pts
				(xy 167.894 -11.863578) (xy 167.386 -11.863578) (xy 167.386 -12.117578) (xy 167.894 -12.117578)
			)
		)
		(polygon
			(pts
				(xy 167.132 -11.863578) (xy 166.878 -11.863578) (xy 166.878 -12.117578) (xy 167.132 -12.117578)
			)
		)
		(polygon
			(pts
				(xy 162.0774 -11.711178) (xy 161.8234 -11.711178) (xy 161.8234 -11.965178) (xy 162.0774 -11.965178)
			)
		)
		(polygon
			(pts
				(xy 161.5694 -11.711178) (xy 160.9852 -11.711178) (xy 160.9852 -11.965178) (xy 161.5694 -11.965178)
			)
		)
		(polygon
			(pts
				(xy 160.7312 -11.711178) (xy 160.4772 -11.711178) (xy 160.4772 -11.965178) (xy 160.7312 -11.965178)
			)
		)
		(polygon
			(pts
				(xy 159.512 -11.711178) (xy 159.258 -11.711178) (xy 159.258 -11.965178) (xy 159.512 -11.965178)
			)
		)
		(polygon
			(pts
				(xy 159.004 -11.711178) (xy 158.75 -11.711178) (xy 158.75 -11.965178) (xy 159.004 -11.965178)
			)
		)
		(polygon
			(pts
				(xy 165.862 -11.393678) (xy 165.608 -11.393678) (xy 165.608 -11.647678) (xy 165.862 -11.647678)
			)
		)
		(polygon
			(pts
				(xy 164.846 -11.393678) (xy 164.592 -11.393678) (xy 164.592 -11.647678) (xy 164.846 -11.647678)
			)
		)
		(polygon
			(pts
				(xy 158.623 -11.393678) (xy 158.369 -11.393678) (xy 158.369 -11.647678) (xy 158.623 -11.647678)
			)
		)
		(polygon
			(pts
				(xy 157.607 -11.393678) (xy 157.353 -11.393678) (xy 157.353 -11.647678) (xy 157.607 -11.647678)
			)
		)
	)
	(zone
		(net "P1V0")
		(layer "B.Cu")
		(hatch none 0.5)
		(connect_pads
			(clearance 0.5)
		)
		(min_thickness 0.25)
		(fill yes
			(thermal_gap 0.5)
			(thermal_bridge_width 0.5)
			(island_removal_mode 0)
		)
		(polygon
			(pts
				(xy 27.432 -25.4) (xy 25.4 -27.432) (xy 25.4 -31.877) (xy 25.781 -32.258) (xy 28.321 -32.258) (xy 29.21 -31.369)
				(xy 30.988 -31.369) (xy 31.115 -31.242) (xy 31.115 -30.353) (xy 32.004 -29.464) (xy 32.004 -26.797)
				(xy 32.766 -26.035) (xy 32.766 -25.527) (xy 32.639 -25.4)
			)
		)
		(polygon
			(pts
				(xy 28.321 -31.2039) (xy 28.067 -31.2039) (xy 28.067 -31.4579) (xy 28.321 -31.4579)
			)
		)
		(polygon
			(pts
				(xy 27.305 -31.2039) (xy 26.67 -31.2039) (xy 26.67 -31.4579) (xy 27.305 -31.4579)
			)
		)
		(polygon
			(pts
				(xy 25.908 -31.2039) (xy 25.654 -31.2039) (xy 25.654 -31.4579) (xy 25.908 -31.4579)
			)
		)
		(polygon
			(pts
				(xy 30.4419 -30.099) (xy 30.1879 -30.099) (xy 30.1879 -30.353) (xy 30.4419 -30.353)
			)
		)
		(polygon
			(pts
				(xy 32.258 -25.8572) (xy 32.004 -25.8572) (xy 32.004 -26.1112) (xy 32.258 -26.1112)
			)
		)
	)
	(zone
		(layer "B.Cu")
		(hatch none 0.5)
		(connect_pads
			(clearance 0)
		)
		(min_thickness 0.25)
		(keepout
			(tracks allowed)
			(vias allowed)
			(pads allowed)
			(copperpour allowed)
			(footprints allowed)
		)
		(placement
			(enabled no)
			(sheetname "")
		)
		(fill
			(thermal_gap 0.5)
			(thermal_bridge_width 0.5)
			(island_removal_mode 0)
		)
		(polygon
			(pts
				(xy 67.9958 -22.3774) (xy 67.9958 -17.6276) (xy 72.8726 -17.6276) (xy 72.8726 -22.3774)
			)
		)
	)
	(zone
		(layer "B.Cu")
		(hatch none 0.5)
		(connect_pads
			(clearance 0)
		)
		(min_thickness 0.25)
		(keepout
			(tracks not_allowed)
			(vias allowed)
			(pads allowed)
			(copperpour not_allowed)
			(footprints allowed)
		)
		(placement
			(enabled no)
			(sheetname "")
		)
		(fill
			(thermal_gap 0.5)
			(thermal_bridge_width 0.5)
			(island_removal_mode 0)
		)
		(polygon
			(pts
				(xy 72.98055 -14.32306)
				(arc
					(start 72.98055 -14.475714)
					(mid 72.793134 -14.967871)
					(end 72.81545 -14.441678)
				)
				(arc
					(start 72.81545 -14.32433)
					(mid 72.463943 -14.722489)
					(end 72.8472 -15.09014)
				)
				(arc
					(start 73.7108 -15.09014)
					(mid 74.094011 -14.722487)
					(end 73.74255 -14.32433)
				)
				(arc
					(start 73.74255 -14.441678)
					(mid 73.764873 -14.967903)
					(end 73.57745 -14.475714)
				)
				(xy 73.57745 -14.32306)
			)
		)
	)
	(zone
		(net "P3V3_STBY")
		(layer "B.Cu")
		(hatch none 0.5)
		(connect_pads
			(clearance 0.5)
		)
		(min_thickness 0.25)
		(fill yes
			(thermal_gap 0.5)
			(thermal_bridge_width 0.5)
			(island_removal_mode 0)
		)
		(polygon
			(pts
				(xy 85.979 -63.373) (xy 85.852 -63.5) (xy 85.852 -66.04) (xy 84.455 -67.437) (xy 84.455 -69.723)
				(xy 84.709 -69.977) (xy 87.376 -69.977) (xy 87.63 -69.723) (xy 87.63 -67.945) (xy 86.614 -66.929)
				(xy 86.614 -63.5) (xy 86.487 -63.373)
			)
		)
	)
	(zone
		(net "GND")
		(layer "B.Cu")
		(hatch none 0.5)
		(connect_pads
			(clearance 0.5)
		)
		(min_thickness 0.25)
		(fill yes
			(thermal_gap 0.5)
			(thermal_bridge_width 0.5)
			(island_removal_mode 0)
		)
		(polygon
			(pts
				(xy 4.0386 -47.7774) (xy 3.175 -48.641) (xy 3.175 -50.3428) (xy 3.429 -50.5968) (xy 4.318 -50.5968)
				(xy 4.445 -50.4698) (xy 6.4262 -50.4698) (xy 6.858 -50.038) (xy 7.747 -50.038) (xy 8.128 -49.657)
				(xy 8.128 -48.0314) (xy 7.874 -47.7774)
			)
		)
	)
	(zone
		(net "P1V0")
		(layer "B.Cu")
		(hatch none 0.5)
		(connect_pads
			(clearance 0.5)
		)
		(min_thickness 0.25)
		(fill yes
			(thermal_gap 0.5)
			(thermal_bridge_width 0.5)
			(island_removal_mode 0)
		)
		(polygon
			(pts
				(xy 89.662 -16.51) (xy 89.535 -16.637) (xy 89.535 -20.447) (xy 89.281 -20.701) (xy 87.63 -20.701)
				(xy 87.376 -20.955) (xy 87.376 -21.463) (xy 88.011 -22.098) (xy 88.011 -23.495) (xy 88.138 -23.622)
				(xy 88.392 -23.622) (xy 88.646 -23.876) (xy 88.646 -25.019) (xy 88.773 -25.146) (xy 89.154 -25.146)
				(xy 89.281 -25.273) (xy 89.281 -29.21) (xy 89.027 -29.464) (xy 89.027 -31.496) (xy 89.281 -31.75)
				(xy 89.281 -34.036) (xy 89.027 -34.29) (xy 89.027 -34.671) (xy 89.408 -35.052) (xy 90.424 -35.052)
				(xy 90.551 -34.925) (xy 90.551 -34.671) (xy 90.424 -34.544) (xy 90.297 -34.544) (xy 90.17 -34.417)
				(xy 90.17 -33.147) (xy 90.297 -33.02) (xy 90.805 -33.02) (xy 91.059 -33.274) (xy 91.313 -33.274)
				(xy 91.567 -33.02) (xy 91.567 -32.766) (xy 91.821 -32.512) (xy 92.075 -32.512) (xy 92.202 -32.385)
				(xy 92.202 -30.6324) (xy 92.583 -30.2514) (xy 92.583 -28.321) (xy 93.472 -27.432) (xy 93.472 -22.733)
				(xy 94.488 -21.717) (xy 94.488 -17.018) (xy 93.98 -16.51)
			)
		)
		(polygon
			(pts
				(xy 89.7255 -34.3408) (xy 89.4715 -34.3408) (xy 89.4715 -34.5948) (xy 89.7255 -34.5948)
			)
		)
		(polygon
			(pts
				(xy 89.7255 -33.5788) (xy 89.4715 -33.5788) (xy 89.4715 -34.0868) (xy 89.7255 -34.0868)
			)
		)
		(polygon
			(pts
				(xy 89.7255 -33.0708) (xy 89.4715 -33.0708) (xy 89.4715 -33.3248) (xy 89.7255 -33.3248)
			)
		)
		(polygon
			(pts
				(xy 91.8718 -30.988) (xy 91.6178 -30.988) (xy 91.6178 -31.242) (xy 91.8718 -31.242)
			)
		)
		(polygon
			(pts
				(xy 91.8718 -30.48) (xy 91.6178 -30.48) (xy 91.6178 -30.734) (xy 91.8718 -30.734)
			)
		)
		(polygon
			(pts
				(xy 92.2274 -29.718) (xy 91.9734 -29.718) (xy 91.9734 -29.972) (xy 92.2274 -29.972)
			)
		)
		(polygon
			(pts
				(xy 89.8906 -26.416) (xy 89.6366 -26.416) (xy 89.6366 -26.924) (xy 89.8906 -26.924)
			)
		)
		(polygon
			(pts
				(xy 93.1164 -26.289) (xy 92.8624 -26.289) (xy 92.8624 -26.797) (xy 93.1164 -26.797)
			)
		)
		(polygon
			(pts
				(xy 89.8906 -25.654) (xy 89.6366 -25.654) (xy 89.6366 -26.162) (xy 89.8906 -26.162)
			)
		)
		(polygon
			(pts
				(xy 93.1164 -25.527) (xy 92.8624 -25.527) (xy 92.8624 -26.035) (xy 93.1164 -26.035)
			)
		)
		(polygon
			(pts
				(xy 89.8906 -25.146) (xy 89.6366 -25.146) (xy 89.6366 -25.4) (xy 89.8906 -25.4)
			)
		)
		(polygon
			(pts
				(xy 89.2556 -24.13) (xy 89.0016 -24.13) (xy 89.0016 -24.638) (xy 89.2556 -24.638)
			)
		)
		(polygon
			(pts
				(xy 89.2556 -23.622) (xy 89.0016 -23.622) (xy 89.0016 -23.876) (xy 89.2556 -23.876)
			)
		)
		(polygon
			(pts
				(xy 88.6206 -22.606) (xy 88.3666 -22.606) (xy 88.3666 -23.114) (xy 88.6206 -23.114)
			)
		)
		(polygon
			(pts
				(xy 88.6206 -22.098) (xy 88.3666 -22.098) (xy 88.3666 -22.352) (xy 88.6206 -22.352)
			)
		)
		(polygon
			(pts
				(xy 90.297 -16.8656) (xy 90.043 -16.8656) (xy 90.043 -17.1196) (xy 90.297 -17.1196)
			)
		)
	)
	(zone
		(layer "B.Cu")
		(hatch none 0.5)
		(connect_pads
			(clearance 0)
		)
		(min_thickness 0.25)
		(keepout
			(tracks not_allowed)
			(vias allowed)
			(pads allowed)
			(copperpour not_allowed)
			(footprints allowed)
		)
		(placement
			(enabled no)
			(sheetname "")
		)
		(fill
			(thermal_gap 0.5)
			(thermal_bridge_width 0.5)
			(island_removal_mode 0)
		)
		(polygon
			(pts
				(arc
					(start 43.25366 -12.21486)
					(mid 42.87012 -12.5984)
					(end 43.25366 -12.98194)
				)
				(xy 43.47845 -12.98194) (xy 43.47845 -12.94003)
				(arc
					(start 43.374564 -12.836144)
					(mid 43.06506 -12.4098)
					(end 43.491404 -12.719304)
				)
				(xy 43.59529 -12.82319) (xy 43.64355 -12.87145) (xy 43.64355 -12.94003) (xy 43.64355 -12.98194)
				(xy 43.82135 -12.98194) (xy 43.82135 -12.94003) (xy 43.82135 -12.87145) (xy 43.86961 -12.82319)
				(arc
					(start 43.973496 -12.719304)
					(mid 44.39984 -12.4098)
					(end 44.090336 -12.836144)
				)
				(xy 43.98645 -12.94003) (xy 43.98645 -12.98194)
				(arc
					(start 44.210986 -12.98194)
					(mid 44.59478 -12.598527)
					(end 44.21124 -12.21486)
				)
			)
		)
	)
	(zone
		(layer "B.Cu")
		(hatch none 0.5)
		(connect_pads
			(clearance 0)
		)
		(min_thickness 0.25)
		(keepout
			(tracks not_allowed)
			(vias allowed)
			(pads allowed)
			(copperpour not_allowed)
			(footprints allowed)
		)
		(placement
			(enabled no)
			(sheetname "")
		)
		(fill
			(thermal_gap 0.5)
			(thermal_bridge_width 0.5)
			(island_removal_mode 0)
		)
		(polygon
			(pts
				(arc
					(start 61.40831 -9.867138)
					(mid 61.02477 -10.250678)
					(end 61.40831 -10.634218)
				)
				(arc
					(start 62.327536 -10.634218)
					(mid 62.71133 -10.250805)
					(end 62.32779 -9.867138)
				)
				(xy 62.116716 -9.867138) (xy 62.116716 -9.922764)
				(arc
					(start 62.206886 -10.012934)
					(mid 62.51639 -10.439278)
					(end 62.090046 -10.129774)
				)
				(xy 61.999876 -10.039604) (xy 61.951616 -9.991344) (xy 61.951616 -9.922764) (xy 61.951616 -9.867138)
				(xy 61.773816 -9.867138) (xy 61.773816 -9.933432) (xy 61.773816 -10.002012) (xy 61.725556 -10.050272)
				(arc
					(start 61.646054 -10.129774)
					(mid 61.21971 -10.439278)
					(end 61.529214 -10.012934)
				)
				(xy 61.608716 -9.933432) (xy 61.608716 -9.867138)
			)
		)
	)
	(zone
		(layer "B.Cu")
		(hatch none 0.5)
		(connect_pads
			(clearance 0)
		)
		(min_thickness 0.25)
		(keepout
			(tracks not_allowed)
			(vias allowed)
			(pads allowed)
			(copperpour not_allowed)
			(footprints allowed)
		)
		(placement
			(enabled no)
			(sheetname "")
		)
		(fill
			(thermal_gap 0.5)
			(thermal_bridge_width 0.5)
			(island_removal_mode 0)
		)
		(polygon
			(pts
				(xy 77.55255 -14.19606)
				(arc
					(start 77.55255 -14.348714)
					(mid 77.365134 -14.840871)
					(end 77.38745 -14.314678)
				)
				(arc
					(start 77.38745 -14.19733)
					(mid 77.035943 -14.595489)
					(end 77.4192 -14.96314)
				)
				(arc
					(start 78.2828 -14.96314)
					(mid 78.666011 -14.595487)
					(end 78.31455 -14.19733)
				)
				(arc
					(start 78.31455 -14.314678)
					(mid 78.336873 -14.840903)
					(end 78.14945 -14.348714)
				)
				(xy 78.14945 -14.19606)
			)
		)
	)
	(zone
		(layer "B.Cu")
		(hatch none 0.5)
		(connect_pads
			(clearance 0)
		)
		(min_thickness 0.25)
		(keepout
			(tracks not_allowed)
			(vias allowed)
			(pads allowed)
			(copperpour not_allowed)
			(footprints allowed)
		)
		(placement
			(enabled no)
			(sheetname "")
		)
		(fill
			(thermal_gap 0.5)
			(thermal_bridge_width 0.5)
			(island_removal_mode 0)
		)
		(polygon
			(pts
				(arc
					(start 42.453814 -43.77182)
					(mid 42.07002 -44.155233)
					(end 42.45356 -44.5389)
				)
				(xy 42.67835 -44.5389) (xy 42.67835 -44.49699)
				(arc
					(start 42.574464 -44.393104)
					(mid 42.26496 -43.96676)
					(end 42.691304 -44.276264)
				)
				(xy 42.79519 -44.38015) (xy 42.84345 -44.42841) (xy 42.84345 -44.49699) (xy 42.84345 -44.5389) (xy 43.02125 -44.5389)
				(xy 43.02125 -44.49699) (xy 43.02125 -44.42841) (xy 43.06951 -44.38015)
				(arc
					(start 43.173396 -44.276264)
					(mid 43.59974 -43.96676)
					(end 43.290236 -44.393104)
				)
				(xy 43.18635 -44.49699) (xy 43.18635 -44.5389)
				(arc
					(start 43.41114 -44.5389)
					(mid 43.79468 -44.15536)
					(end 43.41114 -43.77182)
				)
			)
		)
	)
	(zone
		(net "PV_VTT_DDR_B")
		(layer "B.Cu")
		(hatch none 0.5)
		(connect_pads
			(clearance 0.5)
		)
		(min_thickness 0.25)
		(fill yes
			(thermal_gap 0.5)
			(thermal_bridge_width 0.5)
			(island_removal_mode 0)
		)
		(polygon
			(pts
				(xy 191.643 -0.762) (xy 191.4398 -0.9652) (xy 191.4398 -8.7884) (xy 191.1731 -9.0551) (xy 191.1731 -10.795)
				(xy 191.643 -11.2649) (xy 191.643 -12.7) (xy 191.262 -13.081) (xy 185.42 -13.081) (xy 185.293 -13.208)
				(xy 185.293 -16.129) (xy 186.309 -17.145) (xy 186.817 -17.145) (xy 186.944 -17.018) (xy 186.944 -16.383)
				(xy 187.198 -16.129) (xy 190.373 -16.129) (xy 190.627 -15.875) (xy 190.627 -15.24) (xy 190.754 -15.113)
				(xy 192.405 -15.113) (xy 196.088 -11.43) (xy 196.088 -4.572) (xy 196.342 -4.318) (xy 197.358 -4.318)
				(xy 197.612 -4.064) (xy 197.612 -1.016) (xy 197.358 -0.762)
			)
		)
		(polygon
			(pts
				(xy 186.563 -16.5354) (xy 186.309 -16.5354) (xy 186.309 -16.7894) (xy 186.563 -16.7894)
			)
		)
		(polygon
			(pts
				(xy 186.2201 -15.367) (xy 185.9661 -15.367) (xy 185.9661 -15.621) (xy 186.2201 -15.621)
			)
		)
		(polygon
			(pts
				(xy 189.484 -15.2019) (xy 188.849 -15.2019) (xy 188.849 -15.4559) (xy 189.484 -15.4559)
			)
		)
		(polygon
			(pts
				(xy 188.087 -15.2019) (xy 187.833 -15.2019) (xy 187.833 -15.4559) (xy 188.087 -15.4559)
			)
		)
		(polygon
			(pts
				(xy 186.2201 -14.097) (xy 185.9661 -14.097) (xy 185.9661 -14.605) (xy 186.2201 -14.605)
			)
		)
		(polygon
			(pts
				(xy 196.8119 -3.3528) (xy 196.5579 -3.3528) (xy 196.5579 -3.6068) (xy 196.8119 -3.6068)
			)
		)
		(polygon
			(pts
				(xy 196.8119 -2.032) (xy 196.5579 -2.032) (xy 196.5579 -2.5908) (xy 196.8119 -2.5908)
			)
		)
		(polygon
			(pts
				(xy 196.8119 -1.016) (xy 196.5579 -1.016) (xy 196.5579 -1.27) (xy 196.8119 -1.27)
			)
		)
	)
	(zone
		(layer "B.Cu")
		(hatch none 0.5)
		(connect_pads
			(clearance 0)
		)
		(min_thickness 0.25)
		(keepout
			(tracks not_allowed)
			(vias allowed)
			(pads allowed)
			(copperpour not_allowed)
			(footprints allowed)
		)
		(placement
			(enabled no)
			(sheetname "")
		)
		(fill
			(thermal_gap 0.5)
			(thermal_bridge_width 0.5)
			(island_removal_mode 0)
		)
		(polygon
			(pts
				(arc
					(start 60.04179 -35.379914)
					(mid 59.658377 -34.99612)
					(end 59.27471 -35.37966)
				)
				(xy 59.27471 -35.60445) (xy 59.31662 -35.60445)
				(arc
					(start 59.420506 -35.500564)
					(mid 59.84685 -35.19106)
					(end 59.537346 -35.617404)
				)
				(xy 59.43346 -35.72129) (xy 59.3852 -35.76955) (xy 59.31662 -35.76955) (xy 59.27471 -35.76955) (xy 59.27471 -35.94735)
				(xy 59.31662 -35.94735) (xy 59.3852 -35.94735) (xy 59.43346 -35.99561)
				(arc
					(start 59.537346 -36.099496)
					(mid 59.84685 -36.52584)
					(end 59.420506 -36.216336)
				)
				(xy 59.31662 -36.11245) (xy 59.27471 -36.11245)
				(arc
					(start 59.27471 -36.33724)
					(mid 59.65825 -36.72078)
					(end 60.04179 -36.33724)
				)
			)
		)
	)
	(zone
		(net "GND")
		(layer "B.Cu")
		(hatch none 0.5)
		(connect_pads
			(clearance 0.5)
		)
		(min_thickness 0.25)
		(fill yes
			(thermal_gap 0.5)
			(thermal_bridge_width 0.5)
			(island_removal_mode 0)
		)
		(polygon
			(pts
				(xy 101.473 -51.562) (xy 100.711 -52.324) (xy 100.457 -52.324) (xy 100.33 -52.451) (xy 100.33 -52.832)
				(xy 100.457 -52.959) (xy 100.838 -52.959) (xy 101.346 -53.467) (xy 102.87 -53.467) (xy 102.997 -53.34)
				(xy 102.997 -52.578) (xy 103.505 -52.07) (xy 104.267 -52.07) (xy 104.394 -51.943) (xy 104.394 -51.689)
				(xy 104.267 -51.562)
			)
		)
		(polygon
			(pts
				(xy 102.5398 -52.959) (xy 102.2858 -52.959) (xy 102.2858 -53.213) (xy 102.5398 -53.213)
			)
		)
		(polygon
			(pts
				(xy 102.5398 -52.451) (xy 102.2858 -52.451) (xy 102.2858 -52.705) (xy 102.5398 -52.705)
			)
		)
		(polygon
			(pts
				(xy 103.124 -51.933602) (xy 102.616 -51.933602) (xy 102.616 -52.187602) (xy 103.124 -52.187602)
			)
		)
		(polygon
			(pts
				(xy 102.362 -51.933602) (xy 101.854 -51.933602) (xy 101.854 -52.187602) (xy 102.362 -52.187602)
			)
		)
		(polygon
			(pts
				(xy 101.6 -51.933602) (xy 101.346 -51.933602) (xy 101.346 -52.187602) (xy 101.6 -52.187602)
			)
		)
	)
	(zone
		(layer "B.Cu")
		(hatch none 0.5)
		(connect_pads
			(clearance 0)
		)
		(min_thickness 0.25)
		(keepout
			(tracks not_allowed)
			(vias allowed)
			(pads allowed)
			(copperpour not_allowed)
			(footprints allowed)
		)
		(placement
			(enabled no)
			(sheetname "")
		)
		(fill
			(thermal_gap 0.5)
			(thermal_bridge_width 0.5)
			(island_removal_mode 0)
		)
		(polygon
			(pts
				(arc
					(start 9.2202 -52.908454)
					(mid 8.839327 -52.5272)
					(end 8.4582 -52.9082)
				)
				(xy 8.4582 -53.17236)
				(arc
					(start 8.601456 -53.029104)
					(mid 9.0278 -52.7196)
					(end 8.718296 -53.145944)
				)
				(xy 8.53059 -53.33365) (xy 8.46201 -53.33365) (xy 8.4582 -53.32984) (xy 8.4582 -53.51145) (xy 8.50011 -53.51145)
				(xy 8.56869 -53.51145) (xy 8.61695 -53.55971)
				(arc
					(start 8.718296 -53.661056)
					(mid 9.0278 -54.0874)
					(end 8.601456 -53.777896)
				)
				(xy 8.50011 -53.67655) (xy 8.4582 -53.67655)
				(arc
					(start 8.4582 -53.8988)
					(mid 8.8392 -54.2798)
					(end 9.2202 -53.8988)
				)
			)
		)
	)
	(zone
		(layer "B.Cu")
		(hatch none 0.5)
		(connect_pads
			(clearance 0)
		)
		(min_thickness 0.25)
		(keepout
			(tracks not_allowed)
			(vias allowed)
			(pads allowed)
			(copperpour not_allowed)
			(footprints allowed)
		)
		(placement
			(enabled no)
			(sheetname "")
		)
		(fill
			(thermal_gap 0.5)
			(thermal_bridge_width 0.5)
			(island_removal_mode 0)
		)
		(polygon
			(pts
				(xy 41.551352 -13.43406)
				(arc
					(start 41.551352 -13.586714)
					(mid 41.363936 -14.078871)
					(end 41.386252 -13.552678)
				)
				(arc
					(start 41.386252 -13.43533)
					(mid 41.034745 -13.833489)
					(end 41.418002 -14.20114)
				)
				(arc
					(start 42.281348 -14.20114)
					(mid 42.665062 -13.833614)
					(end 42.313352 -13.43533)
				)
				(arc
					(start 42.313352 -13.552678)
					(mid 42.335675 -14.078903)
					(end 42.148252 -13.586714)
				)
				(xy 42.148252 -13.43406)
			)
		)
	)
	(zone
		(net "P1V35")
		(layer "B.Cu")
		(hatch none 0.5)
		(connect_pads
			(clearance 0.5)
		)
		(min_thickness 0.25)
		(fill yes
			(thermal_gap 0.5)
			(thermal_bridge_width 0.5)
			(island_removal_mode 0)
		)
		(polygon
			(pts
				(xy 94.742 -33.909) (xy 94.615 -34.036) (xy 94.615 -34.544) (xy 94.742 -34.671) (xy 94.742 -35.814)
				(xy 94.869 -35.941) (xy 96.774 -35.941) (xy 96.901 -35.814) (xy 96.901 -34.671) (xy 96.774 -34.544)
				(xy 96.52 -34.544) (xy 96.266 -34.29) (xy 96.266 -34.036) (xy 96.139 -33.909)
			)
		)
		(polygon
			(pts
				(xy 96.5454 -35.052) (xy 96.2914 -35.052) (xy 96.2914 -35.306) (xy 96.5454 -35.306)
			)
		)
		(polygon
			(pts
				(xy 95.758 -34.2646) (xy 95.25 -34.2646) (xy 95.25 -34.5186) (xy 95.758 -34.5186)
			)
		)
	)
	(zone
		(layer "B.Cu")
		(hatch none 0.5)
		(connect_pads
			(clearance 0)
		)
		(min_thickness 0.25)
		(keepout
			(tracks not_allowed)
			(vias allowed)
			(pads allowed)
			(copperpour not_allowed)
			(footprints allowed)
		)
		(placement
			(enabled no)
			(sheetname "")
		)
		(fill
			(thermal_gap 0.5)
			(thermal_bridge_width 0.5)
			(island_removal_mode 0)
		)
		(polygon
			(pts
				(xy 65.86855 -14.3002)
				(arc
					(start 65.86855 -14.427708)
					(mid 65.786 -14.947795)
					(end 65.70345 -14.427708)
				)
				(arc
					(start 65.70345 -14.309344)
					(mid 65.407361 -14.722722)
					(end 65.786 -15.0622)
				)
				(arc
					(start 66.547746 -15.0622)
					(mid 66.926462 -14.722856)
					(end 66.63055 -14.309344)
				)
				(arc
					(start 66.63055 -14.427708)
					(mid 66.548 -14.947795)
					(end 66.46545 -14.427708)
				)
				(xy 66.46545 -14.3002)
			)
		)
	)
	(zone
		(layer "B.Cu")
		(hatch none 0.5)
		(connect_pads
			(clearance 0)
		)
		(min_thickness 0.25)
		(keepout
			(tracks not_allowed)
			(vias allowed)
			(pads allowed)
			(copperpour not_allowed)
			(footprints allowed)
		)
		(placement
			(enabled no)
			(sheetname "")
		)
		(fill
			(thermal_gap 0.5)
			(thermal_bridge_width 0.5)
			(island_removal_mode 0)
		)
		(polygon
			(pts
				(arc
					(start 22.5298 -14.20114)
					(mid 22.913011 -13.833487)
					(end 22.56155 -13.43533)
				)
				(arc
					(start 22.56155 -13.552678)
					(mid 22.583873 -14.078903)
					(end 22.39645 -13.586714)
				)
				(xy 22.39645 -13.43406) (xy 21.79955 -13.43406)
				(arc
					(start 21.79955 -13.586714)
					(mid 21.612134 -14.078871)
					(end 21.63445 -13.552678)
				)
				(arc
					(start 21.63445 -13.43533)
					(mid 21.282943 -13.833489)
					(end 21.6662 -14.20114)
				)
			)
		)
	)
	(zone
		(net "PV_VDDR")
		(layer "B.Cu")
		(hatch none 0.5)
		(connect_pads
			(clearance 0.5)
		)
		(min_thickness 0.25)
		(fill yes
			(thermal_gap 0.5)
			(thermal_bridge_width 0.5)
			(island_removal_mode 0)
		)
		(polygon
			(pts
				(xy 107.95 -19.558) (xy 107.823 -19.685) (xy 107.823 -27.321002) (xy 107.696 -27.448002) (xy 102.235 -27.448002)
				(xy 100.838 -28.845002) (xy 100.584 -28.845002) (xy 100.33 -28.591002) (xy 99.695 -28.591002) (xy 99.314 -28.972002)
				(xy 99.314 -32.020002) (xy 100.059998 -32.766) (xy 100.711 -32.766) (xy 100.838 -32.893) (xy 100.838 -33.147)
				(xy 100.965 -33.274) (xy 101.092 -33.274) (xy 101.456998 -32.909002) (xy 103.124 -32.909002) (xy 103.759 -32.274002)
				(xy 103.759 -31.766002) (xy 103.886 -31.639002) (xy 104.902 -31.639002) (xy 105.029 -31.512002)
				(xy 105.029 -31.131002) (xy 104.902 -31.004002) (xy 104.902 -30.750002) (xy 105.283 -30.750002)
				(xy 105.537 -31.004002) (xy 106.299 -31.004002) (xy 106.426 -31.131002) (xy 109.093 -31.131002)
				(xy 109.347 -30.877002) (xy 110.363 -30.877002) (xy 111.252 -31.766002) (xy 111.76 -31.766002) (xy 112.268 -31.258002)
				(xy 112.268 -28.083002) (xy 112.014 -27.829002) (xy 109.982 -27.829002) (xy 109.601 -27.448002)
				(xy 109.601 -26.686002) (xy 108.839 -25.924002) (xy 108.839 -19.685) (xy 108.712 -19.558)
			)
		)
		(polygon
			(pts
				(xy 104.013 -30.927802) (xy 103.759 -30.927802) (xy 103.759 -31.181802) (xy 104.013 -31.181802)
			)
		)
		(polygon
			(pts
				(xy 110.363 -30.165802) (xy 110.109 -30.165802) (xy 110.109 -30.419802) (xy 110.363 -30.419802)
			)
		)
		(polygon
			(pts
				(xy 109.855 -30.165802) (xy 109.601 -30.165802) (xy 109.601 -30.419802) (xy 109.855 -30.419802)
			)
		)
		(polygon
			(pts
				(xy 110.617 -28.184602) (xy 110.363 -28.184602) (xy 110.363 -28.438602) (xy 110.617 -28.438602)
			)
		)
		(polygon
			(pts
				(xy 107.569 -27.803602) (xy 107.315 -27.803602) (xy 107.315 -28.057602) (xy 107.569 -28.057602)
			)
		)
		(polygon
			(pts
				(xy 107.061 -27.803602) (xy 106.553 -27.803602) (xy 106.553 -28.057602) (xy 107.061 -28.057602)
			)
		)
		(polygon
			(pts
				(xy 106.299 -27.803602) (xy 105.791 -27.803602) (xy 105.791 -28.057602) (xy 106.299 -28.057602)
			)
		)
		(polygon
			(pts
				(xy 105.537 -27.803602) (xy 105.029 -27.803602) (xy 105.029 -28.057602) (xy 105.537 -28.057602)
			)
		)
		(polygon
			(pts
				(xy 104.775 -27.803602) (xy 104.267 -27.803602) (xy 104.267 -28.057602) (xy 104.775 -28.057602)
			)
		)
		(polygon
			(pts
				(xy 104.013 -27.803602) (xy 103.505 -27.803602) (xy 103.505 -28.057602) (xy 104.013 -28.057602)
			)
		)
		(polygon
			(pts
				(xy 103.251 -27.803602) (xy 102.997 -27.803602) (xy 102.87 -27.905202) (xy 102.616 -27.905202) (xy 102.616 -28.159202)
				(xy 102.87 -28.159202) (xy 102.997 -28.057602) (xy 103.251 -28.057602)
			)
		)
	)
	(zone
		(net "P12V")
		(layer "B.Cu")
		(hatch none 0.5)
		(connect_pads
			(clearance 0.5)
		)
		(min_thickness 0.25)
		(fill yes
			(thermal_gap 0.5)
			(thermal_bridge_width 0.5)
			(island_removal_mode 0)
		)
		(polygon
			(pts
				(xy 96.266 -9.144) (xy 96.012 -9.398) (xy 96.012 -9.906) (xy 95.631 -10.287) (xy 94.234 -10.287)
				(xy 93.853 -10.668) (xy 93.853 -11.938) (xy 93.091 -12.7) (xy 93.091 -13.589) (xy 93.218 -13.716)
				(xy 96.52 -13.716) (xy 97.028 -13.208) (xy 97.028 -11.938) (xy 98.238056 -10.727944) (xy 98.237802 -10.700004)
				(xy 98.237802 -9.144)
			)
		)
	)
	(zone
		(net "GND")
		(layer "B.Cu")
		(hatch none 0.5)
		(connect_pads
			(clearance 0.5)
		)
		(min_thickness 0.25)
		(fill yes
			(thermal_gap 0.5)
			(thermal_bridge_width 0.5)
			(island_removal_mode 0)
		)
		(polygon
			(pts
				(xy 97.79 -51.562) (xy 97.663 -51.689) (xy 97.663 -51.943) (xy 97.282 -52.324) (xy 95.25 -52.324)
				(xy 95.123 -52.451) (xy 95.123 -53.34) (xy 95.25 -53.467) (xy 97.409 -53.467) (xy 97.79 -53.848)
				(xy 98.679 -53.848) (xy 98.806 -53.721) (xy 98.806 -52.324) (xy 98.933 -52.197) (xy 98.933 -51.689)
				(xy 98.806 -51.562)
			)
		)
		(polygon
			(pts
				(xy 98.3488 -52.832) (xy 98.0948 -52.832) (xy 98.0948 -53.086) (xy 98.1964 -53.086) (xy 98.1964 -53.34)
				(xy 98.4504 -53.34) (xy 98.4504 -53.086) (xy 98.3488 -53.086)
			)
		)
		(polygon
			(pts
				(xy 98.298 -51.8414) (xy 98.044 -51.8414) (xy 98.044 -52.0954) (xy 98.274886 -52.256944) (xy 98.133662 -52.468526)
				(xy 98.239326 -52.539138) (xy 98.416618 -52.2732) (xy 98.552 -52.2732) (xy 98.552 -52.0192)
			)
		)
	)
	(zone
		(layer "B.Cu")
		(hatch none 0.5)
		(connect_pads
			(clearance 0)
		)
		(min_thickness 0.25)
		(keepout
			(tracks not_allowed)
			(vias allowed)
			(pads allowed)
			(copperpour not_allowed)
			(footprints allowed)
		)
		(placement
			(enabled no)
			(sheetname "")
		)
		(fill
			(thermal_gap 0.5)
			(thermal_bridge_width 0.5)
			(island_removal_mode 0)
		)
		(polygon
			(pts
				(arc
					(start 82.296254 -13.56106)
					(mid 81.91246 -13.944473)
					(end 82.296 -14.32814)
				)
				(arc
					(start 83.1596 -14.32814)
					(mid 83.54314 -13.9446)
					(end 83.1596 -13.56106)
				)
				(xy 83.00085 -13.56106) (xy 83.00085 -13.66901)
				(arc
					(start 83.038696 -13.706856)
					(mid 83.3482 -14.1332)
					(end 82.921856 -13.823696)
				)
				(xy 82.88401 -13.78585) (xy 82.83575 -13.73759) (xy 82.83575 -13.66901) (xy 82.83575 -13.56106)
				(xy 82.65795 -13.56106) (xy 82.65795 -13.63091) (xy 82.65795 -13.69949) (xy 82.60969 -13.74775)
				(arc
					(start 82.533744 -13.823696)
					(mid 82.1074 -14.1332)
					(end 82.416904 -13.706856)
				)
				(xy 82.49285 -13.63091) (xy 82.49285 -13.56106)
			)
		)
	)
	(zone
		(layer "B.Cu")
		(hatch none 0.5)
		(connect_pads
			(clearance 0)
		)
		(min_thickness 0.25)
		(keepout
			(tracks allowed)
			(vias allowed)
			(pads allowed)
			(copperpour allowed)
			(footprints allowed)
		)
		(placement
			(enabled no)
			(sheetname "")
		)
		(fill
			(thermal_gap 0.5)
			(thermal_bridge_width 0.5)
			(island_removal_mode 0)
		)
		(polygon
			(pts
				(xy 69.85 -21.844) (xy 69.85 -19.939) (xy 72.136 -19.939) (xy 72.136 -21.844)
			)
		)
	)
	(zone
		(net "P3V3")
		(layer "B.Cu")
		(hatch none 0.5)
		(connect_pads
			(clearance 0.5)
		)
		(min_thickness 0.25)
		(fill yes
			(thermal_gap 0.5)
			(thermal_bridge_width 0.5)
			(island_removal_mode 0)
		)
		(polygon
			(pts
				(xy 53.721 -17.018) (xy 53.594 -17.145) (xy 53.594 -19.685) (xy 53.975 -20.066) (xy 56.642 -20.066)
				(xy 56.769 -19.939) (xy 56.769 -18.669) (xy 55.118 -17.018)
			)
		)
		(polygon
			(pts
				(xy 54.2036 -18.923) (xy 53.9496 -18.923) (xy 53.9496 -19.431) (xy 54.2036 -19.431)
			)
		)
		(polygon
			(pts
				(xy 54.2036 -18.161) (xy 53.9496 -18.161) (xy 53.9496 -18.669) (xy 54.2036 -18.669)
			)
		)
		(polygon
			(pts
				(xy 54.2036 -17.653) (xy 53.9496 -17.653) (xy 53.9496 -17.907) (xy 54.2036 -17.907)
			)
		)
	)
	(zone
		(layer "B.Cu")
		(hatch none 0.5)
		(connect_pads
			(clearance 0)
		)
		(min_thickness 0.25)
		(keepout
			(tracks allowed)
			(vias allowed)
			(pads allowed)
			(copperpour allowed)
			(footprints allowed)
		)
		(placement
			(enabled no)
			(sheetname "")
		)
		(fill
			(thermal_gap 0.5)
			(thermal_bridge_width 0.5)
			(island_removal_mode 0)
		)
		(polygon
			(pts
				(xy 119.888 -66.675) (xy 119.888 -60.198) (xy 130.556 -60.198) (xy 130.556 -66.675)
			)
		)
	)
	(zone
		(net "VR_PVIN_P1V8_STBY")
		(layer "B.Cu")
		(hatch none 0.5)
		(connect_pads
			(clearance 0.5)
		)
		(min_thickness 0.25)
		(fill yes
			(thermal_gap 0.5)
			(thermal_bridge_width 0.5)
			(island_removal_mode 0)
		)
		(polygon
			(pts
				(xy 73.533 -20.193) (xy 73.4187 -20.3073) (xy 72.3773 -20.3073) (xy 72.3138 -20.3708) (xy 72.3138 -20.701)
				(xy 72.263 -20.7518) (xy 71.1708 -20.7518) (xy 70.9676 -20.955) (xy 70.9676 -21.8186) (xy 70.993 -21.844)
				(xy 72.009 -21.844) (xy 72.644 -22.479) (xy 74.168 -22.479) (xy 74.295 -22.352) (xy 74.295 -21.4376)
				(xy 74.4093 -21.3233) (xy 75.0697 -21.3233) (xy 75.184 -21.209) (xy 75.184 -20.32) (xy 75.057 -20.193)
			)
		)
		(polygon
			(pts
				(xy 73.6219 -21.3614) (xy 73.3679 -21.3614) (xy 73.3679 -21.6154) (xy 73.6219 -21.6154)
			)
		)
		(polygon
			(pts
				(xy 73.0504 -20.5994) (xy 72.7964 -20.5994) (xy 72.7964 -20.8534) (xy 73.0504 -20.8534)
			)
		)
	)
	(zone
		(net "PV_VDDR")
		(layer "B.Cu")
		(hatch none 0.5)
		(connect_pads
			(clearance 0.5)
		)
		(min_thickness 0.25)
		(fill yes
			(thermal_gap 0.5)
			(thermal_bridge_width 0.5)
			(island_removal_mode 0)
		)
		(polygon
			(pts
				(xy 197.4088 -47.3202) (xy 196.977 -47.752) (xy 196.977 -51.054) (xy 197.358 -51.435) (xy 197.993 -51.435)
				(xy 198.755 -52.197) (xy 198.755 -57.0992) (xy 198.3232 -57.531) (xy 197.993 -57.531) (xy 197.739 -57.785)
				(xy 197.739 -61.468) (xy 197.612 -61.595) (xy 197.612 -65.024) (xy 197.739 -65.151) (xy 200.406 -65.151)
				(xy 200.787 -65.532) (xy 200.787 -66.802) (xy 201.676 -67.691) (xy 203.2 -67.691) (xy 203.454 -67.437)
				(xy 203.454 -55.88) (xy 203.2 -55.626) (xy 203.2 -51.562) (xy 202.819 -51.181) (xy 202.819 -48.26)
				(xy 203.2 -47.879) (xy 203.2 -47.5742) (xy 202.946 -47.3202)
			)
		)
		(polygon
			(pts
				(xy 202.7809 -67.056) (xy 202.5269 -67.056) (xy 202.5269 -67.31) (xy 202.7809 -67.31)
			)
		)
		(polygon
			(pts
				(xy 202.7809 -65.7352) (xy 202.5269 -65.7352) (xy 202.5269 -66.294) (xy 202.7809 -66.294)
			)
		)
		(polygon
			(pts
				(xy 202.7809 -64.4652) (xy 202.5269 -64.4652) (xy 202.5269 -64.9732) (xy 202.7809 -64.9732)
			)
		)
		(polygon
			(pts
				(xy 198.6407 -63.7032) (xy 198.3867 -63.7032) (xy 198.3867 -64.2112) (xy 198.6407 -64.2112)
			)
		)
		(polygon
			(pts
				(xy 202.7809 -63.4492) (xy 202.5269 -63.4492) (xy 202.5269 -63.7032) (xy 202.7809 -63.7032)
			)
		)
		(polygon
			(pts
				(xy 198.6407 -62.4332) (xy 198.3867 -62.4332) (xy 198.3867 -62.9412) (xy 198.6407 -62.9412)
			)
		)
		(polygon
			(pts
				(xy 198.6407 -61.4172) (xy 198.3867 -61.4172) (xy 198.3867 -61.6712) (xy 198.6407 -61.6712)
			)
		)
	)
	(zone
		(layer "B.Cu")
		(hatch none 0.5)
		(connect_pads
			(clearance 0)
		)
		(min_thickness 0.25)
		(keepout
			(tracks allowed)
			(vias allowed)
			(pads allowed)
			(copperpour allowed)
			(footprints not_allowed)
		)
		(placement
			(enabled no)
			(sheetname "")
		)
		(fill
			(thermal_gap 0.5)
			(thermal_bridge_width 0.5)
			(island_removal_mode 0)
		)
		(polygon
			(pts
				(arc
					(start 91.548966 -57.201054)
					(mid 85.951134 -58.701288)
					(end 91.548966 -60.201048)
				)
				(xy 98.951034 -60.201048) (xy 98.951034 -57.201054)
			)
		)
	)
	(zone
		(net "P3V3_STBY_VIN")
		(layer "B.Cu")
		(hatch none 0.5)
		(connect_pads
			(clearance 0.5)
		)
		(min_thickness 0.25)
		(fill yes
			(thermal_gap 0.5)
			(thermal_bridge_width 0.5)
			(island_removal_mode 0)
		)
		(polygon
			(pts
				(xy 6.096 -36.449) (xy 5.842 -36.703) (xy 5.842 -41.529) (xy 6.223 -41.91) (xy 8.509 -41.91) (xy 9.017 -41.402)
				(xy 9.017 -36.576) (xy 8.89 -36.449)
			)
		)
	)
	(zone
		(net "P1V0")
		(layer "B.Cu")
		(hatch none 0.5)
		(connect_pads
			(clearance 0.5)
		)
		(min_thickness 0.25)
		(fill yes
			(thermal_gap 0.5)
			(thermal_bridge_width 0.5)
			(island_removal_mode 0)
		)
		(polygon
			(pts
				(xy 92.583 -43.307) (xy 92.329 -43.561) (xy 92.329 -44.958) (xy 92.837 -45.466) (xy 92.837 -46.482)
				(xy 92.9386 -46.5836) (xy 92.9386 -49.276) (xy 92.8116 -49.403) (xy 92.8116 -50.1142) (xy 93.091 -50.3936)
				(xy 93.091 -52.832) (xy 93.4974 -53.2384) (xy 94.742 -53.2384) (xy 94.869 -53.1114) (xy 94.869 -52.4891)
				(xy 94.742 -52.3621) (xy 94.0816 -52.3621) (xy 93.7514 -52.0319) (xy 93.7514 -50.8889) (xy 94.0435 -50.5968)
				(xy 94.0435 -49.4157) (xy 93.5101 -48.8823) (xy 93.5101 -47.1424) (xy 93.68155 -46.97095) (xy 93.96095 -46.97095)
				(xy 94.107 -47.117) (xy 94.107 -47.8536) (xy 94.234 -47.9806) (xy 95.7326 -47.9806) (xy 95.8342 -47.879)
				(xy 95.8342 -47.4218) (xy 95.8088 -47.3964) (xy 95.3516 -47.3964) (xy 95.1738 -47.2186) (xy 95.1738 -45.4914)
				(xy 94.996 -45.3136) (xy 94.5388 -45.3136) (xy 94.361 -45.1358) (xy 94.361 -43.434) (xy 94.234 -43.307)
			)
		)
		(polygon
			(pts
				(xy 94.71152 -47.01794) (xy 94.45752 -47.01794) (xy 94.45752 -47.27194) (xy 94.488 -47.2948) (xy 94.488 -47.5488)
				(xy 94.742 -47.5488) (xy 94.742 -47.2948) (xy 94.71152 -47.27194)
			)
		)
		(polygon
			(pts
				(xy 93.4466 -46.5328) (xy 93.1926 -46.5328) (xy 93.1926 -46.7868) (xy 93.4466 -46.7868)
			)
		)
		(polygon
			(pts
				(xy 94.71152 -46.50994) (xy 94.45752 -46.50994) (xy 94.45752 -46.76394) (xy 94.71152 -46.76394)
			)
		)
		(polygon
			(pts
				(xy 93.4466 -45.7708) (xy 93.1926 -45.7708) (xy 93.1926 -46.2788) (xy 93.4466 -46.2788)
			)
		)
		(polygon
			(pts
				(xy 93.4466 -45.2628) (xy 93.1926 -45.2628) (xy 93.1926 -45.5168) (xy 93.4466 -45.5168)
			)
		)
	)
	(zone
		(net "GND")
		(layer "B.Cu")
		(hatch none 0.5)
		(connect_pads
			(clearance 0.5)
		)
		(min_thickness 0.25)
		(fill yes
			(thermal_gap 0.5)
			(thermal_bridge_width 0.5)
			(island_removal_mode 0)
		)
		(polygon
			(pts
				(xy 26.035 -41.148) (xy 22.606 -44.577) (xy 21.971 -44.577) (xy 21.59 -44.958) (xy 21.59 -45.847)
				(xy 23.114 -47.371) (xy 24.765 -47.371) (xy 25.4 -48.006) (xy 26.162 -48.006) (xy 26.543 -48.387)
				(xy 26.543 -48.895) (xy 26.67 -49.022) (xy 27.178 -49.022) (xy 27.686 -49.53) (xy 28.702 -49.53)
				(xy 28.8544 -49.6824) (xy 28.8544 -50.1396) (xy 28.9306 -50.2158) (xy 31.9278 -50.2158) (xy 32.004 -50.1396)
				(xy 32.004 -49.5046) (xy 32.1056 -49.403) (xy 33.528 -49.403) (xy 33.782 -49.149) (xy 33.782 -48.6664)
				(xy 33.9344 -48.514) (xy 33.9344 -47.9552) (xy 33.8582 -47.879) (xy 32.131 -47.879) (xy 32.0548 -47.8028)
				(xy 32.0548 -47.1424) (xy 31.9532 -47.0408) (xy 31.9278 -47.0408) (xy 31.877 -46.99) (xy 28.956 -46.99)
				(xy 28.829 -47.117) (xy 28.829 -47.625) (xy 28.702 -47.752) (xy 27.305 -47.752) (xy 26.924 -47.371)
				(xy 25.654 -47.371) (xy 25.273 -46.99) (xy 25.273 -43.307) (xy 25.781 -42.799) (xy 26.797 -42.799)
				(xy 26.8224 -42.7736) (xy 26.8478 -42.799) (xy 30.48 -42.799) (xy 30.5816 -42.6974) (xy 30.5816 -41.7068)
				(xy 30.607 -41.6814) (xy 30.607 -41.402) (xy 30.353 -41.148)
			)
		)
		(polygon
			(pts
				(xy 27.178 -48.4124) (xy 26.924 -48.4124) (xy 26.924 -48.6664) (xy 27.178 -48.6664)
			)
		)
		(polygon
			(pts
				(xy 33.5788 -48.26) (xy 33.3248 -48.26) (xy 33.3248 -48.514) (xy 33.5788 -48.514)
			)
		)
	)
	(zone
		(layer "B.Cu")
		(hatch none 0.5)
		(connect_pads
			(clearance 0)
		)
		(min_thickness 0.25)
		(keepout
			(tracks not_allowed)
			(vias allowed)
			(pads allowed)
			(copperpour not_allowed)
			(footprints allowed)
		)
		(placement
			(enabled no)
			(sheetname "")
		)
		(fill
			(thermal_gap 0.5)
			(thermal_bridge_width 0.5)
			(island_removal_mode 0)
		)
		(polygon
			(pts
				(arc
					(start 38.65372 -29.337254)
					(mid 38.270307 -28.95346)
					(end 37.88664 -29.337)
				)
				(xy 37.88664 -29.50845) (xy 37.98189 -29.50845)
				(arc
					(start 38.032436 -29.457904)
					(mid 38.45878 -29.1484)
					(end 38.149276 -29.574744)
				)
				(xy 38.09873 -29.62529) (xy 38.05047 -29.67355) (xy 37.98189 -29.67355) (xy 37.88664 -29.67355)
				(xy 37.88664 -29.85135) (xy 37.96919 -29.85135) (xy 38.03777 -29.85135) (xy 38.08603 -29.89961)
				(arc
					(start 38.149276 -29.962856)
					(mid 38.45878 -30.3892)
					(end 38.032436 -30.079696)
				)
				(xy 37.96919 -30.01645) (xy 37.88664 -30.01645)
				(arc
					(start 37.88664 -30.2006)
					(mid 38.27018 -30.58414)
					(end 38.65372 -30.2006)
				)
			)
		)
	)
	(zone
		(layer "B.Cu")
		(hatch none 0.5)
		(connect_pads
			(clearance 0)
		)
		(min_thickness 0.25)
		(keepout
			(tracks not_allowed)
			(vias allowed)
			(pads allowed)
			(copperpour not_allowed)
			(footprints allowed)
		)
		(placement
			(enabled no)
			(sheetname "")
		)
		(fill
			(thermal_gap 0.5)
			(thermal_bridge_width 0.5)
			(island_removal_mode 0)
		)
		(polygon
			(pts
				(arc
					(start 51.041554 -47.64278)
					(mid 50.663729 -47.253654)
					(end 50.274474 -47.63135)
				)
				(xy 50.271426 -47.840138) (xy 50.337974 -47.840138)
				(arc
					(start 50.42027 -47.757842)
					(mid 50.846614 -47.448338)
					(end 50.53711 -47.874682)
				)
				(xy 50.454814 -47.956978) (xy 50.406554 -48.005238) (xy 50.337974 -48.005238) (xy 50.26914 -48.005238)
				(xy 50.2666 -48.183038) (xy 50.376328 -48.183038) (xy 50.444908 -48.183038) (xy 50.493168 -48.231298)
				(arc
					(start 50.524664 -48.262794)
					(mid 50.834168 -48.689138)
					(end 50.407824 -48.379634)
				)
				(xy 50.376328 -48.348138) (xy 50.26406 -48.348138)
				(arc
					(start 50.262028 -48.49495)
					(mid 50.63998 -48.884078)
					(end 51.029108 -48.506126)
				)
				(xy 51.033172 -48.231298) (xy 51.03368 -48.183038) (xy 51.036982 -47.956978)
			)
		)
	)
	(zone
		(layer "B.Cu")
		(hatch none 0.5)
		(connect_pads
			(clearance 0)
		)
		(min_thickness 0.25)
		(keepout
			(tracks not_allowed)
			(vias allowed)
			(pads allowed)
			(copperpour not_allowed)
			(footprints allowed)
		)
		(placement
			(enabled no)
			(sheetname "")
		)
		(fill
			(thermal_gap 0.5)
			(thermal_bridge_width 0.5)
			(island_removal_mode 0)
		)
		(polygon
			(pts
				(arc
					(start 49.692052 -37.74567)
					(mid 49.15027 -37.771832)
					(end 49.176432 -38.313614)
				)
				(xy 49.306988 -38.432232) (xy 49.351692 -38.387528)
				(arc
					(start 49.351692 -38.283134)
					(mid 49.434242 -37.763047)
					(end 49.516792 -38.283134)
				)
				(xy 49.516792 -38.387528) (xy 49.516792 -38.456108) (xy 49.468532 -38.504368) (xy 49.429416 -38.543484)
				(xy 49.561242 -38.663118) (xy 49.64811 -38.57625) (xy 49.69637 -38.52799) (xy 49.76495 -38.52799)
				(arc
					(start 49.820068 -38.52799)
					(mid 50.340155 -38.61054)
					(end 49.820068 -38.69309)
				)
				(xy 49.76495 -38.69309) (xy 49.68367 -38.77437)
				(arc
					(start 49.81321 -38.892226)
					(mid 50.356403 -38.869633)
					(end 50.33137 -38.326568)
				)
			)
		)
	)
	(zone
		(layer "B.Cu")
		(hatch none 0.5)
		(connect_pads
			(clearance 0)
		)
		(min_thickness 0.25)
		(keepout
			(tracks not_allowed)
			(vias allowed)
			(pads allowed)
			(copperpour not_allowed)
			(footprints allowed)
		)
		(placement
			(enabled no)
			(sheetname "")
		)
		(fill
			(thermal_gap 0.5)
			(thermal_bridge_width 0.5)
			(island_removal_mode 0)
		)
		(polygon
			(pts
				(xy 52.91455 -35.69843) (xy 53.09235 -35.697922) (xy 53.09235 -35.65144) (xy 53.09235 -35.58286)
				(xy 53.14061 -35.5346)
				(arc
					(start 53.241194 -35.434016)
					(mid 53.667538 -35.124512)
					(end 53.358034 -35.550856)
				)
				(xy 53.25745 -35.65144) (xy 53.25745 -35.697414)
				(arc
					(start 53.479954 -35.696652)
					(mid 53.862478 -35.311969)
					(end 53.477668 -34.929572)
				)
				(arc
					(start 52.52339 -34.93262)
					(mid 52.14112 -35.31743)
					(end 52.52593 -35.6997)
				)
				(xy 52.74945 -35.698938) (xy 52.74945 -35.65779)
				(arc
					(start 52.645564 -35.553904)
					(mid 52.33606 -35.12756)
					(end 52.762404 -35.437064)
				)
				(xy 52.86629 -35.54095) (xy 52.91455 -35.58921) (xy 52.91455 -35.65779)
			)
		)
	)
	(zone
		(layer "B.Cu")
		(hatch none 0.5)
		(connect_pads
			(clearance 0)
		)
		(min_thickness 0.25)
		(keepout
			(tracks not_allowed)
			(vias allowed)
			(pads allowed)
			(copperpour not_allowed)
			(footprints allowed)
		)
		(placement
			(enabled no)
			(sheetname "")
		)
		(fill
			(thermal_gap 0.5)
			(thermal_bridge_width 0.5)
			(island_removal_mode 0)
		)
		(polygon
			(pts
				(arc
					(start 47.46371 -13.4112)
					(mid 47.08271 -13.7922)
					(end 47.46371 -14.1732)
				)
				(xy 47.5107 -14.1732)
				(arc
					(start 47.5107 -14.054836)
					(mid 47.324692 -13.564473)
					(end 47.6758 -13.953998)
				)
				(xy 47.6758 -13.95603) (xy 47.6758 -14.1732) (xy 47.8536 -14.1732) (xy 47.8536 -14.07414) (xy 47.8536 -14.00556)
				(xy 47.90186 -13.9573)
				(arc
					(start 47.946056 -13.913104)
					(mid 48.3724 -13.6036)
					(end 48.062896 -14.029944)
				)
				(xy 48.0187 -14.07414) (xy 48.0187 -14.1732)
				(arc
					(start 48.183546 -14.1732)
					(mid 48.5648 -13.792327)
					(end 48.1838 -13.4112)
				)
			)
		)
	)
	(zone
		(net "PV_VDDR")
		(layer "B.Cu")
		(hatch none 0.5)
		(connect_pads
			(clearance 0.5)
		)
		(min_thickness 0.25)
		(fill yes
			(thermal_gap 0.5)
			(thermal_bridge_width 0.5)
			(island_removal_mode 0)
		)
		(polygon
			(pts
				(xy 147.193 -59.436) (xy 146.939 -59.69) (xy 146.939 -60.579) (xy 147.701 -61.341) (xy 148.3614 -61.341)
				(xy 148.59 -61.5696) (xy 148.59 -63.4238) (xy 148.6408 -63.4746) (xy 148.844 -63.4746) (xy 148.9202 -63.3984)
				(xy 148.9202 -61.5442) (xy 149.1234 -61.341) (xy 150.7744 -61.341) (xy 150.9776 -61.5442) (xy 150.9776 -63.3984)
				(xy 151.0792 -63.5) (xy 151.2316 -63.5) (xy 151.3332 -63.3984) (xy 151.3332 -61.5696) (xy 151.5618 -61.341)
				(xy 153.2128 -61.341) (xy 153.3652 -61.4934) (xy 153.3652 -63.3984) (xy 153.4668 -63.5) (xy 153.6192 -63.5)
				(xy 153.7208 -63.3984) (xy 153.7208 -61.5188) (xy 153.8986 -61.341) (xy 155.0162 -61.341) (xy 155.1686 -61.4934)
				(xy 155.1686 -63.3984) (xy 155.2702 -63.5) (xy 155.4226 -63.5) (xy 155.5242 -63.3984) (xy 155.5242 -61.5188)
				(xy 155.702 -61.341) (xy 157.3784 -61.341) (xy 157.5816 -61.5442) (xy 157.5816 -63.3984) (xy 157.6832 -63.5)
				(xy 157.8356 -63.5) (xy 157.9118 -63.4238) (xy 157.9118 -61.5696) (xy 158.1404 -61.341) (xy 159.8168 -61.341)
				(xy 159.9946 -61.5188) (xy 159.9946 -63.4238) (xy 160.0708 -63.5) (xy 160.2232 -63.5) (xy 160.3248 -63.3984)
				(xy 160.3248 -61.5188) (xy 160.5026 -61.341) (xy 162.2044 -61.341) (xy 162.3822 -61.5188) (xy 162.3822 -63.4238)
				(xy 162.4584 -63.5) (xy 162.6362 -63.5) (xy 162.7124 -63.4238) (xy 162.7124 -61.8236) (xy 163.957 -60.579)
				(xy 163.957 -59.69) (xy 163.83 -59.563) (xy 159.131 -59.563) (xy 158.9278 -59.7662) (xy 154.5336 -59.7662)
				(xy 154.3812 -59.6138) (xy 153.416 -59.6138) (xy 153.0858 -59.944) (xy 152.3492 -59.944) (xy 151.8412 -59.436)
			)
		)
		(polygon
			(pts
				(xy 160.147 -60.2361) (xy 159.893 -60.2361) (xy 159.893 -60.4901) (xy 160.147 -60.4901)
			)
		)
		(polygon
			(pts
				(xy 153.543 -60.2361) (xy 153.289 -60.2361) (xy 153.289 -60.4901) (xy 153.543 -60.4901)
			)
		)
		(polygon
			(pts
				(xy 152.019 -60.2361) (xy 151.765 -60.2361) (xy 151.765 -60.4901) (xy 152.019 -60.4901)
			)
		)
		(polygon
			(pts
				(xy 151.003 -60.2361) (xy 150.749 -60.2361) (xy 150.749 -60.4901) (xy 151.003 -60.4901)
			)
		)
		(polygon
			(pts
				(xy 153.0604 -60.1726) (xy 152.8064 -60.1726) (xy 152.8064 -60.4266) (xy 153.0604 -60.4266)
			)
		)
		(polygon
			(pts
				(xy 152.5524 -60.1726) (xy 152.2984 -60.1726) (xy 152.2984 -60.4266) (xy 152.5524 -60.4266)
			)
		)
		(polygon
			(pts
				(xy 158.8262 -60.1472) (xy 158.5722 -60.1472) (xy 158.5722 -60.4012) (xy 158.8262 -60.4012) (xy 158.877 -60.4901)
				(xy 159.131 -60.4901) (xy 159.131 -60.2361) (xy 158.877 -60.2361)
			)
		)
		(polygon
			(pts
				(xy 158.3182 -60.1472) (xy 157.8102 -60.1472) (xy 157.8102 -60.4012) (xy 158.3182 -60.4012)
			)
		)
		(polygon
			(pts
				(xy 157.5562 -60.1472) (xy 157.0482 -60.1472) (xy 157.0482 -60.4012) (xy 157.5562 -60.4012)
			)
		)
		(polygon
			(pts
				(xy 156.7942 -60.1472) (xy 156.5402 -60.1472) (xy 156.5402 -60.4012) (xy 156.7942 -60.4012)
			)
		)
		(polygon
			(pts
				(xy 156.1338 -60.071) (xy 155.8798 -60.071) (xy 155.8798 -60.325) (xy 156.1338 -60.325)
			)
		)
		(polygon
			(pts
				(xy 155.6258 -60.071) (xy 155.1178 -60.071) (xy 155.1178 -60.325) (xy 155.6258 -60.325)
			)
		)
		(polygon
			(pts
				(xy 154.8638 -60.071) (xy 154.6098 -60.071) (xy 154.305 -60.2361) (xy 154.305 -60.4901) (xy 154.559 -60.4901)
				(xy 154.8638 -60.325)
			)
		)
	)
	(zone
		(net "GND")
		(layer "B.Cu")
		(hatch none 0.5)
		(connect_pads
			(clearance 0.5)
		)
		(min_thickness 0.25)
		(fill yes
			(thermal_gap 0.5)
			(thermal_bridge_width 0.5)
			(island_removal_mode 0)
		)
		(polygon
			(pts
				(xy 89.916 -61.849) (xy 89.789 -61.976) (xy 89.789 -67.818) (xy 89.916 -67.945) (xy 93.853 -67.945)
				(xy 94.234 -68.326) (xy 94.7928 -68.326) (xy 94.869 -68.2498) (xy 94.869 -67.9196) (xy 94.9198 -67.8688)
				(xy 96.901 -67.8688) (xy 96.9137 -67.8815) (xy 97.6503 -67.8815) (xy 97.79 -67.7418) (xy 97.79 -66.1924)
				(xy 97.6122 -66.0146) (xy 94.9452 -66.0146) (xy 94.8944 -65.9638) (xy 94.8944 -65.532) (xy 94.8182 -65.4558)
				(xy 94.1832 -65.4558) (xy 93.9038 -65.7352) (xy 91.9734 -65.7352) (xy 91.694 -65.4558) (xy 91.694 -61.976)
				(xy 91.567 -61.849)
			)
		)
	)
	(zone
		(net "GND")
		(layer "B.Cu")
		(hatch none 0.5)
		(connect_pads
			(clearance 0.5)
		)
		(min_thickness 0.25)
		(fill yes
			(thermal_gap 0.5)
			(thermal_bridge_width 0.5)
			(island_removal_mode 0)
		)
		(polygon
			(pts
				(xy 90.297 -40.767) (xy 90.17 -40.894) (xy 90.17 -41.275) (xy 90.297 -41.402) (xy 90.678 -41.402)
				(xy 90.805 -41.529) (xy 90.805 -42.037) (xy 91.059 -42.291) (xy 91.821 -42.291) (xy 92.202 -42.672)
				(xy 92.202 -42.926) (xy 91.948 -43.18) (xy 90.932 -43.18) (xy 90.678 -42.926) (xy 90.678 -42.672)
				(xy 90.551 -42.545) (xy 89.916 -42.545) (xy 89.662 -42.291) (xy 89.154 -42.291) (xy 89.027 -42.418)
				(xy 89.027 -42.672) (xy 89.154 -42.799) (xy 89.408 -42.799) (xy 89.916 -43.307) (xy 89.916 -44.577)
				(xy 89.789 -44.704) (xy 89.281 -44.704) (xy 89.154 -44.577) (xy 89.154 -44.323) (xy 89.027 -44.196)
				(xy 88.646 -44.196) (xy 88.519 -44.323) (xy 88.519 -45.085) (xy 88.773 -45.339) (xy 89.408 -45.339)
				(xy 89.535 -45.466) (xy 89.535 -45.847) (xy 89.662 -45.974) (xy 89.916 -45.974) (xy 90.043 -45.847)
				(xy 90.043 -45.339) (xy 90.932 -44.45) (xy 91.313 -44.45) (xy 92.075 -43.688) (xy 92.075 -43.561)
				(xy 92.583 -43.053) (xy 93.599 -43.053) (xy 93.726 -42.926) (xy 93.726 -42.672) (xy 93.599 -42.545)
				(xy 92.583 -42.545) (xy 92.2909 -42.2529) (xy 92.2909 -41.8465) (xy 92.4687 -41.6687) (xy 92.6846 -41.6687)
				(xy 92.7735 -41.5798) (xy 92.7735 -41.2496) (xy 92.6592 -41.1353) (xy 92.3417 -41.1353) (xy 92.2274 -41.2496)
				(xy 92.2274 -41.4401) (xy 92.03055 -41.63695) (xy 91.42095 -41.63695) (xy 91.313 -41.529) (xy 91.313 -40.894)
				(xy 91.186 -40.767)
			)
		)
		(polygon
			(pts
				(xy 89.916 -45.0596) (xy 89.662 -45.0596) (xy 89.662 -45.3136) (xy 89.916 -45.3136)
			)
		)
		(polygon
			(pts
				(xy 91.567 -43.5356) (xy 91.313 -43.5356) (xy 91.313 -43.7896) (xy 91.567 -43.7896)
			)
		)
		(polygon
			(pts
				(xy 91.059 -43.5356) (xy 90.805 -43.5356) (xy 90.551 -43.8404) (xy 90.551 -44.0944) (xy 91.059 -44.0944)
			)
		)
	)
	(zone
		(net "TPS74801_1V35_OUT")
		(layer "B.Cu")
		(hatch none 0.5)
		(connect_pads
			(clearance 0.5)
		)
		(min_thickness 0.25)
		(fill yes
			(thermal_gap 0.5)
			(thermal_bridge_width 0.5)
			(island_removal_mode 0)
		)
		(polygon
			(pts
				(xy 84.582 -14.732) (xy 83.947 -15.367) (xy 83.439 -15.367) (xy 83.312 -15.494) (xy 83.312 -16.129)
				(xy 83.439 -16.256) (xy 83.82 -16.256) (xy 84.074 -16.51) (xy 84.074 -18.415) (xy 84.201 -18.542)
				(xy 86.741 -18.542) (xy 87.503 -17.78) (xy 89.027 -17.78) (xy 89.154 -17.653) (xy 89.154 -15.367)
				(xy 88.9 -15.113) (xy 85.217 -15.113) (xy 85.09 -14.986) (xy 85.09 -14.859) (xy 84.963 -14.732)
			)
		)
	)
	(zone
		(layer "B.Cu")
		(hatch none 0.5)
		(connect_pads
			(clearance 0)
		)
		(min_thickness 0.25)
		(keepout
			(tracks not_allowed)
			(vias allowed)
			(pads allowed)
			(copperpour not_allowed)
			(footprints allowed)
		)
		(placement
			(enabled no)
			(sheetname "")
		)
		(fill
			(thermal_gap 0.5)
			(thermal_bridge_width 0.5)
			(island_removal_mode 0)
		)
		(polygon
			(pts
				(xy 7.75081 -51.04765) (xy 7.747 -51.04384) (xy 7.747 -51.22545) (xy 7.78891 -51.22545) (xy 7.85749 -51.22545)
				(xy 7.90575 -51.27371)
				(arc
					(start 8.007096 -51.375056)
					(mid 8.3166 -51.8014)
					(end 7.890256 -51.491896)
				)
				(xy 7.78891 -51.39055) (xy 7.747 -51.39055)
				(arc
					(start 7.747 -51.6128)
					(mid 8.128 -51.9938)
					(end 8.509 -51.6128)
				)
				(arc
					(start 8.509 -50.622454)
					(mid 8.128127 -50.2412)
					(end 7.747 -50.6222)
				)
				(xy 7.747 -50.88636)
				(arc
					(start 7.890256 -50.743104)
					(mid 8.3166 -50.4336)
					(end 8.007096 -50.859944)
				)
				(xy 7.81939 -51.04765)
			)
		)
	)
	(zone
		(layer "B.Cu")
		(hatch none 0.5)
		(connect_pads
			(clearance 0)
		)
		(min_thickness 0.25)
		(keepout
			(tracks allowed)
			(vias allowed)
			(pads allowed)
			(copperpour allowed)
			(footprints allowed)
		)
		(placement
			(enabled no)
			(sheetname "")
		)
		(fill
			(thermal_gap 0.5)
			(thermal_bridge_width 0.5)
			(island_removal_mode 0)
		)
		(polygon
			(pts
				(xy 54.9656 -31.3182) (xy 54.9656 -29.5148) (xy 57.2516 -29.5148) (xy 57.2516 -31.3182)
			)
		)
	)
	(zone
		(layer "B.Cu")
		(hatch none 0.5)
		(connect_pads
			(clearance 0)
		)
		(min_thickness 0.25)
		(keepout
			(tracks allowed)
			(vias allowed)
			(pads allowed)
			(copperpour allowed)
			(footprints allowed)
		)
		(placement
			(enabled no)
			(sheetname "")
		)
		(fill
			(thermal_gap 0.5)
			(thermal_bridge_width 0.5)
			(island_removal_mode 0)
		)
		(polygon
			(pts
				(xy 190.373 -6.605778) (xy 190.373 -0.128778) (xy 200.279 -0.128778) (xy 200.279 -6.605778)
			)
		)
	)
	(zone
		(layer "B.Cu")
		(hatch none 0.5)
		(connect_pads
			(clearance 0)
		)
		(min_thickness 0.25)
		(keepout
			(tracks allowed)
			(vias allowed)
			(pads allowed)
			(copperpour allowed)
			(footprints allowed)
		)
		(placement
			(enabled no)
			(sheetname "")
		)
		(fill
			(thermal_gap 0.5)
			(thermal_bridge_width 0.5)
			(island_removal_mode 0)
		)
		(polygon
			(pts
				(xy 40.7924 -53.721) (xy 40.7924 -42.926) (xy 50.5968 -42.926) (xy 50.5968 -53.721)
			)
		)
	)
	(zone
		(net "PV_VTT_DDR_A")
		(layer "B.Cu")
		(hatch none 0.5)
		(connect_pads
			(clearance 0.5)
		)
		(min_thickness 0.25)
		(fill yes
			(thermal_gap 0.5)
			(thermal_bridge_width 0.5)
			(island_removal_mode 0)
		)
		(polygon
			(pts
				(xy 126.492 -56.642) (xy 124.714 -58.42) (xy 119.888 -58.42) (xy 119.507 -58.801) (xy 119.507 -63.5)
				(xy 120.2055 -64.1985) (xy 126.4285 -64.1985) (xy 127.254 -63.373) (xy 127.254 -60.833) (xy 130.175 -57.912)
				(xy 133.985 -57.912) (xy 134.239 -57.658) (xy 134.239 -56.896) (xy 133.985 -56.642)
			)
		)
		(polygon
			(pts
				(xy 120.1166 -61.722) (xy 119.8626 -61.722) (xy 119.8626 -61.976) (xy 120.1166 -61.976)
			)
		)
		(polygon
			(pts
				(xy 120.1166 -61.214) (xy 119.8626 -61.214) (xy 119.8626 -61.468) (xy 120.1166 -61.468)
			)
		)
		(polygon
			(pts
				(xy 120.5611 -60.96) (xy 120.3071 -60.96) (xy 120.3071 -61.214) (xy 120.5611 -61.214)
			)
		)
		(polygon
			(pts
				(xy 120.5611 -59.563) (xy 120.3071 -59.563) (xy 120.3071 -60.198) (xy 120.5611 -60.198)
			)
		)
		(polygon
			(pts
				(xy 133.35 -57.3151) (xy 133.096 -57.3151) (xy 133.096 -57.5691) (xy 133.35 -57.5691)
			)
		)
		(polygon
			(pts
				(xy 132.334 -57.3151) (xy 131.826 -57.3151) (xy 131.826 -57.5691) (xy 132.334 -57.5691)
			)
		)
		(polygon
			(pts
				(xy 131.064 -57.3151) (xy 130.556 -57.3151) (xy 130.556 -57.5691) (xy 131.064 -57.5691)
			)
		)
		(polygon
			(pts
				(xy 129.794 -57.3151) (xy 129.159 -57.3151) (xy 129.159 -57.5691) (xy 129.794 -57.5691)
			)
		)
		(polygon
			(pts
				(xy 128.397 -57.3151) (xy 128.143 -57.3151) (xy 128.143 -57.5691) (xy 128.397 -57.5691)
			)
		)
	)
	(zone
		(net "GND")
		(layer "B.Cu")
		(hatch none 0.5)
		(connect_pads
			(clearance 0.5)
		)
		(min_thickness 0.25)
		(fill yes
			(thermal_gap 0.5)
			(thermal_bridge_width 0.5)
			(island_removal_mode 0)
		)
		(polygon
			(pts
				(xy 9.525 -34.925) (xy 9.398 -35.052) (xy 9.398 -41.021) (xy 9.779 -41.402) (xy 13.208 -41.402)
				(xy 13.462 -41.148) (xy 13.462 -35.052) (xy 13.335 -34.925)
			)
		)
	)
	(zone
		(layer "B.Cu")
		(hatch none 0.5)
		(connect_pads
			(clearance 0)
		)
		(min_thickness 0.25)
		(keepout
			(tracks allowed)
			(vias allowed)
			(pads allowed)
			(copperpour allowed)
			(footprints not_allowed)
		)
		(placement
			(enabled no)
			(sheetname "")
		)
		(fill
			(thermal_gap 0.5)
			(thermal_bridge_width 0.5)
			(island_removal_mode 0)
		)
		(polygon
			(pts
				(xy 9.400032 -36.805108) (xy 6.999986 -36.805108) (xy 6.999986 -46.630082) (xy 9.400032 -46.630082)
			)
		)
	)
	(zone
		(net "P1V8_STBY_VOUT")
		(layer "B.Cu")
		(hatch none 0.5)
		(connect_pads
			(clearance 0.5)
		)
		(min_thickness 0.25)
		(fill yes
			(thermal_gap 0.5)
			(thermal_bridge_width 0.5)
			(island_removal_mode 0)
		)
		(polygon
			(pts
				(xy 69.596 -14.732) (xy 68.834 -15.494) (xy 68.072 -15.494) (xy 67.564 -16.002) (xy 67.564 -20.193)
				(xy 67.818 -20.447) (xy 69.342 -20.447) (xy 69.469 -20.32) (xy 69.469 -19.812) (xy 69.342 -19.685)
				(xy 68.707 -19.685) (xy 68.58 -19.558) (xy 68.58 -18.3642) (xy 68.8086 -18.1356) (xy 69.8246 -18.1356)
				(xy 69.977 -17.9832) (xy 69.977 -16.764) (xy 70.485 -16.256) (xy 70.485 -14.859) (xy 70.358 -14.732)
			)
		)
		(polygon
			(pts
				(xy 68.2752 -17.907) (xy 68.0212 -17.907) (xy 68.0212 -18.161) (xy 68.2752 -18.161)
			)
		)
		(polygon
			(pts
				(xy 68.4911 -17.018) (xy 68.2371 -17.018) (xy 68.0212 -17.399) (xy 68.0212 -17.653) (xy 68.2752 -17.653)
				(xy 68.4911 -17.272)
			)
		)
		(polygon
			(pts
				(xy 68.4911 -16.002) (xy 68.2371 -16.002) (xy 68.2371 -16.256) (xy 68.4911 -16.256)
			)
		)
	)
	(zone
		(layer "B.Cu")
		(hatch none 0.5)
		(connect_pads
			(clearance 0)
		)
		(min_thickness 0.25)
		(keepout
			(tracks not_allowed)
			(vias allowed)
			(pads allowed)
			(copperpour not_allowed)
			(footprints allowed)
		)
		(placement
			(enabled no)
			(sheetname "")
		)
		(fill
			(thermal_gap 0.5)
			(thermal_bridge_width 0.5)
			(island_removal_mode 0)
		)
		(polygon
			(pts
				(arc
					(start 51.2826 -33.70326)
					(mid 50.898806 -34.086673)
					(end 51.282346 -34.47034)
				)
				(xy 51.53025 -34.47034) (xy 51.53025 -34.451544)
				(arc
					(start 51.40325 -34.324544)
					(mid 51.093746 -33.8982)
					(end 51.52009 -34.207704)
				)
				(xy 51.64709 -34.334704) (xy 51.69535 -34.382964) (xy 51.69535 -34.451544) (xy 51.69535 -34.47034)
				(xy 51.87315 -34.47034) (xy 51.87315 -34.33191) (xy 51.87315 -34.26333) (xy 51.92141 -34.21507)
				(arc
					(start 51.928776 -34.207704)
					(mid 52.35512 -33.8982)
					(end 52.045616 -34.324544)
				)
				(xy 52.03825 -34.33191) (xy 52.03825 -34.47034)
				(arc
					(start 52.16652 -34.47034)
					(mid 52.55006 -34.0868)
					(end 52.16652 -33.70326)
				)
			)
		)
	)
	(zone
		(net "GND")
		(layer "B.Cu")
		(hatch none 0.5)
		(connect_pads
			(clearance 0.5)
		)
		(min_thickness 0.25)
		(fill yes
			(thermal_gap 0.5)
			(thermal_bridge_width 0.5)
			(island_removal_mode 0)
		)
		(polygon
			(pts
				(xy 81.4832 -20.1422) (xy 81.4578 -20.1676) (xy 81.4578 -21.2598) (xy 80.645 -22.0726) (xy 80.645 -22.606)
				(xy 80.899 -22.86) (xy 82.042 -22.86) (xy 83.058 -23.876) (xy 83.058 -25.146) (xy 83.566 -25.654)
				(xy 83.947 -25.654) (xy 84.328 -26.035) (xy 85.979 -26.035) (xy 86.106 -26.162) (xy 88.011 -26.162)
				(xy 88.138 -26.289) (xy 88.138 -27.813) (xy 88.265 -27.94) (xy 88.646 -27.94) (xy 89.027 -27.559)
				(xy 89.027 -25.4) (xy 88.9 -25.273) (xy 88.519 -25.273) (xy 88.392 -25.146) (xy 88.392 -23.876)
				(xy 88.265 -23.749) (xy 88.011 -23.749) (xy 87.757 -23.495) (xy 87.757 -22.098) (xy 86.868 -21.209)
				(xy 86.36 -21.209) (xy 86.233 -21.336) (xy 86.233 -22.606) (xy 85.979 -22.86) (xy 83.693 -22.86)
				(xy 83.058 -22.225) (xy 83.058 -21.8694) (xy 83.0834 -21.844) (xy 83.0834 -20.193) (xy 83.0326 -20.1422)
			)
		)
		(polygon
			(pts
				(xy 88.6714 -27.178) (xy 88.4174 -27.178) (xy 88.4174 -27.432) (xy 88.6714 -27.432)
			)
		)
		(polygon
			(pts
				(xy 88.6714 -26.416) (xy 88.4174 -26.416) (xy 88.4174 -26.924) (xy 88.6714 -26.924)
			)
		)
		(polygon
			(pts
				(xy 88.6714 -25.654) (xy 88.4174 -25.654) (xy 88.4174 -26.162) (xy 88.6714 -26.162)
			)
		)
		(polygon
			(pts
				(xy 87.46236 -25.23236) (xy 86.95436 -25.23236) (xy 86.95436 -25.48636) (xy 87.46236 -25.48636)
			)
		)
		(polygon
			(pts
				(xy 86.70036 -25.23236) (xy 86.44636 -25.23236) (xy 86.44636 -25.48636) (xy 86.70036 -25.48636)
			)
		)
		(polygon
			(pts
				(xy 88.0364 -24.892) (xy 87.7824 -24.892) (xy 87.7824 -25.146) (xy 87.71636 -25.23236) (xy 87.71636 -25.48636)
				(xy 87.97036 -25.48636) (xy 87.97036 -25.23236) (xy 88.0364 -25.146)
			)
		)
		(polygon
			(pts
				(xy 88.0364 -24.13) (xy 87.7824 -24.13) (xy 87.7824 -24.638) (xy 88.0364 -24.638)
			)
		)
		(polygon
			(pts
				(xy 87.4014 -23.368) (xy 87.1474 -23.368) (xy 87.1474 -23.622) (xy 87.4014 -23.622)
			)
		)
		(polygon
			(pts
				(xy 87.4014 -22.606) (xy 87.1474 -22.606) (xy 87.1474 -23.114) (xy 87.4014 -23.114)
			)
		)
		(polygon
			(pts
				(xy 87.4014 -22.098) (xy 87.1474 -22.098) (xy 87.1474 -22.352) (xy 87.4014 -22.352)
			)
		)
		(polygon
			(pts
				(xy 82.7024 -21.717) (xy 82.4484 -21.717) (xy 82.4484 -21.971) (xy 82.7024 -21.971)
			)
		)
		(polygon
			(pts
				(xy 86.9442 -21.59) (xy 86.6902 -21.59) (xy 86.6902 -21.844) (xy 86.9442 -21.844)
			)
		)
		(polygon
			(pts
				(xy 82.7024 -21.209) (xy 82.4484 -21.209) (xy 82.4484 -21.463) (xy 82.7024 -21.463)
			)
		)
	)
	(zone
		(net "P1V5_STBY_OUT")
		(layer "B.Cu")
		(hatch none 0.5)
		(connect_pads
			(clearance 0.5)
		)
		(min_thickness 0.25)
		(fill yes
			(thermal_gap 0.5)
			(thermal_bridge_width 0.5)
			(island_removal_mode 0)
		)
		(polygon
			(pts
				(xy 31.115 -42.672) (xy 30.353 -43.434) (xy 25.908 -43.434) (xy 25.781 -43.561) (xy 25.781 -46.736)
				(xy 26.035 -46.99) (xy 27.178 -46.99) (xy 27.686 -47.498) (xy 28.194 -47.498) (xy 28.321 -47.371)
				(xy 28.321 -46.736) (xy 28.448 -46.609) (xy 30.353 -46.609) (xy 30.48 -46.482) (xy 30.48 -45.085)
				(xy 30.861 -44.704) (xy 31.242 -44.704) (xy 31.369 -44.577) (xy 31.369 -44.069) (xy 31.496 -43.942)
				(xy 32.893 -43.942) (xy 33.02 -43.815) (xy 33.02 -42.672)
			)
		)
		(polygon
			(pts
				(xy 31.0134 -44.069) (xy 30.7594 -44.069) (xy 30.7594 -44.323) (xy 31.0134 -44.323)
			)
		)
		(polygon
			(pts
				(xy 32.004 -43.4721) (xy 31.75 -43.4721) (xy 31.75 -43.7261) (xy 32.004 -43.7261)
			)
		)
		(polygon
			(pts
				(xy 30.988 -43.4721) (xy 30.734 -43.4721) (xy 30.734 -43.7261) (xy 30.988 -43.7261)
			)
		)
		(polygon
			(pts
				(xy 32.5628 -43.053) (xy 32.3088 -43.053) (xy 32.3088 -43.307) (xy 32.4104 -43.307) (xy 32.4104 -43.561)
				(xy 32.6644 -43.561) (xy 32.6644 -43.307) (xy 32.5628 -43.307)
			)
		)
	)
	(zone
		(net "P3V3_STBY")
		(layer "B.Cu")
		(hatch none 0.5)
		(connect_pads
			(clearance 0.5)
		)
		(min_thickness 0.25)
		(fill yes
			(thermal_gap 0.5)
			(thermal_bridge_width 0.5)
			(island_removal_mode 0)
		)
		(polygon
			(pts
				(xy 77.216 -21.336) (xy 77.089 -21.463) (xy 74.93 -21.463) (xy 74.803 -21.59) (xy 74.803 -22.606)
				(xy 74.676 -22.733) (xy 73.914 -22.733) (xy 73.787 -22.86) (xy 73.787 -24.003) (xy 73.914 -24.13)
				(xy 75.692 -24.13) (xy 76.454 -23.368) (xy 76.708 -23.368) (xy 77.724 -22.352) (xy 77.724 -21.336)
			)
		)
		(polygon
			(pts
				(xy 74.549 -23.1394) (xy 74.295 -23.1394) (xy 74.295 -23.3934) (xy 74.549 -23.3934)
			)
		)
		(polygon
			(pts
				(xy 75.7301 -22.3774) (xy 75.4761 -22.3774) (xy 75.4761 -22.6314) (xy 75.7301 -22.6314)
			)
		)
	)
	(zone
		(net "GND")
		(layer "B.Cu")
		(hatch none 0.5)
		(connect_pads
			(clearance 0.5)
		)
		(min_thickness 0.25)
		(fill yes
			(thermal_gap 0.5)
			(thermal_bridge_width 0.5)
			(island_removal_mode 0)
		)
		(polygon
			(pts
				(xy 17.78 -43.942) (xy 15.621 -46.101) (xy 15.621 -47.117) (xy 15.494 -47.244) (xy 14.097 -47.244)
				(xy 13.462 -46.609) (xy 13.208 -46.609) (xy 13.081 -46.736) (xy 13.081 -46.99) (xy 13.589 -47.498)
				(xy 13.589 -49.149) (xy 13.716 -49.276) (xy 13.97 -49.276) (xy 14.097 -49.149) (xy 14.097 -48.26)
				(xy 14.351 -48.006) (xy 17.399 -48.006) (xy 17.526 -47.879) (xy 17.526 -46.482) (xy 18.415 -45.593)
				(xy 18.415 -44.069) (xy 18.288 -43.942)
			)
		)
		(polygon
			(pts
				(xy 17.018 -47.3964) (xy 16.51 -47.3964) (xy 16.51 -47.6504) (xy 17.018 -47.6504)
			)
		)
		(polygon
			(pts
				(xy 16.256 -47.3964) (xy 15.748 -47.3964) (xy 15.748 -47.6504) (xy 16.256 -47.6504)
			)
		)
		(polygon
			(pts
				(xy 15.494 -47.3964) (xy 14.986 -47.3964) (xy 14.986 -47.6504) (xy 15.494 -47.6504)
			)
		)
		(polygon
			(pts
				(xy 14.732 -47.3964) (xy 14.478 -47.3964) (xy 14.478 -47.6504) (xy 14.732 -47.6504)
			)
		)
	)
	(zone
		(layer "B.Cu")
		(hatch none 0.5)
		(connect_pads
			(clearance 0)
		)
		(min_thickness 0.25)
		(keepout
			(tracks not_allowed)
			(vias allowed)
			(pads allowed)
			(copperpour not_allowed)
			(footprints allowed)
		)
		(placement
			(enabled no)
			(sheetname "")
		)
		(fill
			(thermal_gap 0.5)
			(thermal_bridge_width 0.5)
			(island_removal_mode 0)
		)
		(polygon
			(pts
				(arc
					(start 39.443914 -11.9634)
					(mid 39.06012 -12.346813)
					(end 39.44366 -12.73048)
				)
				(xy 39.66845 -12.73048) (xy 39.66845 -12.68857)
				(arc
					(start 39.564564 -12.584684)
					(mid 39.25506 -12.15834)
					(end 39.681404 -12.467844)
				)
				(xy 39.78529 -12.57173) (xy 39.83355 -12.61999) (xy 39.83355 -12.68857) (xy 39.83355 -12.73048)
				(xy 40.01135 -12.73048) (xy 40.01135 -12.68857) (xy 40.01135 -12.61999) (xy 40.05961 -12.57173)
				(arc
					(start 40.163496 -12.467844)
					(mid 40.58984 -12.15834)
					(end 40.280336 -12.584684)
				)
				(xy 40.17645 -12.68857) (xy 40.17645 -12.73048)
				(arc
					(start 40.40124 -12.73048)
					(mid 40.78478 -12.34694)
					(end 40.40124 -11.9634)
				)
			)
		)
	)
	(zone
		(layer "B.Cu")
		(hatch none 0.5)
		(connect_pads
			(clearance 0)
		)
		(min_thickness 0.25)
		(keepout
			(tracks allowed)
			(vias allowed)
			(pads allowed)
			(copperpour allowed)
			(footprints not_allowed)
		)
		(placement
			(enabled no)
			(sheetname "")
		)
		(fill
			(thermal_gap 0.5)
			(thermal_bridge_width 0.5)
			(island_removal_mode 0)
		)
		(polygon
			(pts
				(xy 126.000002 -9.240012) (xy 194.00012 -9.240012) (xy 194.00012 -36.139882) (xy 192.499996 -36.139882)
				(xy 192.499996 -63.799974) (xy 124.499878 -63.799974) (xy 124.499878 -36.139882) (xy 126.000002 -36.139882)
			)
		)
	)
	(zone
		(net "P1V5_STBY_IN")
		(layer "B.Cu")
		(hatch none 0.5)
		(connect_pads
			(clearance 0.5)
		)
		(min_thickness 0.25)
		(fill yes
			(thermal_gap 0.5)
			(thermal_bridge_width 0.5)
			(island_removal_mode 0)
		)
		(polygon
			(pts
				(xy 25.146 -48.387) (xy 25.019 -48.514) (xy 25.019 -50.038) (xy 27.305 -52.324) (xy 28.194 -52.324)
				(xy 28.575 -51.943) (xy 30.226 -51.943) (xy 30.607 -51.562) (xy 30.607 -50.673) (xy 30.5054 -50.5714)
				(xy 28.4988 -50.5714) (xy 28.448 -50.5206) (xy 28.448 -49.911) (xy 28.321 -49.784) (xy 27.559 -49.784)
				(xy 27.051 -49.276) (xy 26.416 -49.276) (xy 26.162 -49.022) (xy 26.162 -48.514) (xy 26.035 -48.387)
			)
		)
		(polygon
			(pts
				(xy 26.67 -49.6316) (xy 26.416 -49.6316) (xy 26.416 -49.8856) (xy 26.67 -49.8856)
			)
		)
		(polygon
			(pts
				(xy 25.9461 -49.403) (xy 25.6921 -49.403) (xy 25.6921 -49.657) (xy 25.9461 -49.657)
			)
		)
	)
	(zone
		(net "GND")
		(layer "B.Cu")
		(hatch none 0.5)
		(connect_pads
			(clearance 0.5)
		)
		(min_thickness 0.25)
		(fill yes
			(thermal_gap 0.5)
			(thermal_bridge_width 0.5)
			(island_removal_mode 0)
		)
		(polygon
			(pts
				(xy 98.679 -59.7281) (xy 98.171 -60.2361) (xy 98.171 -61.595) (xy 99.314 -62.738) (xy 100.584 -62.738)
				(xy 101.092 -63.246) (xy 102.489 -63.246) (xy 102.997 -63.754) (xy 102.997 -64.008) (xy 102.87 -64.135)
				(xy 102.87 -64.897) (xy 104.2416 -66.2686) (xy 105.3846 -66.2686) (xy 108.204 -69.088) (xy 111.633 -69.088)
				(xy 113.157 -67.564) (xy 114.935 -67.564) (xy 115.062 -67.437) (xy 115.062 -65.278) (xy 114.808 -65.024)
				(xy 113.284 -65.024) (xy 113.03 -65.278) (xy 113.03 -66.548) (xy 112.776 -66.802) (xy 110.49 -66.802)
				(xy 110.363 -66.675) (xy 110.363 -64.008) (xy 110.109 -63.754) (xy 106.045 -63.754) (xy 102.0191 -59.7281)
			)
		)
	)
	(zone
		(net "PVCCP")
		(layer "B.Cu")
		(hatch none 0.5)
		(connect_pads
			(clearance 0.5)
		)
		(min_thickness 0.25)
		(fill yes
			(thermal_gap 0.5)
			(thermal_bridge_width 0.5)
			(island_removal_mode 0)
		)
		(polygon
			(pts
				(xy 113.157 -35.306) (xy 112.395 -36.068) (xy 111.633 -36.068) (xy 111.506 -36.195) (xy 111.506 -37.354002)
				(xy 111.125 -37.735002) (xy 107.315 -37.735002) (xy 107.298998 -37.719) (xy 104.267 -37.719) (xy 104.250998 -37.735002)
				(xy 102.87 -37.735002) (xy 102.616 -37.481002) (xy 102.616 -37.227002) (xy 102.489 -37.100002) (xy 102.235 -37.100002)
				(xy 102.108 -36.973002) (xy 101.118416 -36.973002) (xy 101.105208 -36.98621) (xy 100.443792 -36.98621)
				(xy 100.33 -37.100002) (xy 100.33 -37.481002) (xy 100.203 -37.608002) (xy 99.822 -37.608002) (xy 99.568 -37.862002)
				(xy 99.568 -41.291002) (xy 99.695 -41.418002) (xy 99.949 -41.418002) (xy 99.957128 -41.410128) (xy 101.343968 -41.410128)
				(xy 101.346 -41.408096) (xy 102.2604 -41.408096) (xy 102.75062 -40.917622) (xy 103.75138 -40.917622)
				(xy 103.759 -40.910002) (xy 108.594906 -40.910002) (xy 109.089952 -41.405048) (xy 109.093 -41.402)
				(xy 109.601 -41.402) (xy 109.855 -41.656) (xy 109.855 -42.672) (xy 110.109 -42.926) (xy 110.109 -43.434)
				(xy 110.735872 -44.060872) (xy 110.735872 -44.069) (xy 110.744 -44.069) (xy 110.871 -44.196) (xy 110.871 -45.085)
				(xy 110.998 -45.212) (xy 114.427 -45.212) (xy 114.554 -45.085) (xy 114.554 -44.196) (xy 114.046 -43.688)
				(xy 114.046 -42.545) (xy 115.189 -41.402) (xy 115.189 -35.433) (xy 115.062 -35.306)
			)
		)
		(polygon
			(pts
				(xy 110.7186 -43.307) (xy 110.4646 -43.307) (xy 110.4646 -43.561) (xy 110.7186 -43.561)
			)
		)
		(polygon
			(pts
				(xy 101.946964 -40.7924) (xy 101.692964 -40.7924) (xy 101.692964 -41.0464) (xy 101.946964 -41.0464)
			)
		)
		(polygon
			(pts
				(xy 107.696 -40.2844) (xy 107.442 -40.2844) (xy 107.442 -40.5384) (xy 107.696 -40.5384)
			)
		)
		(polygon
			(pts
				(xy 110.8456 -38.0746) (xy 110.5916 -38.0746) (xy 110.5916 -38.3286) (xy 110.8456 -38.3286)
			)
		)
		(polygon
			(pts
				(xy 110.3376 -38.0746) (xy 110.0836 -38.0746) (xy 110.0836 -38.3286) (xy 110.3376 -38.3286)
			)
		)
	)
	(zone
		(net "P1V5_STBY")
		(layer "B.Cu")
		(hatch none 0.5)
		(connect_pads
			(clearance 0.5)
		)
		(min_thickness 0.25)
		(fill yes
			(thermal_gap 0.5)
			(thermal_bridge_width 0.5)
			(island_removal_mode 0)
		)
		(polygon
			(pts
				(xy 31.369 -40.767) (xy 30.861 -41.275) (xy 30.861 -42.291) (xy 30.988 -42.418) (xy 32.893 -42.418)
				(xy 33.02 -42.291) (xy 33.02 -41.021) (xy 32.766 -40.767)
			)
		)
		(polygon
			(pts
				(xy 32.004 -41.3639) (xy 31.75 -41.3639) (xy 31.75 -41.6179) (xy 32.004 -41.6179)
			)
		)
	)
	(zone
		(net "GND")
		(layer "B.Cu")
		(hatch none 0.5)
		(connect_pads
			(clearance 0.5)
		)
		(min_thickness 0.25)
		(fill yes
			(thermal_gap 0.5)
			(thermal_bridge_width 0.5)
			(island_removal_mode 0)
		)
		(polygon
			(pts
				(xy 98.044 -38.481) (xy 97.917 -38.608) (xy 97.917 -39.624) (xy 98.171 -39.878) (xy 99.187 -39.878)
				(xy 99.187 -38.862) (xy 99.06 -38.735) (xy 98.552 -38.735) (xy 98.298 -38.481)
			)
		)
		(polygon
			(pts
				(xy 98.5266 -38.862) (xy 98.2726 -38.862) (xy 98.2726 -39.116) (xy 98.552 -39.335202) (xy 98.806 -39.335202)
				(xy 98.806 -39.081202)
			)
		)
	)
	(zone
		(layer "B.Cu")
		(hatch none 0.5)
		(connect_pads
			(clearance 0)
		)
		(min_thickness 0.25)
		(keepout
			(tracks allowed)
			(vias allowed)
			(pads allowed)
			(copperpour allowed)
			(footprints not_allowed)
		)
		(placement
			(enabled no)
			(sheetname "")
		)
		(fill
			(thermal_gap 0.5)
			(thermal_bridge_width 0.5)
			(island_removal_mode 0)
		)
		(polygon
			(pts
				(arc
					(start 209.00009 -73.799954)
					(mid 209.707195 -73.507061)
					(end 210.000088 -72.799956)
				)
				(arc
					(start 210.000088 -0.999998)
					(mid 209.707195 -0.292893)
					(end 209.00009 0)
				)
				(xy 206.000096 0) (xy 206.000096 -73.799954)
			)
		)
	)
	(zone
		(net "P3V3")
		(layer "B.Cu")
		(hatch none 0.5)
		(connect_pads
			(clearance 0.5)
		)
		(min_thickness 0.25)
		(fill yes
			(thermal_gap 0.5)
			(thermal_bridge_width 0.5)
			(island_removal_mode 0)
		)
		(polygon
			(pts
				(xy 57.277 -31.496) (xy 57.15 -31.623) (xy 57.15 -34.0106) (xy 56.9976 -34.163) (xy 55.372 -34.163)
				(xy 52.9844 -36.5506) (xy 52.9844 -40.2336) (xy 53.467 -40.7162) (xy 53.467 -43.18) (xy 53.721 -43.434)
				(xy 56.769 -43.434) (xy 56.769 -42.799) (xy 54.61 -42.799) (xy 54.4322 -42.6212) (xy 54.4322 -36.9062)
				(xy 55.7022 -35.6362) (xy 57.2262 -35.6362) (xy 58.293 -34.5694) (xy 58.293 -32.258) (xy 57.531 -31.496)
			)
		)
	)
	(zone
		(net "GND")
		(layer "B.Cu")
		(hatch none 0.5)
		(connect_pads
			(clearance 0.5)
		)
		(min_thickness 0.25)
		(fill yes
			(thermal_gap 0.5)
			(thermal_bridge_width 0.5)
			(island_removal_mode 0)
		)
		(polygon
			(pts
				(xy 71.12 -14.732) (xy 70.993 -14.859) (xy 70.993 -16.3576) (xy 70.4596 -16.891) (xy 70.4596 -19.1262)
				(xy 70.5104 -19.177) (xy 71.2216 -19.177) (xy 71.247 -19.1516) (xy 71.247 -18.161) (xy 71.3486 -18.0594)
				(xy 72.2122 -18.0594) (xy 72.3646 -18.2118) (xy 72.3646 -19.9136) (xy 72.4154 -19.9644) (xy 73.3298 -19.9644)
				(xy 73.5584 -19.7358) (xy 74.5744 -19.7358) (xy 75.2602 -19.05) (xy 76.581 -19.05) (xy 76.708 -18.923)
				(xy 76.708 -15.875) (xy 76.454 -15.621) (xy 75.057 -15.621) (xy 74.676 -16.002) (xy 73.406 -16.002)
				(xy 72.136 -14.732)
			)
		)
		(polygon
			(pts
				(xy 73.0504 -19.3802) (xy 72.7964 -19.3802) (xy 72.7964 -19.6342) (xy 73.0504 -19.6342)
			)
		)
	)
	(zone
		(layer "B.Cu")
		(hatch none 0.5)
		(connect_pads
			(clearance 0)
		)
		(min_thickness 0.25)
		(keepout
			(tracks not_allowed)
			(vias allowed)
			(pads allowed)
			(copperpour not_allowed)
			(footprints allowed)
		)
		(placement
			(enabled no)
			(sheetname "")
		)
		(fill
			(thermal_gap 0.5)
			(thermal_bridge_width 0.5)
			(island_removal_mode 0)
		)
		(polygon
			(pts
				(arc
					(start 20.09521 -15.105126)
					(mid 19.71167 -15.488666)
					(end 20.09521 -15.872206)
				)
				(arc
					(start 21.052536 -15.872206)
					(mid 21.43633 -15.488793)
					(end 21.05279 -15.105126)
				)
				(xy 20.828 -15.105126) (xy 20.828 -15.147036)
				(arc
					(start 20.931886 -15.250922)
					(mid 21.24139 -15.677266)
					(end 20.815046 -15.367762)
				)
				(xy 20.71116 -15.263876) (xy 20.6629 -15.215616) (xy 20.6629 -15.147036) (xy 20.6629 -15.105126)
				(xy 20.4851 -15.105126) (xy 20.4851 -15.147036) (xy 20.4851 -15.215616) (xy 20.43684 -15.263876)
				(arc
					(start 20.332954 -15.367762)
					(mid 19.90661 -15.677266)
					(end 20.216114 -15.250922)
				)
				(xy 20.32 -15.147036) (xy 20.32 -15.105126)
			)
		)
	)
	(zone
		(net "GND")
		(layer "B.Cu")
		(hatch none 0.5)
		(connect_pads
			(clearance 0.5)
		)
		(min_thickness 0.25)
		(fill yes
			(thermal_gap 0.5)
			(thermal_bridge_width 0.5)
			(island_removal_mode 0)
		)
		(polygon
			(pts
				(xy 16.129 -60.579) (xy 16.002 -60.706) (xy 16.002 -67.691) (xy 15.748 -67.945) (xy 15.367 -67.945)
				(xy 15.24 -68.072) (xy 15.24 -68.453) (xy 15.367 -68.58) (xy 16.637 -68.58) (xy 17.526 -67.691)
				(xy 17.526 -63.754) (xy 16.51 -62.738) (xy 16.51 -60.706) (xy 16.383 -60.579)
			)
		)
		(polygon
			(pts
				(xy 16.6116 -67.3862) (xy 16.3576 -67.3862) (xy 16.3576 -67.6402) (xy 16.6116 -67.6402)
			)
		)
		(polygon
			(pts
				(xy 16.6116 -66.5988) (xy 16.3576 -66.5988) (xy 16.3576 -67.1322) (xy 16.6116 -67.1322)
			)
		)
		(polygon
			(pts
				(xy 16.6116 -66.0908) (xy 16.3576 -66.0908) (xy 16.3576 -66.3448) (xy 16.6116 -66.3448)
			)
		)
		(polygon
			(pts
				(xy 16.6116 -64.77) (xy 16.3576 -64.77) (xy 16.3576 -65.024) (xy 16.6116 -65.024)
			)
		)
		(polygon
			(pts
				(xy 16.6116 -64.008) (xy 16.3576 -64.008) (xy 16.3576 -64.516) (xy 16.6116 -64.516)
			)
		)
		(polygon
			(pts
				(xy 16.6116 -63.5) (xy 16.3576 -63.5) (xy 16.3576 -63.754) (xy 16.6116 -63.754)
			)
		)
	)
	(zone
		(net "P1V1")
		(layer "B.Cu")
		(hatch none 0.5)
		(connect_pads
			(clearance 0.5)
		)
		(min_thickness 0.25)
		(fill yes
			(thermal_gap 0.5)
			(thermal_bridge_width 0.5)
			(island_removal_mode 0)
		)
		(polygon
			(pts
				(xy 93.091 -58.166) (xy 92.2274 -59.0296) (xy 92.2274 -65.278) (xy 92.3798 -65.4304) (xy 93.5736 -65.4304)
				(xy 94.1832 -64.8208) (xy 94.8436 -64.8208) (xy 94.9198 -64.7446) (xy 94.9198 -62.5602) (xy 94.9452 -62.5348)
				(xy 95.885 -62.5348) (xy 95.9358 -62.484) (xy 95.9358 -59.6138) (xy 94.488 -58.166)
			)
		)
	)
	(zone
		(net "GND")
		(layer "B.Cu")
		(hatch none 0.5)
		(connect_pads
			(clearance 0.5)
		)
		(min_thickness 0.25)
		(fill yes
			(thermal_gap 0.5)
			(thermal_bridge_width 0.5)
			(island_removal_mode 0)
		)
		(polygon
			(pts
				(xy 97.282 -35.179) (xy 97.155 -35.306) (xy 97.155 -35.814) (xy 96.901 -36.068) (xy 93.98 -36.068)
				(xy 93.853 -36.195) (xy 93.853 -36.576) (xy 93.98 -36.703) (xy 94.615 -36.703) (xy 94.742 -36.83)
				(xy 94.742 -37.338) (xy 94.869 -37.465) (xy 95.25 -37.465) (xy 95.377 -37.338) (xy 95.377 -36.83)
				(xy 95.504 -36.703) (xy 99.06 -36.703) (xy 99.187 -36.576) (xy 99.187 -36.322) (xy 99.06 -36.195)
				(xy 98.806 -36.195) (xy 97.79 -35.179)
			)
		)
		(polygon
			(pts
				(xy 97.7646 -35.56) (xy 97.5106 -35.56) (xy 97.5106 -35.814) (xy 97.7646 -35.814)
			)
		)
	)
	(zone
		(layer "B.Cu")
		(hatch none 0.5)
		(connect_pads
			(clearance 0)
		)
		(min_thickness 0.25)
		(keepout
			(tracks allowed)
			(vias allowed)
			(pads allowed)
			(copperpour allowed)
			(footprints allowed)
		)
		(placement
			(enabled no)
			(sheetname "")
		)
		(fill
			(thermal_gap 0.5)
			(thermal_bridge_width 0.5)
			(island_removal_mode 0)
		)
		(polygon
			(pts
				(xy 195.326 -13.971778) (xy 187.452 -13.971778) (xy 187.452 -8.510778) (xy 195.326 -8.510778)
			)
		)
	)
	(zone
		(net "GND")
		(layer "B.Cu")
		(hatch none 0.5)
		(connect_pads
			(clearance 0.5)
		)
		(min_thickness 0.25)
		(fill yes
			(thermal_gap 0.5)
			(thermal_bridge_width 0.5)
			(island_removal_mode 0)
		)
		(polygon
			(pts
				(xy 187.325 -31.75) (xy 187.198 -31.877) (xy 187.198 -35.306) (xy 186.944 -35.56) (xy 185.674 -35.56)
				(xy 185.42 -35.306) (xy 184.531 -35.306) (xy 184.404 -35.433) (xy 184.404 -42.418) (xy 181.737 -45.085)
				(xy 181.737 -46.736) (xy 172.974 -55.499) (xy 155.956 -55.499) (xy 154.94 -56.515) (xy 144.399 -56.515)
				(xy 142.494 -58.42) (xy 137.287 -58.42) (xy 137.16 -58.547) (xy 137.16 -60.071) (xy 137.033 -60.198)
				(xy 136.652 -60.198) (xy 136.525 -60.325) (xy 136.525 -61.214) (xy 136.652 -61.341) (xy 144.653 -61.341)
				(xy 146.939 -59.055) (xy 151.892 -59.055) (xy 152.4 -59.563) (xy 153.035 -59.563) (xy 153.416 -59.182)
				(xy 154.559 -59.182) (xy 154.813 -59.436) (xy 158.75 -59.436) (xy 159.004 -59.182) (xy 163.957 -59.182)
				(xy 165.862 -61.087) (xy 181.356 -61.087) (xy 184.912 -57.531) (xy 185.166 -57.531) (xy 187.579 -59.944)
				(xy 188.468 -59.944) (xy 188.722 -60.198) (xy 189.992 -60.198) (xy 190.754 -60.96) (xy 190.754 -64.643)
				(xy 191.262 -65.151) (xy 197.104 -65.151) (xy 197.231 -65.024) (xy 197.231 -61.341) (xy 197.358 -61.214)
				(xy 197.358 -57.531) (xy 197.739 -57.15) (xy 198.12 -57.15) (xy 198.247 -57.023) (xy 198.247 -52.451)
				(xy 197.739 -51.943) (xy 197.104 -51.943) (xy 196.596 -51.435) (xy 196.596 -46.99) (xy 195.961 -46.355)
				(xy 194.437 -46.355) (xy 193.802 -45.72) (xy 193.802 -44.704) (xy 195.58 -42.926) (xy 195.58 -41.656)
				(xy 196.596 -40.64) (xy 198.247 -40.64) (xy 198.374 -40.513) (xy 198.374 -39.497) (xy 198.247 -39.37)
				(xy 196.215 -39.37) (xy 196.088 -39.497) (xy 195.326 -39.497) (xy 194.564 -40.259) (xy 192.405 -40.259)
				(xy 191.897 -39.751) (xy 191.897 -36.703) (xy 191.008 -35.814) (xy 191.008 -32.131) (xy 190.627 -31.75)
			)
		)
		(polygon
			(pts
				(xy 196.5325 -63.7032) (xy 196.2785 -63.7032) (xy 196.2785 -64.2112) (xy 196.5325 -64.2112)
			)
		)
		(polygon
			(pts
				(xy 196.5325 -62.4332) (xy 196.2785 -62.4332) (xy 196.2785 -62.9412) (xy 196.5325 -62.9412)
			)
		)
		(polygon
			(pts
				(xy 196.5325 -61.4172) (xy 196.2785 -61.4172) (xy 196.2785 -61.6712) (xy 196.5325 -61.6712)
			)
		)
		(polygon
			(pts
				(xy 137.16 -60.7822) (xy 136.906 -60.7822) (xy 136.906 -61.0362) (xy 137.16 -61.0362)
			)
		)
		(polygon
			(pts
				(xy 189.484 -59.5884) (xy 189.23 -59.5884) (xy 189.23 -59.8424) (xy 189.484 -59.8424)
			)
		)
		(polygon
			(pts
				(xy 188.595 -59.5503) (xy 188.341 -59.5503) (xy 188.341 -59.8043) (xy 188.595 -59.8043) (xy 188.722 -59.8424)
				(xy 188.976 -59.8424) (xy 188.976 -59.5884) (xy 188.722 -59.5884)
			)
		)
		(polygon
			(pts
				(xy 153.0604 -58.9534) (xy 152.8064 -58.9534) (xy 152.8064 -59.2074) (xy 153.0604 -59.2074)
			)
		)
		(polygon
			(pts
				(xy 152.5524 -58.9534) (xy 152.2984 -58.9534) (xy 152.2984 -59.2074) (xy 152.5524 -59.2074)
			)
		)
		(polygon
			(pts
				(xy 158.3182 -58.928) (xy 157.8102 -58.928) (xy 157.8102 -59.182) (xy 158.3182 -59.182)
			)
		)
		(polygon
			(pts
				(xy 157.5562 -58.928) (xy 157.0482 -58.928) (xy 157.0482 -59.182) (xy 157.5562 -59.182)
			)
		)
		(polygon
			(pts
				(xy 156.7942 -58.928) (xy 156.5402 -58.928) (xy 156.5402 -59.182) (xy 156.7942 -59.182)
			)
		)
		(polygon
			(pts
				(xy 156.1338 -58.8518) (xy 155.8798 -58.8518) (xy 155.8798 -59.1058) (xy 156.1338 -59.1058)
			)
		)
		(polygon
			(pts
				(xy 155.6258 -58.8518) (xy 155.1178 -58.8518) (xy 155.1178 -59.1058) (xy 155.6258 -59.1058)
			)
		)
		(polygon
			(pts
				(xy 188.595 -58.7629) (xy 188.341 -58.7629) (xy 188.341 -59.0169) (xy 188.595 -59.0169)
			)
		)
		(polygon
			(pts
				(xy 187.579 -58.7629) (xy 187.325 -58.7629) (xy 187.325 -59.0169) (xy 187.579 -59.0169)
			)
		)
		(polygon
			(pts
				(xy 160.147 -58.1279) (xy 159.893 -58.1279) (xy 159.893 -58.3819) (xy 160.147 -58.3819)
			)
		)
		(polygon
			(pts
				(xy 159.131 -58.1279) (xy 158.877 -58.1279) (xy 158.877 -58.3819) (xy 159.131 -58.3819)
			)
		)
		(polygon
			(pts
				(xy 154.559 -58.1279) (xy 154.305 -58.1279) (xy 154.305 -58.3819) (xy 154.559 -58.3819)
			)
		)
		(polygon
			(pts
				(xy 153.543 -58.1279) (xy 153.289 -58.1279) (xy 153.289 -58.3819) (xy 153.543 -58.3819)
			)
		)
		(polygon
			(pts
				(xy 152.019 -58.1279) (xy 151.765 -58.1279) (xy 151.765 -58.3819) (xy 152.019 -58.3819)
			)
		)
		(polygon
			(pts
				(xy 151.003 -58.1279) (xy 150.749 -58.1279) (xy 150.749 -58.3819) (xy 151.003 -58.3819)
			)
		)
		(polygon
			(pts
				(xy 187.7568 -34.9504) (xy 187.5028 -34.9504) (xy 187.5028 -35.2044) (xy 187.7568 -35.2044)
			)
		)
		(polygon
			(pts
				(xy 187.8584 -34.1884) (xy 187.6044 -34.1884) (xy 187.6044 -34.4424) (xy 187.5028 -34.4424) (xy 187.5028 -34.6964)
				(xy 187.7568 -34.6964) (xy 187.7568 -34.4424) (xy 187.8584 -34.4424)
			)
		)
		(polygon
			(pts
				(xy 187.7822 -33.3756) (xy 187.5282 -33.3756) (xy 187.5282 -33.6296) (xy 187.6044 -33.6804) (xy 187.6044 -33.9344)
				(xy 187.8584 -33.9344) (xy 187.8584 -33.6804) (xy 187.7822 -33.6296)
			)
		)
		(polygon
			(pts
				(xy 187.7822 -32.8676) (xy 187.5282 -32.8676) (xy 187.5282 -33.1216) (xy 187.7822 -33.1216)
			)
		)
		(polygon
			(pts
				(xy 187.9092 -32.3088) (xy 187.6552 -32.3088) (xy 187.6552 -32.5628) (xy 187.9092 -32.5628)
			)
		)
		(polygon
			(pts
				(xy 190.754 -32.2072) (xy 190.5 -32.2072) (xy 190.5 -32.4612) (xy 190.754 -32.4612)
			)
		)
		(polygon
			(pts
				(xy 190.246 -32.2072) (xy 189.992 -32.2072) (xy 189.992 -32.4612) (xy 190.246 -32.4612)
			)
		)
	)
	(zone
		(net "GND")
		(layer "B.Cu")
		(hatch none 0.5)
		(connect_pads
			(clearance 0.5)
		)
		(min_thickness 0.25)
		(fill yes
			(thermal_gap 0.5)
			(thermal_bridge_width 0.5)
			(island_removal_mode 0)
		)
		(polygon
			(pts
				(xy 84.328 -13.589) (xy 83.566 -14.351) (xy 81.788 -14.351) (xy 81.661 -14.478) (xy 81.661 -14.859)
				(xy 81.407 -15.113) (xy 81.407 -16.129) (xy 81.534 -16.256) (xy 82.931 -16.256) (xy 83.058 -16.129)
				(xy 83.058 -15.113) (xy 83.185 -14.986) (xy 83.82 -14.986) (xy 84.455 -14.351) (xy 85.09 -14.351)
				(xy 85.471 -14.732) (xy 89.027 -14.732) (xy 89.662 -15.367) (xy 89.662 -16.129) (xy 89.789 -16.256)
				(xy 90.678 -16.256) (xy 91.44 -15.494) (xy 96.266 -15.494) (xy 98.933 -18.161) (xy 98.933 -18.669)
				(xy 98.679 -18.923) (xy 98.298 -18.923) (xy 97.536 -18.161) (xy 96.266 -18.161) (xy 96.139 -18.288)
				(xy 96.139 -19.812) (xy 96.23425 -19.90725) (xy 96.67875 -19.90725) (xy 96.901 -19.685) (xy 98.806 -19.685)
				(xy 99.06 -19.431) (xy 101.346 -19.431) (xy 101.727 -19.05) (xy 108.966 -19.05) (xy 109.474 -19.558)
				(xy 109.474 -26.162) (xy 109.982 -26.67) (xy 109.982 -27.305) (xy 110.236 -27.559) (xy 112.141 -27.559)
				(xy 112.522 -27.94) (xy 112.522 -29.591) (xy 113.157 -30.226) (xy 113.157 -31.623) (xy 112.395 -32.385)
				(xy 110.744 -32.385) (xy 110.109 -31.75) (xy 105.791 -31.75) (xy 105.156 -32.385) (xy 105.156 -33.02)
				(xy 104.902 -33.274) (xy 103.505 -33.274) (xy 103.251 -33.02) (xy 102.235 -33.02) (xy 102.108 -33.147)
				(xy 102.108 -33.401) (xy 102.235 -33.528) (xy 103.124 -33.528) (xy 103.378 -33.782) (xy 103.378 -35.814)
				(xy 102.997 -36.195) (xy 101.346 -36.195) (xy 101.219 -36.322) (xy 101.219 -36.576) (xy 101.346 -36.703)
				(xy 102.108 -36.703) (xy 102.362 -36.957) (xy 102.616 -36.957) (xy 102.87 -37.211) (xy 102.87 -37.465)
				(xy 102.997 -37.592) (xy 104.013 -37.592) (xy 104.14 -37.465) (xy 104.14 -36.957) (xy 104.648 -36.449)
				(xy 106.553 -36.449) (xy 107.569 -37.465) (xy 111.125 -37.465) (xy 111.252 -37.338) (xy 111.252 -36.068)
				(xy 111.506 -35.814) (xy 112.395 -35.814) (xy 113.284 -34.925) (xy 117.348 -34.925) (xy 117.602 -35.179)
				(xy 117.602 -50.165) (xy 116.967 -50.8) (xy 114.3 -50.8) (xy 113.8428 -50.3428) (xy 113.8428 -47.244)
				(xy 114.3 -46.7868) (xy 114.3 -45.847) (xy 114.173 -45.72) (xy 110.998 -45.72) (xy 110.744 -45.466)
				(xy 110.744 -44.339002) (xy 109.846872 -43.442128) (xy 109.855 -43.434) (xy 109.855 -42.926) (xy 109.601 -42.672)
				(xy 109.601 -41.672002) (xy 109.474 -41.545002) (xy 108.966 -41.545002) (xy 108.458 -41.037002)
				(xy 107.696 -41.037002) (xy 107.188 -41.545002) (xy 106.68 -41.545002) (xy 106.299 -41.164002) (xy 104.14 -41.164002)
				(xy 104.013 -41.037002) (xy 102.997 -41.037002) (xy 102.362 -41.672002) (xy 101.346 -41.672002)
				(xy 101.219 -41.799002) (xy 101.219 -42.180002) (xy 100.965 -42.434002) (xy 96.52 -42.434002) (xy 96.393 -42.561002)
				(xy 96.393 -42.942002) (xy 96.52 -43.069002) (xy 101.092 -43.069002) (xy 101.100128 -43.061128)
				(xy 101.337872 -43.061128) (xy 101.837998 -42.561002) (xy 102.362 -42.561002) (xy 102.489 -42.688002)
				(xy 102.489 -43.196002) (xy 102.616 -43.323002) (xy 103.124 -43.323002) (xy 103.378 -43.577002)
				(xy 103.378 -45.339) (xy 103.632 -45.593) (xy 103.759 -45.593) (xy 104.14 -45.212) (xy 104.14 -44.196)
				(xy 104.394 -43.942) (xy 105.774998 -43.942) (xy 106.172 -44.339002) (xy 106.172 -44.847002) (xy 105.918 -45.101002)
				(xy 105.918 -45.482002) (xy 106.68 -46.244002) (xy 107.188 -46.244002) (xy 107.196128 -46.236128)
				(xy 109.365796 -46.236128) (xy 110.373668 -47.244) (xy 110.373668 -47.250096) (xy 110.746286 -47.622714)
				(xy 110.746286 -49.784) (xy 110.744 -49.786286) (xy 110.744 -50.546) (xy 110.871 -50.673) (xy 110.871 -51.308)
				(xy 110.744 -51.435) (xy 110.744 -52.823364) (xy 110.246668 -53.320696) (xy 108.930694 -53.320696)
				(xy 108.458 -52.848002) (xy 106.299 -52.848002) (xy 105.791 -52.340002) (xy 105.664 -52.340002)
				(xy 105.647998 -52.324) (xy 105.283 -52.324) (xy 104.902 -52.705) (xy 104.902 -53.34) (xy 105.029 -53.467)
				(xy 105.41 -53.467) (xy 108.712 -56.769) (xy 111.76 -56.769) (xy 124.46 -44.069) (xy 124.46 -38.862)
				(xy 121.793 -36.195) (xy 121.793 -32.258) (xy 113.284 -23.749) (xy 113.284 -18.034) (xy 112.395 -17.145)
				(xy 107.442 -17.145) (xy 106.68 -17.907) (xy 102.87 -17.907) (xy 102.743 -17.78) (xy 102.743 -16.256)
				(xy 102.616 -16.129) (xy 99.822 -16.129) (xy 98.044 -14.351) (xy 91.186 -14.351) (xy 90.424 -13.589)
			)
		)
		(polygon
			(pts
				(xy 107.823 -53.203602) (xy 107.569 -53.203602) (xy 107.569 -53.457602) (xy 107.823 -53.457602)
			)
		)
		(polygon
			(pts
				(xy 105.5116 -52.959) (xy 105.2576 -52.959) (xy 105.2576 -53.213) (xy 105.5116 -53.213)
			)
		)
		(polygon
			(pts
				(xy 111.4806 -50.943002) (xy 111.2266 -50.943002) (xy 111.2266 -51.197002) (xy 111.4806 -51.197002)
			)
		)
		(polygon
			(pts
				(xy 111.3536 -48.006) (xy 111.0996 -48.006) (xy 111.0996 -48.26) (xy 111.3536 -48.26)
			)
		)
		(polygon
			(pts
				(xy 111.3536 -47.498) (xy 111.0996 -47.498) (xy 111.0996 -47.752) (xy 111.3536 -47.752)
			)
		)
		(polygon
			(pts
				(xy 102.454964 -42.0116) (xy 102.200964 -42.0116) (xy 102.200964 -42.2656) (xy 102.454964 -42.2656)
			)
		)
		(polygon
			(pts
				(xy 101.946964 -42.0116) (xy 101.692964 -42.0116) (xy 101.692964 -42.2656) (xy 101.946964 -42.2656)
			)
		)
		(polygon
			(pts
				(xy 110.8456 -36.8554) (xy 110.5916 -36.8554) (xy 110.5916 -37.1094) (xy 110.8456 -37.1094)
			)
		)
		(polygon
			(pts
				(xy 110.3376 -36.8554) (xy 110.0836 -36.8554) (xy 110.0836 -37.1094) (xy 110.3376 -37.1094)
			)
		)
		(polygon
			(pts
				(xy 103.990648 -35.747452) (xy 103.736648 -35.747452) (xy 103.736648 -36.001452) (xy 103.990648 -36.001452)
			)
		)
		(polygon
			(pts
				(xy 112.395 -35.2044) (xy 112.141 -35.2044) (xy 112.141 -35.4584) (xy 112.395 -35.4584)
			)
		)
		(polygon
			(pts
				(xy 111.887 -35.2044) (xy 111.633 -35.2044) (xy 111.633 -35.4584) (xy 111.887 -35.4584)
			)
		)
		(polygon
			(pts
				(xy 103.9876 -34.941002) (xy 103.7336 -34.941002) (xy 103.7336 -35.195002) (xy 103.736648 -35.239452)
				(xy 103.736648 -35.493452) (xy 103.990648 -35.493452) (xy 103.990648 -35.239452) (xy 103.9876 -35.195002)
			)
		)
		(polygon
			(pts
				(xy 103.9876 -34.179002) (xy 103.7336 -34.179002) (xy 103.7336 -34.687002) (xy 103.9876 -34.687002)
			)
		)
		(polygon
			(pts
				(xy 104.902 -33.8836) (xy 104.648 -33.8836) (xy 104.648 -34.1376) (xy 104.902 -34.1376)
			)
		)
		(polygon
			(pts
				(xy 104.394 -33.8836) (xy 104.14 -33.8836) (xy 104.14 -34.1376) (xy 104.394 -34.1376)
			)
		)
		(polygon
			(pts
				(xy 103.9876 -33.671002) (xy 103.7336 -33.671002) (xy 103.7336 -33.925002) (xy 103.9876 -33.925002)
			)
		)
		(polygon
			(pts
				(xy 113.2332 -32.401002) (xy 112.9792 -32.401002) (xy 112.9792 -32.655002) (xy 113.2332 -32.655002)
			)
		)
		(polygon
			(pts
				(xy 117.221 -29.718) (xy 114.681 -29.718) (xy 114.427 -29.972) (xy 114.427 -34.036) (xy 114.681 -34.29)
				(xy 117.221 -34.29) (xy 117.475 -34.036) (xy 117.475 -29.972)
			)
		)
		(polygon
			(pts
				(xy 113.1316 -29.226002) (xy 112.8776 -29.226002) (xy 112.8776 -29.480002) (xy 113.1316 -29.480002)
			)
		)
		(polygon
			(pts
				(xy 113.1316 -28.464002) (xy 112.8776 -28.464002) (xy 112.8776 -28.972002) (xy 113.1316 -28.972002)
			)
		)
		(polygon
			(pts
				(xy 113.1316 -27.956002) (xy 112.8776 -27.956002) (xy 112.8776 -28.210002) (xy 113.1316 -28.210002)
			)
		)
		(polygon
			(pts
				(xy 111.125 -26.965402) (xy 110.871 -26.965402) (xy 110.871 -27.219402) (xy 111.125 -27.219402)
			)
		)
		(polygon
			(pts
				(xy 110.617 -26.965402) (xy 110.363 -26.965402) (xy 110.363 -27.219402) (xy 110.617 -27.219402)
			)
		)
		(polygon
			(pts
				(xy 96.7486 -19.304) (xy 96.4946 -19.304) (xy 96.4946 -19.558) (xy 96.7486 -19.558)
			)
		)
		(polygon
			(pts
				(xy 97.282 -18.977102) (xy 97.028 -18.977102) (xy 97.028 -19.231102) (xy 97.282 -19.231102)
			)
		)
		(polygon
			(pts
				(xy 100.838 -18.6944) (xy 100.584 -18.6944) (xy 100.584 -18.9484) (xy 100.838 -18.9484)
			)
		)
		(polygon
			(pts
				(xy 100.33 -18.6944) (xy 99.695 -18.6944) (xy 99.695 -18.9484) (xy 100.33 -18.9484)
			)
		)
		(polygon
			(pts
				(xy 103.632 -18.2626) (xy 103.378 -18.2626) (xy 103.378 -18.5166) (xy 103.632 -18.5166)
			)
		)
		(polygon
			(pts
				(xy 103.124 -18.2626) (xy 102.87 -18.2626) (xy 102.87 -18.5166) (xy 103.124 -18.5166)
			)
		)
		(polygon
			(pts
				(xy 90.297 -15.6464) (xy 90.043 -15.6464) (xy 90.043 -15.9004) (xy 90.297 -15.9004)
			)
		)
		(polygon
			(pts
				(xy 85.217 -13.7414) (xy 84.963 -13.7414) (xy 84.963 -13.9954) (xy 85.217 -13.9954)
			)
		)
		(polygon
			(pts
				(xy 84.709 -13.7414) (xy 84.455 -13.7414) (xy 84.455 -13.9954) (xy 84.709 -13.9954)
			)
		)
	)
	(zone
		(net "GND")
		(layer "B.Cu")
		(hatch none 0.5)
		(connect_pads
			(clearance 0.5)
		)
		(min_thickness 0.25)
		(fill yes
			(thermal_gap 0.5)
			(thermal_bridge_width 0.5)
			(island_removal_mode 0)
		)
		(polygon
			(pts
				(xy 93.853 -25.146) (xy 93.726 -25.273) (xy 93.726 -27.305) (xy 92.71 -28.321) (xy 92.71 -30.4038)
				(xy 92.329 -30.7848) (xy 92.329 -32.385) (xy 92.075 -32.639) (xy 91.948 -32.639) (xy 91.694 -32.893)
				(xy 91.694 -33.147) (xy 91.44 -33.401) (xy 91.059 -33.401) (xy 90.805 -33.147) (xy 90.424 -33.147)
				(xy 90.297 -33.274) (xy 90.297 -34.417) (xy 90.424 -34.544) (xy 90.678 -34.544) (xy 90.805 -34.671)
				(xy 90.805 -35.052) (xy 90.551 -35.306) (xy 89.408 -35.306) (xy 89.154 -35.052) (xy 89.027 -35.052)
				(xy 88.9 -35.179) (xy 88.9 -35.56) (xy 89.281 -35.941) (xy 89.916 -35.941) (xy 90.043 -36.068) (xy 90.043 -36.576)
				(xy 90.17 -36.703) (xy 90.424 -36.703) (xy 90.551 -36.576) (xy 90.551 -36.068) (xy 90.678 -35.941)
				(xy 91.948 -35.941) (xy 92.075 -35.814) (xy 92.075 -35.56) (xy 91.567 -35.052) (xy 91.567 -33.655)
				(xy 92.329 -32.893) (xy 93.091 -32.893) (xy 93.853 -33.655) (xy 96.139 -33.655) (xy 96.393 -33.909)
				(xy 96.393 -34.163) (xy 96.52 -34.29) (xy 96.774 -34.29) (xy 96.901 -34.163) (xy 96.901 -33.909)
				(xy 96.012 -33.02) (xy 94.4372 -33.02) (xy 94.234 -32.8168) (xy 94.234 -32.4358) (xy 94.0562 -32.258)
				(xy 93.853 -32.258) (xy 93.599 -32.004) (xy 93.599 -31.75) (xy 93.345 -31.496) (xy 93.091 -31.496)
				(xy 92.964 -31.369) (xy 92.964 -30.861) (xy 93.345 -30.48) (xy 93.345 -28.575) (xy 94.742 -27.178)
				(xy 94.742 -25.273) (xy 94.615 -25.146)
			)
		)
		(polygon
			(pts
				(xy 91.1987 -34.3408) (xy 90.9447 -34.3408) (xy 90.9447 -34.5948) (xy 91.1987 -34.5948)
			)
		)
		(polygon
			(pts
				(xy 90.9447 -33.5788) (xy 90.6907 -33.5788) (xy 90.6907 -34.0868) (xy 91.1987 -34.0868) (xy 91.1987 -33.8328)
			)
		)
		(polygon
			(pts
				(xy 93.8022 -32.6644) (xy 93.5482 -32.6644) (xy 93.5482 -32.9184) (xy 93.8022 -32.9184)
			)
		)
		(polygon
			(pts
				(xy 92.964 -32.2834) (xy 92.71 -32.2834) (xy 92.71 -32.5374) (xy 92.964 -32.5374)
			)
		)
		(polygon
			(pts
				(xy 94.3356 -27.051) (xy 94.0816 -27.051) (xy 94.0816 -27.305) (xy 94.3356 -27.305)
			)
		)
		(polygon
			(pts
				(xy 94.3356 -26.289) (xy 94.0816 -26.289) (xy 94.0816 -26.797) (xy 94.3356 -26.797)
			)
		)
		(polygon
			(pts
				(xy 94.3356 -25.527) (xy 94.0816 -25.527) (xy 94.0816 -26.035) (xy 94.3356 -26.035)
			)
		)
	)
	(zone
		(net "GND")
		(layer "B.Cu")
		(hatch none 0.5)
		(connect_pads
			(clearance 0.5)
		)
		(min_thickness 0.25)
		(fill yes
			(thermal_gap 0.5)
			(thermal_bridge_width 0.5)
			(island_removal_mode 0)
		)
		(polygon
			(pts
				(xy 92.075 -45.339) (xy 91.948 -45.466) (xy 91.948 -45.593) (xy 91.313 -46.228) (xy 89.662 -46.228)
				(xy 89.535 -46.355) (xy 88.9 -46.355) (xy 88.773 -46.482) (xy 88.773 -47.244) (xy 88.646 -47.371)
				(xy 88.646 -48.006) (xy 89.154 -48.514) (xy 90.17 -48.514) (xy 90.424 -48.768) (xy 90.805 -48.768)
				(xy 91.059 -48.514) (xy 91.059 -48.133) (xy 91.313 -47.879) (xy 91.948 -47.879) (xy 92.075 -47.752)
				(xy 92.075 -47.371) (xy 92.583 -46.863) (xy 92.583 -45.466) (xy 92.456 -45.339)
			)
		)
		(polygon
			(pts
				(xy 91.567 -46.5836) (xy 91.313 -46.5836) (xy 91.313 -46.8376) (xy 91.567 -46.8376)
			)
		)
		(polygon
			(pts
				(xy 92.2274 -46.5328) (xy 91.9734 -46.5328) (xy 91.9734 -46.7868) (xy 92.2274 -46.7868)
			)
		)
		(polygon
			(pts
				(xy 92.2274 -45.7708) (xy 91.9734 -45.7708) (xy 91.9734 -46.2788) (xy 92.2274 -46.2788)
			)
		)
	)
	(zone
		(layer "B.Cu")
		(hatch none 0.5)
		(connect_pads
			(clearance 0)
		)
		(min_thickness 0.25)
		(keepout
			(tracks not_allowed)
			(vias allowed)
			(pads allowed)
			(copperpour not_allowed)
			(footprints allowed)
		)
		(placement
			(enabled no)
			(sheetname "")
		)
		(fill
			(thermal_gap 0.5)
			(thermal_bridge_width 0.5)
			(island_removal_mode 0)
		)
		(polygon
			(pts
				(arc
					(start 49.389284 -9.87679)
					(mid 49.00549 -10.260203)
					(end 49.38903 -10.64387)
				)
				(arc
					(start 50.310542 -10.64387)
					(mid 50.694082 -10.26033)
					(end 50.310542 -9.87679)
				)
				(xy 50.103786 -9.87679) (xy 50.103786 -9.936734)
				(arc
					(start 50.189638 -10.022586)
					(mid 50.499142 -10.44893)
					(end 50.072798 -10.139426)
				)
				(xy 49.986946 -10.053574) (xy 49.938686 -10.005314) (xy 49.938686 -9.936734) (xy 49.938686 -9.87679)
				(xy 49.760886 -9.87679) (xy 49.760886 -9.936734) (xy 49.760886 -10.005314) (xy 49.712626 -10.053574)
				(arc
					(start 49.626774 -10.139426)
					(mid 49.20043 -10.44893)
					(end 49.509934 -10.022586)
				)
				(xy 49.595786 -9.936734) (xy 49.595786 -9.87679)
			)
		)
	)
	(zone
		(net "P1V0_STBY")
		(layer "B.Cu")
		(hatch none 0.5)
		(connect_pads
			(clearance 0.5)
		)
		(min_thickness 0.25)
		(fill yes
			(thermal_gap 0.5)
			(thermal_bridge_width 0.5)
			(island_removal_mode 0)
		)
		(polygon
			(pts
				(xy 92.329 -33.147) (xy 91.694 -33.782) (xy 91.694 -34.798) (xy 92.329 -35.433) (xy 92.329 -36.068)
				(xy 92.202 -36.195) (xy 90.932 -36.195) (xy 90.805 -36.322) (xy 90.805 -36.576) (xy 90.932 -36.703)
				(xy 93.599 -36.703) (xy 93.726 -36.576) (xy 93.726 -35.941) (xy 93.853 -35.814) (xy 94.361 -35.814)
				(xy 94.488 -35.687) (xy 94.488 -34.036) (xy 94.361 -33.909) (xy 93.726 -33.909) (xy 92.964 -33.147)
			)
		)
		(polygon
			(pts
				(xy 94.041468 -35.185096) (xy 93.787468 -35.185096) (xy 93.787468 -35.439096) (xy 94.041468 -35.439096)
			)
		)
		(polygon
			(pts
				(xy 92.964 -33.5026) (xy 92.71 -33.5026) (xy 92.71 -33.7566) (xy 92.964 -33.7566)
			)
		)
		(polygon
			(pts
				(xy 92.456 -33.5026) (xy 92.202 -33.5026) (xy 92.202 -33.7566) (xy 92.1639 -33.8328) (xy 92.1639 -34.0868)
				(xy 92.4179 -34.0868) (xy 92.4179 -33.8328) (xy 92.456 -33.7566)
			)
		)
	)
	(zone
		(layer "B.Cu")
		(hatch none 0.5)
		(connect_pads
			(clearance 0)
		)
		(min_thickness 0.25)
		(keepout
			(tracks allowed)
			(vias allowed)
			(pads allowed)
			(copperpour allowed)
			(footprints not_allowed)
		)
		(placement
			(enabled no)
			(sheetname "")
		)
		(fill
			(thermal_gap 0.5)
			(thermal_bridge_width 0.5)
			(island_removal_mode 0)
		)
		(polygon
			(pts
				(xy 9.400032 -16.780002) (xy 9.400032 -26.604976) (xy 6.999986 -26.604976) (xy 6.999986 -16.780002)
			)
		)
	)
	(zone
		(layer "B.Cu")
		(hatch none 0.5)
		(connect_pads
			(clearance 0)
		)
		(min_thickness 0.25)
		(keepout
			(tracks allowed)
			(vias allowed)
			(pads allowed)
			(copperpour allowed)
			(footprints allowed)
		)
		(placement
			(enabled no)
			(sheetname "")
		)
		(fill
			(thermal_gap 0.5)
			(thermal_bridge_width 0.5)
			(island_removal_mode 0)
		)
		(polygon
			(pts
				(xy 70.6628 -18.1102) (xy 70.6628 -16.5354) (xy 72.4408 -16.5354) (xy 72.4408 -18.1102)
			)
		)
	)
	(zone
		(net "GND")
		(layer "B.Cu")
		(hatch none 0.5)
		(connect_pads
			(clearance 0.5)
		)
		(min_thickness 0.25)
		(fill yes
			(thermal_gap 0.5)
			(thermal_bridge_width 0.5)
			(island_removal_mode 0)
		)
		(polygon
			(pts
				(xy 1.143 -18.923) (xy 0.762 -19.304) (xy 0.762 -72.771) (xy 1.016 -73.025) (xy 8.382 -73.025) (xy 8.509 -72.898)
				(xy 8.509 -71.12) (xy 8.001 -70.612) (xy 8.001 -68.58) (xy 7.747 -68.326) (xy 5.08 -68.326) (xy 4.699 -68.707)
				(xy 3.048 -68.707) (xy 2.032 -67.691) (xy 1.651 -67.691) (xy 1.397 -67.437) (xy 1.397 -59.944) (xy 1.651 -59.69)
				(xy 2.54 -59.69) (xy 2.794 -59.436) (xy 2.794 -54.864) (xy 1.651 -53.721) (xy 1.651 -47.625) (xy 3.556 -45.72)
				(xy 3.556 -43.307) (xy 5.461 -41.402) (xy 5.461 -36.068) (xy 6.096 -35.433) (xy 6.096 -34.798) (xy 5.969 -34.671)
				(xy 5.715 -34.671) (xy 5.08 -34.036) (xy 5.08 -32.258) (xy 6.477 -30.861) (xy 8.636 -30.861) (xy 9.017 -30.48)
				(xy 11.938 -30.48) (xy 12.7 -29.718) (xy 17.018 -29.718) (xy 21.0185 -33.7185) (xy 22.1615 -33.7185)
				(xy 24.13 -35.687) (xy 26.797 -35.687) (xy 27.178 -35.306) (xy 28.829 -35.306) (xy 29.21 -35.687)
				(xy 30.734 -35.687) (xy 30.988 -35.433) (xy 30.988 -35.179) (xy 30.861 -35.052) (xy 30.353 -35.052)
				(xy 28.7782 -33.4772) (xy 28.7782 -32.9692) (xy 28.448 -32.639) (xy 25.527 -32.639) (xy 24.892 -32.004)
				(xy 24.892 -27.432) (xy 27.051 -25.273) (xy 27.051 -23.241) (xy 26.67 -22.86) (xy 24.511 -22.86)
				(xy 23.749 -23.622) (xy 23.749 -28.067) (xy 22.352 -29.464) (xy 20.193 -29.464) (xy 15.748 -25.019)
				(xy 15.748 -23.876) (xy 15.621 -23.749) (xy 13.208 -23.749) (xy 11.8364 -25.1206) (xy 11.8364 -25.7556)
				(xy 11.811 -25.781) (xy 11.811 -28.321) (xy 10.668 -29.464) (xy 5.588 -29.464) (xy 5.207 -29.083)
				(xy 5.207 -25.781) (xy 5.588 -25.4) (xy 8.255 -25.4) (xy 8.382 -25.273) (xy 8.382 -24.892) (xy 8.255 -24.765)
				(xy 7.366 -24.765) (xy 6.604 -24.003) (xy 6.604 -20.193) (xy 6.731 -20.066) (xy 6.731 -19.177) (xy 6.477 -18.923)
			)
		)
		(polygon
			(pts
				(xy 5.7404 -35.306) (xy 5.4864 -35.306) (xy 5.4864 -35.56) (xy 5.7404 -35.56)
			)
		)
		(polygon
			(pts
				(xy 28.321 -33.3121) (xy 28.067 -33.3121) (xy 28.067 -33.5661) (xy 28.321 -33.5661)
			)
		)
		(polygon
			(pts
				(xy 27.305 -33.3121) (xy 26.67 -33.3121) (xy 26.67 -33.5661) (xy 27.305 -33.5661)
			)
		)
		(polygon
			(pts
				(xy 25.908 -33.3121) (xy 25.654 -33.3121) (xy 25.654 -33.5661) (xy 25.908 -33.5661)
			)
		)
		(polygon
			(pts
				(xy 15.2908 -24.13) (xy 15.0368 -24.13) (xy 15.0368 -24.384) (xy 15.2908 -24.384)
			)
		)
	)
	(zone
		(layer "B.Cu")
		(hatch none 0.5)
		(connect_pads
			(clearance 0)
		)
		(min_thickness 0.25)
		(keepout
			(tracks allowed)
			(vias allowed)
			(pads allowed)
			(copperpour allowed)
			(footprints allowed)
		)
		(placement
			(enabled no)
			(sheetname "")
		)
		(fill
			(thermal_gap 0.5)
			(thermal_bridge_width 0.5)
			(island_removal_mode 0)
		)
		(polygon
			(pts
				(xy 62.6872 -33.0962) (xy 62.6872 -26.2636) (xy 65.8114 -26.2636) (xy 65.8114 -33.0962)
			)
		)
	)
	(zone
		(layer "B.Cu")
		(hatch none 0.5)
		(connect_pads
			(clearance 0)
		)
		(min_thickness 0.25)
		(keepout
			(tracks allowed)
			(vias allowed)
			(pads allowed)
			(copperpour allowed)
			(footprints allowed)
		)
		(placement
			(enabled no)
			(sheetname "")
		)
		(fill
			(thermal_gap 0.5)
			(thermal_bridge_width 0.5)
			(island_removal_mode 0)
		)
		(polygon
			(pts
				(xy 39.116 -20.574) (xy 39.116 -17.018) (xy 52.324 -17.018) (xy 52.324 -20.574)
			)
		)
	)
	(zone
		(net "P1V0")
		(layer "B.Cu")
		(hatch none 0.5)
		(connect_pads
			(clearance 0.5)
		)
		(min_thickness 0.25)
		(fill yes
			(thermal_gap 0.5)
			(thermal_bridge_width 0.5)
			(island_removal_mode 0)
		)
		(polygon
			(pts
				(xy 100.313998 -33.036002) (xy 100.203 -33.147) (xy 100.203 -33.655) (xy 100.059998 -33.798002)
				(xy 99.695 -33.798002) (xy 99.568 -33.925002) (xy 99.568 -34.941002) (xy 100.33 -35.703002) (xy 100.33 -36.592002)
				(xy 100.457 -36.719002) (xy 100.838 -36.719002) (xy 100.965 -36.592002) (xy 100.965 -36.211002)
				(xy 101.219 -35.957002) (xy 102.997 -35.957002) (xy 103.124 -35.830002) (xy 103.124 -33.798002)
				(xy 102.997 -33.671002) (xy 101.981 -33.671002) (xy 101.854 -33.544002) (xy 101.854 -33.163002)
				(xy 101.727 -33.036002) (xy 101.583998 -33.036002) (xy 101.219 -33.401) (xy 100.838 -33.401) (xy 100.473002 -33.036002)
			)
		)
		(polygon
			(pts
				(xy 102.7684 -34.941002) (xy 102.5144 -34.941002) (xy 102.5144 -35.195002) (xy 102.517448 -35.239452)
				(xy 102.517448 -35.493452) (xy 102.771448 -35.493452) (xy 102.771448 -35.239452) (xy 102.7684 -35.195002)
			)
		)
		(polygon
			(pts
				(xy 102.7684 -34.179002) (xy 102.5144 -34.179002) (xy 102.5144 -34.687002) (xy 102.7684 -34.687002)
			)
		)
	)
	(zone
		(net "P1V8_STBY")
		(layer "B.Cu")
		(hatch none 0.5)
		(connect_pads
			(clearance 0.5)
		)
		(min_thickness 0.25)
		(fill yes
			(thermal_gap 0.5)
			(thermal_bridge_width 0.5)
			(island_removal_mode 0)
		)
		(polygon
			(pts
				(xy 65.405 -15.875) (xy 65.278 -16.002) (xy 65.278 -17.145) (xy 65.405 -17.272) (xy 66.929 -17.272)
				(xy 67.056 -17.145) (xy 67.056 -16.002) (xy 66.929 -15.875)
			)
		)
	)
	(zone
		(layer "B.Cu")
		(hatch none 0.5)
		(connect_pads
			(clearance 0)
		)
		(min_thickness 0.25)
		(keepout
			(tracks allowed)
			(vias allowed)
			(pads allowed)
			(copperpour allowed)
			(footprints allowed)
		)
		(placement
			(enabled no)
			(sheetname "")
		)
		(fill
			(thermal_gap 0.5)
			(thermal_bridge_width 0.5)
			(island_removal_mode 0)
		)
		(polygon
			(pts
				(xy 93.472 -61.468) (xy 100.076 -61.468) (xy 100.076 -69.977) (xy 93.472 -69.977)
			)
		)
	)
	(zone
		(layer "B.Cu")
		(hatch none 0.5)
		(connect_pads
			(clearance 0)
		)
		(min_thickness 0.25)
		(keepout
			(tracks not_allowed)
			(vias allowed)
			(pads allowed)
			(copperpour not_allowed)
			(footprints allowed)
		)
		(placement
			(enabled no)
			(sheetname "")
		)
		(fill
			(thermal_gap 0.5)
			(thermal_bridge_width 0.5)
			(island_removal_mode 0)
		)
		(polygon
			(pts
				(arc
					(start 61.317378 -45.848016)
					(mid 60.910088 -45.489868)
					(end 60.551822 -45.897038)
				)
				(xy 60.562998 -46.06925) (xy 60.62091 -46.06925)
				(arc
					(start 60.696856 -45.993304)
					(mid 61.1232 -45.6838)
					(end 60.813696 -46.110144)
				)
				(xy 60.73775 -46.18609) (xy 60.68949 -46.23435) (xy 60.62091 -46.23435) (xy 60.573666 -46.23435)
				(xy 60.585096 -46.41215) (xy 60.716414 -46.41215) (xy 60.784994 -46.41215) (xy 60.833254 -46.46041)
				(arc
					(start 60.869322 -46.496478)
					(mid 61.178826 -46.922822)
					(end 60.752482 -46.613318)
				)
				(xy 60.716414 -46.57725) (xy 60.595764 -46.57725)
				(arc
					(start 60.607448 -46.75886)
					(mid 61.014864 -47.117)
					(end 61.373004 -46.709584)
				)
				(xy 61.357002 -46.46041) (xy 61.3537 -46.41215) (xy 61.339222 -46.18609)
			)
		)
	)
	(zone
		(net "P1V1")
		(layer "B.Cu")
		(hatch none 0.5)
		(connect_pads
			(clearance 0.5)
		)
		(min_thickness 0.25)
		(fill yes
			(thermal_gap 0.5)
			(thermal_bridge_width 0.5)
			(island_removal_mode 0)
		)
		(polygon
			(pts
				(xy 96.52 -36.973002) (xy 96.393 -37.100002) (xy 96.393 -38.878002) (xy 96.52 -39.005002) (xy 97.536 -39.005002)
				(xy 97.663 -38.878002) (xy 97.663 -37.100002) (xy 97.536 -36.973002)
			)
		)
		(polygon
			(pts
				(xy 97.3074 -38.354) (xy 97.0534 -38.354) (xy 97.0534 -38.608) (xy 97.3074 -38.608)
			)
		)
	)
	(zone
		(layers "B.Cu" "In2.Cu" "In4.Cu" "In5.Cu" "In6.Cu" "In7.Cu" "In10.Cu")
		(hatch none 0.5)
		(connect_pads
			(clearance 0)
		)
		(min_thickness 0.25)
		(keepout
			(tracks not_allowed)
			(vias allowed)
			(pads allowed)
			(copperpour not_allowed)
			(footprints allowed)
		)
		(placement
			(enabled no)
			(sheetname "")
		)
		(fill yes
			(thermal_gap 0.5)
			(thermal_bridge_width 0.5)
			(island_removal_mode 0)
		)
		(polygon
			(pts
				(arc
					(start 205.388972 -6.866128)
					(mid 203.059284 -6.866128)
					(end 205.388972 -6.866128)
				)
			)
		)
	)
	(zone
		(layers "B.Cu" "In2.Cu" "In4.Cu" "In5.Cu" "In6.Cu" "In7.Cu" "In10.Cu")
		(hatch none 0.5)
		(connect_pads
			(clearance 0)
		)
		(min_thickness 0.25)
		(keepout
			(tracks not_allowed)
			(vias allowed)
			(pads allowed)
			(copperpour not_allowed)
			(footprints allowed)
		)
		(placement
			(enabled no)
			(sheetname "")
		)
		(fill yes
			(thermal_gap 0.5)
			(thermal_bridge_width 0.5)
			(island_removal_mode 0)
		)
		(polygon
			(pts
				(arc
					(start 205.388972 -17.026128)
					(mid 203.059284 -17.026128)
					(end 205.388972 -17.026128)
				)
			)
		)
	)
	(zone
		(layers "B.Cu" "In2.Cu" "In4.Cu" "In7.Cu")
		(hatch none 0.5)
		(connect_pads
			(clearance 0)
		)
		(min_thickness 0.25)
		(keepout
			(tracks not_allowed)
			(vias allowed)
			(pads allowed)
			(copperpour not_allowed)
			(footprints allowed)
		)
		(placement
			(enabled no)
			(sheetname "")
		)
		(fill yes
			(thermal_gap 0.5)
			(thermal_bridge_width 0.5)
			(island_removal_mode 0)
		)
		(polygon
			(pts
				(arc
					(start 101.734366 -61.66993)
					(mid 101.189299 -61.660676)
					(end 101.185472 -62.20587)
				)
				(arc
					(start 101.795072 -62.817756)
					(mid 102.212157 -62.902047)
					(end 102.450392 -62.549532)
				)
				(arc
					(start 102.333552 -62.549532)
					(mid 102.066852 -62.813704)
					(end 101.800152 -62.549532)
				)
				(arc
					(start 101.800152 -62.546992)
					(mid 102.066852 -62.280292)
					(end 102.333552 -62.546992)
				)
				(arc
					(start 102.450392 -62.546992)
					(mid 102.421349 -62.400535)
					(end 102.338632 -62.276228)
				)
				(xy 102.001066 -61.937646)
				(arc
					(start 101.723952 -61.937646)
					(mid 101.457252 -62.201818)
					(end 101.190552 -61.937646)
				)
				(arc
					(start 101.190552 -61.935106)
					(mid 101.457252 -61.668406)
					(end 101.723952 -61.935106)
				)
				(xy 101.998526 -61.935106)
			)
		)
	)
	(zone
		(layers "B.Cu" "In2.Cu" "In4.Cu" "In7.Cu")
		(hatch none 0.5)
		(connect_pads
			(clearance 0)
		)
		(min_thickness 0.25)
		(keepout
			(tracks not_allowed)
			(vias allowed)
			(pads allowed)
			(copperpour not_allowed)
			(footprints allowed)
		)
		(placement
			(enabled no)
			(sheetname "")
		)
		(fill yes
			(thermal_gap 0.5)
			(thermal_bridge_width 0.5)
			(island_removal_mode 0)
		)
		(polygon
			(pts
				(arc
					(start 67.34556 -9.90092)
					(mid 66.96202 -10.28446)
					(end 67.34556 -10.668)
				)
				(arc
					(start 68.302886 -10.668)
					(mid 68.573354 -10.55665)
					(end 68.68668 -10.287)
				)
				(arc
					(start 68.56984 -10.287)
					(mid 68.30314 -10.551172)
					(end 68.03644 -10.287)
				)
				(arc
					(start 67.61226 -10.287)
					(mid 67.34556 -10.551172)
					(end 67.07886 -10.287)
				)
				(arc
					(start 67.07886 -10.28446)
					(mid 67.34556 -10.01776)
					(end 67.61226 -10.28446)
				)
				(arc
					(start 68.03644 -10.28446)
					(mid 68.30314 -10.01776)
					(end 68.56984 -10.28446)
				)
				(arc
					(start 68.68668 -10.28446)
					(mid 68.574344 -10.013256)
					(end 68.30314 -9.90092)
				)
			)
		)
	)
	(zone
		(layers "B.Cu" "In2.Cu" "In4.Cu" "In7.Cu")
		(hatch none 0.5)
		(connect_pads
			(clearance 0)
		)
		(min_thickness 0.25)
		(keepout
			(tracks not_allowed)
			(vias allowed)
			(pads allowed)
			(copperpour not_allowed)
			(footprints allowed)
		)
		(placement
			(enabled no)
			(sheetname "")
		)
		(fill yes
			(thermal_gap 0.5)
			(thermal_bridge_width 0.5)
			(island_removal_mode 0)
		)
		(polygon
			(pts
				(arc
					(start 31.40837 -9.867138)
					(mid 31.02483 -10.250678)
					(end 31.40837 -10.634218)
				)
				(arc
					(start 32.327596 -10.634218)
					(mid 32.598064 -10.522868)
					(end 32.71139 -10.253218)
				)
				(arc
					(start 32.59455 -10.253218)
					(mid 32.32785 -10.51739)
					(end 32.06115 -10.253218)
				)
				(arc
					(start 31.67507 -10.253218)
					(mid 31.40837 -10.51739)
					(end 31.14167 -10.253218)
				)
				(arc
					(start 31.14167 -10.250678)
					(mid 31.40837 -9.983978)
					(end 31.67507 -10.250678)
				)
				(arc
					(start 32.06115 -10.250678)
					(mid 32.32785 -9.983978)
					(end 32.59455 -10.250678)
				)
				(arc
					(start 32.71139 -10.250678)
					(mid 32.599054 -9.979474)
					(end 32.32785 -9.867138)
				)
			)
		)
	)
	(zone
		(layers "B.Cu" "In2.Cu" "In4.Cu" "In7.Cu")
		(hatch none 0.5)
		(connect_pads
			(clearance 0)
		)
		(min_thickness 0.25)
		(keepout
			(tracks not_allowed)
			(vias allowed)
			(pads allowed)
			(copperpour not_allowed)
			(footprints allowed)
		)
		(placement
			(enabled no)
			(sheetname "")
		)
		(fill yes
			(thermal_gap 0.5)
			(thermal_bridge_width 0.5)
			(island_removal_mode 0)
		)
		(polygon
			(pts
				(arc
					(start 23.40864 -9.867138)
					(mid 23.024846 -10.250551)
					(end 23.408386 -10.634218)
				)
				(arc
					(start 24.327866 -10.634218)
					(mid 24.59817 -10.522778)
					(end 24.711406 -10.253218)
				)
				(arc
					(start 24.594566 -10.253218)
					(mid 24.327866 -10.51739)
					(end 24.061166 -10.253218)
				)
				(arc
					(start 23.675086 -10.253218)
					(mid 23.408386 -10.51739)
					(end 23.141686 -10.253218)
				)
				(arc
					(start 23.141686 -10.250678)
					(mid 23.408386 -9.983978)
					(end 23.675086 -10.250678)
				)
				(arc
					(start 24.061166 -10.250678)
					(mid 24.327866 -9.983978)
					(end 24.594566 -10.250678)
				)
				(arc
					(start 24.711406 -10.250678)
					(mid 24.59907 -9.979474)
					(end 24.327866 -9.867138)
				)
			)
		)
	)
	(zone
		(layers "B.Cu" "In2.Cu" "In4.Cu" "In7.Cu")
		(hatch none 0.5)
		(connect_pads
			(clearance 0)
		)
		(min_thickness 0.25)
		(keepout
			(tracks not_allowed)
			(vias allowed)
			(pads allowed)
			(copperpour not_allowed)
			(footprints allowed)
		)
		(placement
			(enabled no)
			(sheetname "")
		)
		(fill yes
			(thermal_gap 0.5)
			(thermal_bridge_width 0.5)
			(island_removal_mode 0)
		)
		(polygon
			(pts
				(arc
					(start 47.408592 -9.867138)
					(mid 47.024798 -10.250551)
					(end 47.408338 -10.634218)
				)
				(arc
					(start 48.327818 -10.634218)
					(mid 48.598122 -10.522778)
					(end 48.711358 -10.253218)
				)
				(arc
					(start 48.594518 -10.253218)
					(mid 48.327818 -10.51739)
					(end 48.061118 -10.253218)
				)
				(arc
					(start 47.675038 -10.253218)
					(mid 47.408338 -10.51739)
					(end 47.141638 -10.253218)
				)
				(arc
					(start 47.141638 -10.250678)
					(mid 47.408338 -9.983978)
					(end 47.675038 -10.250678)
				)
				(arc
					(start 48.061118 -10.250678)
					(mid 48.327818 -9.983978)
					(end 48.594518 -10.250678)
				)
				(arc
					(start 48.711358 -10.250678)
					(mid 48.599022 -9.979474)
					(end 48.327818 -9.867138)
				)
			)
		)
	)
	(zone
		(layers "B.Cu" "In2.Cu" "In4.Cu" "In7.Cu")
		(hatch none 0.5)
		(connect_pads
			(clearance 0)
		)
		(min_thickness 0.25)
		(keepout
			(tracks not_allowed)
			(vias allowed)
			(pads allowed)
			(copperpour not_allowed)
			(footprints allowed)
		)
		(placement
			(enabled no)
			(sheetname "")
		)
		(fill yes
			(thermal_gap 0.5)
			(thermal_bridge_width 0.5)
			(island_removal_mode 0)
		)
		(polygon
			(pts
				(arc
					(start 43.4086 -9.867138)
					(mid 43.024806 -10.250551)
					(end 43.408346 -10.634218)
				)
				(arc
					(start 44.327826 -10.634218)
					(mid 44.59813 -10.522778)
					(end 44.711366 -10.253218)
				)
				(arc
					(start 44.594526 -10.253218)
					(mid 44.327826 -10.51739)
					(end 44.061126 -10.253218)
				)
				(arc
					(start 43.675046 -10.253218)
					(mid 43.408346 -10.51739)
					(end 43.141646 -10.253218)
				)
				(arc
					(start 43.141646 -10.250678)
					(mid 43.408346 -9.983978)
					(end 43.675046 -10.250678)
				)
				(arc
					(start 44.061126 -10.250678)
					(mid 44.327826 -9.983978)
					(end 44.594526 -10.250678)
				)
				(arc
					(start 44.711366 -10.250678)
					(mid 44.59903 -9.979474)
					(end 44.327826 -9.867138)
				)
			)
		)
	)
	(zone
		(layers "B.Cu" "In2.Cu" "In4.Cu" "In7.Cu")
		(hatch none 0.5)
		(connect_pads
			(clearance 0)
		)
		(min_thickness 0.25)
		(keepout
			(tracks not_allowed)
			(vias allowed)
			(pads allowed)
			(copperpour not_allowed)
			(footprints allowed)
		)
		(placement
			(enabled no)
			(sheetname "")
		)
		(fill yes
			(thermal_gap 0.5)
			(thermal_bridge_width 0.5)
			(island_removal_mode 0)
		)
		(polygon
			(pts
				(arc
					(start 39.408608 -9.867138)
					(mid 39.024814 -10.250551)
					(end 39.408354 -10.634218)
				)
				(arc
					(start 40.327834 -10.634218)
					(mid 40.598138 -10.522778)
					(end 40.711374 -10.253218)
				)
				(arc
					(start 40.594534 -10.253218)
					(mid 40.327834 -10.51739)
					(end 40.061134 -10.253218)
				)
				(arc
					(start 39.675054 -10.253218)
					(mid 39.408354 -10.51739)
					(end 39.141654 -10.253218)
				)
				(arc
					(start 39.141654 -10.250678)
					(mid 39.408354 -9.983978)
					(end 39.675054 -10.250678)
				)
				(arc
					(start 40.061134 -10.250678)
					(mid 40.327834 -9.983978)
					(end 40.594534 -10.250678)
				)
				(arc
					(start 40.711374 -10.250678)
					(mid 40.599038 -9.979474)
					(end 40.327834 -9.867138)
				)
			)
		)
	)
	(zone
		(layers "B.Cu" "In2.Cu" "In4.Cu" "In7.Cu")
		(hatch none 0.5)
		(connect_pads
			(clearance 0)
		)
		(min_thickness 0.25)
		(keepout
			(tracks not_allowed)
			(vias allowed)
			(pads allowed)
			(copperpour not_allowed)
			(footprints allowed)
		)
		(placement
			(enabled no)
			(sheetname "")
		)
		(fill yes
			(thermal_gap 0.5)
			(thermal_bridge_width 0.5)
			(island_removal_mode 0)
		)
		(polygon
			(pts
				(arc
					(start 99.781106 -60.369704)
					(mid 99.238816 -60.378086)
					(end 99.247198 -60.920376)
				)
				(xy 99.24542 -60.922154) (xy 99.86518 -61.523372) (xy 99.865434 -61.523372)
				(arc
					(start 99.866958 -61.521848)
					(mid 100.282474 -61.600369)
					(end 100.517706 -61.249052)
				)
				(arc
					(start 100.400866 -61.249052)
					(mid 100.134166 -61.513224)
					(end 99.867466 -61.249052)
				)
				(arc
					(start 99.867466 -61.246512)
					(mid 100.134166 -60.979812)
					(end 100.400866 -61.246512)
				)
				(arc
					(start 100.517706 -61.246512)
					(mid 100.487366 -61.097004)
					(end 100.40112 -60.971176)
				)
				(xy 100.402898 -60.969398) (xy 100.071174 -60.64758)
				(arc
					(start 99.780852 -60.64758)
					(mid 99.514152 -60.911752)
					(end 99.247452 -60.64758)
				)
				(arc
					(start 99.247452 -60.64504)
					(mid 99.514152 -60.37834)
					(end 99.780852 -60.64504)
				)
				(xy 100.068634 -60.64504) (xy 99.782884 -60.367926)
			)
		)
	)
	(zone
		(layers "B.Cu" "In2.Cu" "In4.Cu" "In7.Cu")
		(hatch none 0.5)
		(connect_pads
			(clearance 0)
		)
		(min_thickness 0.25)
		(keepout
			(tracks not_allowed)
			(vias allowed)
			(pads allowed)
			(copperpour not_allowed)
			(footprints allowed)
		)
		(placement
			(enabled no)
			(sheetname "")
		)
		(fill yes
			(thermal_gap 0.5)
			(thermal_bridge_width 0.5)
			(island_removal_mode 0)
		)
		(polygon
			(pts
				(arc
					(start 19.408648 -9.867138)
					(mid 19.024854 -10.250551)
					(end 19.408394 -10.634218)
				)
				(arc
					(start 20.327874 -10.634218)
					(mid 20.598178 -10.522778)
					(end 20.711414 -10.253218)
				)
				(arc
					(start 20.594574 -10.253218)
					(mid 20.327874 -10.51739)
					(end 20.061174 -10.253218)
				)
				(arc
					(start 19.675094 -10.253218)
					(mid 19.408394 -10.51739)
					(end 19.141694 -10.253218)
				)
				(arc
					(start 19.141694 -10.250678)
					(mid 19.408394 -9.983978)
					(end 19.675094 -10.250678)
				)
				(arc
					(start 20.061174 -10.250678)
					(mid 20.327874 -9.983978)
					(end 20.594574 -10.250678)
				)
				(arc
					(start 20.711414 -10.250678)
					(mid 20.599078 -9.979474)
					(end 20.327874 -9.867138)
				)
			)
		)
	)
	(zone
		(layers "B.Cu" "In2.Cu" "In4.Cu" "In7.Cu")
		(hatch none 0.5)
		(connect_pads
			(clearance 0)
		)
		(min_thickness 0.25)
		(keepout
			(tracks not_allowed)
			(vias allowed)
			(pads allowed)
			(copperpour not_allowed)
			(footprints allowed)
		)
		(placement
			(enabled no)
			(sheetname "")
		)
		(fill yes
			(thermal_gap 0.5)
			(thermal_bridge_width 0.5)
			(island_removal_mode 0)
		)
		(polygon
			(pts
				(arc
					(start 27.408378 -9.867138)
					(mid 27.024838 -10.250678)
					(end 27.408378 -10.634218)
				)
				(arc
					(start 28.327604 -10.634218)
					(mid 28.598072 -10.522868)
					(end 28.711398 -10.253218)
				)
				(arc
					(start 28.594558 -10.253218)
					(mid 28.327858 -10.51739)
					(end 28.061158 -10.253218)
				)
				(arc
					(start 27.675078 -10.253218)
					(mid 27.408378 -10.51739)
					(end 27.141678 -10.253218)
				)
				(arc
					(start 27.141678 -10.250678)
					(mid 27.408378 -9.983978)
					(end 27.675078 -10.250678)
				)
				(arc
					(start 28.061158 -10.250678)
					(mid 28.327858 -9.983978)
					(end 28.594558 -10.250678)
				)
				(arc
					(start 28.711398 -10.250678)
					(mid 28.599062 -9.979474)
					(end 28.327858 -9.867138)
				)
			)
		)
	)
	(zone
		(layers "B.Cu" "In2.Cu" "In4.Cu" "In7.Cu")
		(hatch none 0.5)
		(connect_pads
			(clearance 0)
		)
		(min_thickness 0.25)
		(keepout
			(tracks not_allowed)
			(vias allowed)
			(pads allowed)
			(copperpour not_allowed)
			(footprints allowed)
		)
		(placement
			(enabled no)
			(sheetname "")
		)
		(fill yes
			(thermal_gap 0.5)
			(thermal_bridge_width 0.5)
			(island_removal_mode 0)
		)
		(polygon
			(pts
				(arc
					(start 79.37119 -9.95172)
					(mid 78.987396 -10.335133)
					(end 79.370936 -10.7188)
				)
				(arc
					(start 80.328516 -10.7188)
					(mid 80.59882 -10.60736)
					(end 80.712056 -10.3378)
				)
				(arc
					(start 80.595216 -10.3378)
					(mid 80.328516 -10.601972)
					(end 80.061816 -10.3378)
				)
				(arc
					(start 79.637636 -10.3378)
					(mid 79.370936 -10.601972)
					(end 79.104236 -10.3378)
				)
				(arc
					(start 79.104236 -10.33526)
					(mid 79.370936 -10.06856)
					(end 79.637636 -10.33526)
				)
				(arc
					(start 80.061816 -10.33526)
					(mid 80.328516 -10.06856)
					(end 80.595216 -10.33526)
				)
				(arc
					(start 80.712056 -10.33526)
					(mid 80.59972 -10.064056)
					(end 80.328516 -9.95172)
				)
			)
		)
	)
	(zone
		(layers "B.Cu" "In2.Cu" "In4.Cu" "In7.Cu")
		(hatch none 0.5)
		(connect_pads
			(clearance 0)
		)
		(min_thickness 0.25)
		(keepout
			(tracks not_allowed)
			(vias allowed)
			(pads allowed)
			(copperpour not_allowed)
			(footprints allowed)
		)
		(placement
			(enabled no)
			(sheetname "")
		)
		(fill yes
			(thermal_gap 0.5)
			(thermal_bridge_width 0.5)
			(island_removal_mode 0)
		)
		(polygon
			(pts
				(arc
					(start 35.408362 -9.867138)
					(mid 35.024822 -10.250678)
					(end 35.408362 -10.634218)
				)
				(arc
					(start 36.327588 -10.634218)
					(mid 36.598056 -10.522868)
					(end 36.711382 -10.253218)
				)
				(arc
					(start 36.594542 -10.253218)
					(mid 36.327842 -10.51739)
					(end 36.061142 -10.253218)
				)
				(arc
					(start 35.675062 -10.253218)
					(mid 35.408362 -10.51739)
					(end 35.141662 -10.253218)
				)
				(arc
					(start 35.141662 -10.250678)
					(mid 35.408362 -9.983978)
					(end 35.675062 -10.250678)
				)
				(arc
					(start 36.061142 -10.250678)
					(mid 36.327842 -9.983978)
					(end 36.594542 -10.250678)
				)
				(arc
					(start 36.711382 -10.250678)
					(mid 36.599046 -9.979474)
					(end 36.327842 -9.867138)
				)
			)
		)
	)
	(zone
		(layers "B.Cu" "In2.Cu" "In4.Cu" "In7.Cu")
		(hatch none 0.5)
		(connect_pads
			(clearance 0)
		)
		(min_thickness 0.25)
		(keepout
			(tracks not_allowed)
			(vias allowed)
			(pads allowed)
			(copperpour not_allowed)
			(footprints allowed)
		)
		(placement
			(enabled no)
			(sheetname "")
		)
		(fill yes
			(thermal_gap 0.5)
			(thermal_bridge_width 0.5)
			(island_removal_mode 0)
		)
		(polygon
			(pts
				(arc
					(start 71.371206 -9.90092)
					(mid 70.987412 -10.284333)
					(end 71.370952 -10.668)
				)
				(arc
					(start 72.328532 -10.668)
					(mid 72.598836 -10.55656)
					(end 72.712072 -10.287)
				)
				(arc
					(start 72.595232 -10.287)
					(mid 72.328532 -10.551172)
					(end 72.061832 -10.287)
				)
				(arc
					(start 71.637652 -10.287)
					(mid 71.370952 -10.551172)
					(end 71.104252 -10.287)
				)
				(arc
					(start 71.104252 -10.28446)
					(mid 71.370952 -10.01776)
					(end 71.637652 -10.28446)
				)
				(arc
					(start 72.061832 -10.28446)
					(mid 72.328532 -10.01776)
					(end 72.595232 -10.28446)
				)
				(arc
					(start 72.712072 -10.28446)
					(mid 72.599736 -10.013256)
					(end 72.328532 -9.90092)
				)
			)
		)
	)
	(zone
		(layers "B.Cu" "In2.Cu" "In4.Cu" "In7.Cu")
		(hatch none 0.5)
		(connect_pads
			(clearance 0)
		)
		(min_thickness 0.25)
		(keepout
			(tracks not_allowed)
			(vias allowed)
			(pads allowed)
			(copperpour not_allowed)
			(footprints allowed)
		)
		(placement
			(enabled no)
			(sheetname "")
		)
		(fill yes
			(thermal_gap 0.5)
			(thermal_bridge_width 0.5)
			(island_removal_mode 0)
		)
		(polygon
			(pts
				(arc
					(start 75.371198 -9.90092)
					(mid 74.987404 -10.284333)
					(end 75.370944 -10.668)
				)
				(arc
					(start 76.328524 -10.668)
					(mid 76.598828 -10.55656)
					(end 76.712064 -10.287)
				)
				(arc
					(start 76.595224 -10.287)
					(mid 76.328524 -10.551172)
					(end 76.061824 -10.287)
				)
				(arc
					(start 75.637644 -10.287)
					(mid 75.370944 -10.551172)
					(end 75.104244 -10.287)
				)
				(arc
					(start 75.104244 -10.28446)
					(mid 75.370944 -10.01776)
					(end 75.637644 -10.28446)
				)
				(arc
					(start 76.061824 -10.28446)
					(mid 76.328524 -10.01776)
					(end 76.595224 -10.28446)
				)
				(arc
					(start 76.712064 -10.28446)
					(mid 76.599728 -10.013256)
					(end 76.328524 -9.90092)
				)
			)
		)
	)
	(zone
		(layers "B.Cu" "In2.Cu" "In4.Cu" "In9.Cu")
		(hatch none 0.5)
		(connect_pads
			(clearance 0)
		)
		(min_thickness 0.25)
		(keepout
			(tracks not_allowed)
			(vias allowed)
			(pads allowed)
			(copperpour not_allowed)
			(footprints allowed)
		)
		(placement
			(enabled no)
			(sheetname "")
		)
		(fill yes
			(thermal_gap 0.5)
			(thermal_bridge_width 0.5)
			(island_removal_mode 0)
		)
		(polygon
			(pts
				(arc
					(start 80.264254 -60.0329)
					(mid 79.9211 -60.375673)
					(end 80.264 -60.7187)
				)
				(arc
					(start 81.0514 -60.7187)
					(mid 81.292967 -60.619163)
					(end 81.3943 -60.37834)
				)
				(arc
					(start 81.28 -60.37834)
					(mid 81.0514 -60.604414)
					(end 80.8228 -60.37834)
				)
				(arc
					(start 80.4926 -60.37834)
					(mid 80.264 -60.604414)
					(end 80.0354 -60.37834)
				)
				(arc
					(start 80.0354 -60.3758)
					(mid 80.264 -60.1472)
					(end 80.4926 -60.3758)
				)
				(arc
					(start 80.8228 -60.3758)
					(mid 81.0514 -60.1472)
					(end 81.28 -60.3758)
				)
				(arc
					(start 81.3943 -60.3758)
					(mid 81.293867 -60.133333)
					(end 81.0514 -60.0329)
				)
			)
		)
	)
	(zone
		(layers "B.Cu" "In2.Cu" "In4.Cu" "In9.Cu")
		(hatch none 0.5)
		(connect_pads
			(clearance 0)
		)
		(min_thickness 0.25)
		(keepout
			(tracks not_allowed)
			(vias allowed)
			(pads allowed)
			(copperpour not_allowed)
			(footprints allowed)
		)
		(placement
			(enabled no)
			(sheetname "")
		)
		(fill yes
			(thermal_gap 0.5)
			(thermal_bridge_width 0.5)
			(island_removal_mode 0)
		)
		(polygon
			(pts
				(arc
					(start 10.009886 -62.727078)
					(mid 9.615678 -62.354714)
					(end 9.243314 -62.748922)
				)
				(xy 9.240774 -62.748922) (xy 9.266174 -63.637668) (xy 9.266428 -63.637922)
				(arc
					(start 9.268714 -63.637922)
					(mid 9.656192 -64.010419)
					(end 10.03554 -63.62954)
				)
				(arc
					(start 9.9187 -63.62954)
					(mid 9.652 -63.893712)
					(end 9.3853 -63.62954)
				)
				(arc
					(start 9.3853 -63.627)
					(mid 9.652 -63.3603)
					(end 9.9187 -63.627)
				)
				(xy 10.03554 -63.627) (xy 10.035286 -63.616078) (xy 10.037826 -63.616078) (xy 10.012934 -62.74054)
				(arc
					(start 9.8933 -62.74054)
					(mid 9.6266 -63.004712)
					(end 9.3599 -62.74054)
				)
				(arc
					(start 9.3599 -62.738)
					(mid 9.6266 -62.4713)
					(end 9.8933 -62.738)
				)
				(xy 10.01268 -62.738) (xy 10.012426 -62.727078)
			)
		)
	)
	(zone
		(layers "B.Cu" "In2.Cu" "In4.Cu" "In9.Cu")
		(hatch none 0.5)
		(connect_pads
			(clearance 0)
		)
		(min_thickness 0.25)
		(keepout
			(tracks not_allowed)
			(vias allowed)
			(pads allowed)
			(copperpour not_allowed)
			(footprints allowed)
		)
		(placement
			(enabled no)
			(sheetname "")
		)
		(fill yes
			(thermal_gap 0.5)
			(thermal_bridge_width 0.5)
			(island_removal_mode 0)
		)
		(polygon
			(pts
				(arc
					(start 13.55598 -47.66056)
					(mid 13.17244 -47.27702)
					(end 12.7889 -47.66056)
				)
				(arc
					(start 12.7889 -48.617886)
					(mid 13.171043 -49.001678)
					(end 13.55598 -48.62068)
				)
				(arc
					(start 13.43914 -48.62068)
					(mid 13.17244 -48.884852)
					(end 12.90574 -48.62068)
				)
				(arc
					(start 12.90574 -48.61814)
					(mid 13.17244 -48.35144)
					(end 13.43914 -48.61814)
				)
				(xy 13.55598 -48.61814) (xy 13.55598 -47.6631)
				(arc
					(start 13.43914 -47.6631)
					(mid 13.17244 -47.927272)
					(end 12.90574 -47.6631)
				)
				(arc
					(start 12.90574 -47.66056)
					(mid 13.17244 -47.39386)
					(end 13.43914 -47.66056)
				)
			)
		)
	)
	(zone
		(layers "B.Cu" "In2.Cu" "In4.Cu" "In9.Cu")
		(hatch none 0.5)
		(connect_pads
			(clearance 0)
		)
		(min_thickness 0.25)
		(keepout
			(tracks not_allowed)
			(vias allowed)
			(pads allowed)
			(copperpour not_allowed)
			(footprints allowed)
		)
		(placement
			(enabled no)
			(sheetname "")
		)
		(fill yes
			(thermal_gap 0.5)
			(thermal_bridge_width 0.5)
			(island_removal_mode 0)
		)
		(polygon
			(pts
				(arc
					(start 10.01014 -57.404)
					(mid 9.6266 -57.02046)
					(end 9.24306 -57.404)
				)
				(arc
					(start 9.24306 -58.293)
					(mid 9.62533 -58.676538)
					(end 10.01014 -58.29554)
				)
				(arc
					(start 9.8933 -58.29554)
					(mid 9.6266 -58.559712)
					(end 9.3599 -58.29554)
				)
				(arc
					(start 9.3599 -58.293)
					(mid 9.6266 -58.0263)
					(end 9.8933 -58.293)
				)
				(xy 10.01014 -58.293) (xy 10.01014 -57.40654)
				(arc
					(start 9.8933 -57.40654)
					(mid 9.6266 -57.670712)
					(end 9.3599 -57.40654)
				)
				(arc
					(start 9.3599 -57.404)
					(mid 9.6266 -57.1373)
					(end 9.8933 -57.404)
				)
			)
		)
	)
	(zone
		(layers "B.Cu" "In2.Cu" "In4.Cu" "In9.Cu")
		(hatch none 0.5)
		(connect_pads
			(clearance 0)
		)
		(min_thickness 0.25)
		(keepout
			(tracks not_allowed)
			(vias allowed)
			(pads allowed)
			(copperpour not_allowed)
			(footprints allowed)
		)
		(placement
			(enabled no)
			(sheetname "")
		)
		(fill yes
			(thermal_gap 0.5)
			(thermal_bridge_width 0.5)
			(island_removal_mode 0)
		)
		(polygon
			(pts
				(arc
					(start 52.1462 -13.56106)
					(mid 51.76266 -13.9446)
					(end 52.1462 -14.32814)
				)
				(arc
					(start 53.009546 -14.32814)
					(mid 53.280014 -14.21679)
					(end 53.39334 -13.94714)
				)
				(arc
					(start 53.2765 -13.94714)
					(mid 53.0098 -14.211312)
					(end 52.7431 -13.94714)
				)
				(arc
					(start 52.4129 -13.94714)
					(mid 52.1462 -14.211312)
					(end 51.8795 -13.94714)
				)
				(arc
					(start 51.8795 -13.9446)
					(mid 52.1462 -13.6779)
					(end 52.4129 -13.9446)
				)
				(arc
					(start 52.7431 -13.9446)
					(mid 53.0098 -13.6779)
					(end 53.2765 -13.9446)
				)
				(arc
					(start 53.39334 -13.9446)
					(mid 53.281004 -13.673396)
					(end 53.0098 -13.56106)
				)
			)
		)
	)
	(zone
		(layers "B.Cu" "In2.Cu" "In4.Cu" "In9.Cu")
		(hatch none 0.5)
		(connect_pads
			(clearance 0)
		)
		(min_thickness 0.25)
		(keepout
			(tracks not_allowed)
			(vias allowed)
			(pads allowed)
			(copperpour not_allowed)
			(footprints allowed)
		)
		(placement
			(enabled no)
			(sheetname "")
		)
		(fill yes
			(thermal_gap 0.5)
			(thermal_bridge_width 0.5)
			(island_removal_mode 0)
		)
		(polygon
			(pts
				(arc
					(start 83.78698 -55.45328)
					(mid 83.562783 -55.129816)
					(end 83.18119 -55.226204)
				)
				(arc
					(start 82.803746 -55.65902)
					(mid 82.83702 -56.146446)
					(end 83.324446 -56.113172)
				)
				(xy 83.52028 -55.888636)
				(arc
					(start 83.292696 -55.888636)
					(mid 83.064096 -56.11471)
					(end 82.835496 -55.888636)
				)
				(arc
					(start 82.835496 -55.886096)
					(mid 83.064096 -55.657496)
					(end 83.292696 -55.886096)
				)
				(xy 83.522566 -55.886096)
				(arc
					(start 83.701636 -55.68061)
					(mid 83.764492 -55.575879)
					(end 83.78698 -55.45582)
				)
				(arc
					(start 83.67014 -55.45582)
					(mid 83.44154 -55.681894)
					(end 83.21294 -55.45582)
				)
				(arc
					(start 83.21294 -55.45328)
					(mid 83.44154 -55.22468)
					(end 83.67014 -55.45328)
				)
			)
		)
	)
	(zone
		(layers "B.Cu" "In2.Cu" "In4.Cu" "In9.Cu")
		(hatch none 0.5)
		(connect_pads
			(clearance 0)
		)
		(min_thickness 0.25)
		(keepout
			(tracks not_allowed)
			(vias allowed)
			(pads allowed)
			(copperpour not_allowed)
			(footprints allowed)
		)
		(placement
			(enabled no)
			(sheetname "")
		)
		(fill yes
			(thermal_gap 0.5)
			(thermal_bridge_width 0.5)
			(island_removal_mode 0)
		)
		(polygon
			(pts
				(arc
					(start 49.454054 -13.4366)
					(mid 49.0728 -13.817473)
					(end 49.4538 -14.1986)
				)
				(arc
					(start 50.2158 -14.1986)
					(mid 50.484308 -14.087904)
					(end 50.5968 -13.82014)
				)
				(arc
					(start 50.4825 -13.82014)
					(mid 50.2158 -14.084312)
					(end 49.9491 -13.82014)
				)
				(arc
					(start 49.7205 -13.82014)
					(mid 49.4538 -14.084312)
					(end 49.1871 -13.82014)
				)
				(arc
					(start 49.1871 -13.8176)
					(mid 49.4538 -13.5509)
					(end 49.7205 -13.8176)
				)
				(arc
					(start 49.9491 -13.8176)
					(mid 50.2158 -13.5509)
					(end 50.4825 -13.8176)
				)
				(arc
					(start 50.5968 -13.8176)
					(mid 50.485208 -13.548192)
					(end 50.2158 -13.4366)
				)
			)
		)
	)
	(zone
		(layers "B.Cu" "In2.Cu" "In4.Cu" "In9.Cu")
		(hatch none 0.5)
		(connect_pads
			(clearance 0)
		)
		(min_thickness 0.25)
		(keepout
			(tracks not_allowed)
			(vias allowed)
			(pads allowed)
			(copperpour not_allowed)
			(footprints allowed)
		)
		(placement
			(enabled no)
			(sheetname "")
		)
		(fill yes
			(thermal_gap 0.5)
			(thermal_bridge_width 0.5)
			(island_removal_mode 0)
		)
		(polygon
			(pts
				(arc
					(start 10.01014 -60.96)
					(mid 9.6266 -60.57646)
					(end 9.24306 -60.96)
				)
				(arc
					(start 9.24306 -61.849)
					(mid 9.62533 -62.232538)
					(end 10.01014 -61.85154)
				)
				(arc
					(start 9.8933 -61.85154)
					(mid 9.6266 -62.115712)
					(end 9.3599 -61.85154)
				)
				(arc
					(start 9.3599 -61.849)
					(mid 9.6266 -61.5823)
					(end 9.8933 -61.849)
				)
				(xy 10.01014 -61.849) (xy 10.01014 -60.96254)
				(arc
					(start 9.8933 -60.96254)
					(mid 9.6266 -61.226712)
					(end 9.3599 -60.96254)
				)
				(arc
					(start 9.3599 -60.96)
					(mid 9.6266 -60.6933)
					(end 9.8933 -60.96)
				)
			)
		)
	)
	(zone
		(layers "B.Cu" "In2.Cu" "In4.Cu" "In9.Cu")
		(hatch none 0.5)
		(connect_pads
			(clearance 0)
		)
		(min_thickness 0.25)
		(keepout
			(tracks not_allowed)
			(vias allowed)
			(pads allowed)
			(copperpour not_allowed)
			(footprints allowed)
		)
		(placement
			(enabled no)
			(sheetname "")
		)
		(fill yes
			(thermal_gap 0.5)
			(thermal_bridge_width 0.5)
			(island_removal_mode 0)
		)
		(polygon
			(pts
				(arc
					(start 84.452968 -59.349132)
					(mid 84.241622 -59.032471)
					(end 83.868006 -59.106054)
				)
				(arc
					(start 83.309968 -59.661806)
					(mid 83.308952 -60.146946)
					(end 83.794092 -60.147962)
				)
				(xy 84.035392 -59.907424)
				(arc
					(start 83.78063 -59.907424)
					(mid 83.55203 -60.133498)
					(end 83.32343 -59.907424)
				)
				(arc
					(start 83.32343 -59.904884)
					(mid 83.55203 -59.676284)
					(end 83.78063 -59.904884)
				)
				(xy 84.037932 -59.904884)
				(arc
					(start 84.348828 -59.595258)
					(mid 84.425369 -59.483927)
					(end 84.452968 -59.351672)
				)
				(arc
					(start 84.338668 -59.351672)
					(mid 84.110068 -59.577746)
					(end 83.881468 -59.351672)
				)
				(arc
					(start 83.881468 -59.349132)
					(mid 84.110068 -59.120532)
					(end 84.338668 -59.349132)
				)
			)
		)
	)
	(zone
		(layers "B.Cu" "In2.Cu" "In4.Cu" "In9.Cu")
		(hatch none 0.5)
		(connect_pads
			(clearance 0)
		)
		(min_thickness 0.25)
		(keepout
			(tracks not_allowed)
			(vias allowed)
			(pads allowed)
			(copperpour not_allowed)
			(footprints allowed)
		)
		(placement
			(enabled no)
			(sheetname "")
		)
		(fill yes
			(thermal_gap 0.5)
			(thermal_bridge_width 0.5)
			(island_removal_mode 0)
		)
		(polygon
			(pts
				(arc
					(start 10.009886 -59.171078)
					(mid 9.615678 -58.798714)
					(end 9.243314 -59.192922)
				)
				(xy 9.240774 -59.192922) (xy 9.266174 -60.081668) (xy 9.266428 -60.081922)
				(arc
					(start 9.268714 -60.081922)
					(mid 9.656192 -60.454419)
					(end 10.03554 -60.07354)
				)
				(arc
					(start 9.9187 -60.07354)
					(mid 9.652 -60.337712)
					(end 9.3853 -60.07354)
				)
				(arc
					(start 9.3853 -60.071)
					(mid 9.652 -59.8043)
					(end 9.9187 -60.071)
				)
				(xy 10.03554 -60.071) (xy 10.035286 -60.060078) (xy 10.037826 -60.060078) (xy 10.012934 -59.18454)
				(arc
					(start 9.8933 -59.18454)
					(mid 9.6266 -59.448712)
					(end 9.3599 -59.18454)
				)
				(arc
					(start 9.3599 -59.182)
					(mid 9.6266 -58.9153)
					(end 9.8933 -59.182)
				)
				(xy 10.01268 -59.182) (xy 10.012426 -59.171078)
			)
		)
	)
	(zone
		(layers "B.Cu" "In2.Cu" "In4.Cu" "In9.Cu")
		(hatch none 0.5)
		(connect_pads
			(clearance 0)
		)
		(min_thickness 0.25)
		(keepout
			(tracks not_allowed)
			(vias allowed)
			(pads allowed)
			(copperpour not_allowed)
			(footprints allowed)
		)
		(placement
			(enabled no)
			(sheetname "")
		)
		(fill yes
			(thermal_gap 0.5)
			(thermal_bridge_width 0.5)
			(island_removal_mode 0)
		)
		(polygon
			(pts
				(arc
					(start 91.403932 -53.39588)
					(mid 91.067513 -53.050558)
					(end 90.71356 -53.377846)
				)
				(xy 90.71102 -53.377592) (xy 90.681556 -53.93817)
				(arc
					(start 90.684096 -53.938424)
					(mid 91.010994 -54.30139)
					(end 91.37396 -53.974492)
				)
				(xy 91.3765 -53.974746) (xy 91.377262 -53.958998)
				(arc
					(start 91.257628 -53.958998)
					(mid 91.029028 -54.185072)
					(end 90.800428 -53.958998)
				)
				(arc
					(start 90.800428 -53.956458)
					(mid 91.029028 -53.727858)
					(end 91.257628 -53.956458)
				)
				(xy 91.377516 -53.956458) (xy 91.405964 -53.414422) (xy 91.40571 -53.414168) (xy 91.403424 -53.414168)
				(xy 91.403932 -53.39842)
				(arc
					(start 91.287092 -53.39842)
					(mid 91.058492 -53.624494)
					(end 90.829892 -53.39842)
				)
				(arc
					(start 90.829892 -53.39588)
					(mid 91.058492 -53.16728)
					(end 91.287092 -53.39588)
				)
			)
		)
	)
	(zone
		(layers "B.Cu" "In2.Cu" "In4.Cu" "In9.Cu")
		(hatch none 0.5)
		(connect_pads
			(clearance 0)
		)
		(min_thickness 0.25)
		(keepout
			(tracks not_allowed)
			(vias allowed)
			(pads allowed)
			(copperpour not_allowed)
			(footprints allowed)
		)
		(placement
			(enabled no)
			(sheetname "")
		)
		(fill yes
			(thermal_gap 0.5)
			(thermal_bridge_width 0.5)
			(island_removal_mode 0)
		)
		(polygon
			(pts
				(arc
					(start 10.01014 -64.516)
					(mid 9.6266 -64.13246)
					(end 9.24306 -64.516)
				)
				(arc
					(start 9.24306 -65.405)
					(mid 9.62533 -65.788538)
					(end 10.01014 -65.40754)
				)
				(arc
					(start 9.8933 -65.40754)
					(mid 9.6266 -65.671712)
					(end 9.3599 -65.40754)
				)
				(arc
					(start 9.3599 -65.405)
					(mid 9.6266 -65.1383)
					(end 9.8933 -65.405)
				)
				(xy 10.01014 -65.405) (xy 10.01014 -64.51854)
				(arc
					(start 9.8933 -64.51854)
					(mid 9.6266 -64.782712)
					(end 9.3599 -64.51854)
				)
				(arc
					(start 9.3599 -64.516)
					(mid 9.6266 -64.2493)
					(end 9.8933 -64.516)
				)
			)
		)
	)
	(zone
		(layers "B.Cu" "In2.Cu" "In4.Cu" "In9.Cu")
		(hatch none 0.5)
		(connect_pads
			(clearance 0)
		)
		(min_thickness 0.25)
		(keepout
			(tracks not_allowed)
			(vias allowed)
			(pads allowed)
			(copperpour not_allowed)
			(footprints allowed)
		)
		(placement
			(enabled no)
			(sheetname "")
		)
		(fill yes
			(thermal_gap 0.5)
			(thermal_bridge_width 0.5)
			(island_removal_mode 0)
		)
		(polygon
			(pts
				(arc
					(start 63.627254 -14.3256)
					(mid 63.246 -14.706473)
					(end 63.627 -15.0876)
				)
				(arc
					(start 64.389 -15.0876)
					(mid 64.657508 -14.976904)
					(end 64.77 -14.70914)
				)
				(arc
					(start 64.6557 -14.70914)
					(mid 64.389 -14.973312)
					(end 64.1223 -14.70914)
				)
				(arc
					(start 63.8937 -14.70914)
					(mid 63.627 -14.973312)
					(end 63.3603 -14.70914)
				)
				(arc
					(start 63.3603 -14.7066)
					(mid 63.627 -14.4399)
					(end 63.8937 -14.7066)
				)
				(arc
					(start 64.1223 -14.7066)
					(mid 64.389 -14.4399)
					(end 64.6557 -14.7066)
				)
				(arc
					(start 64.77 -14.7066)
					(mid 64.658408 -14.437192)
					(end 64.389 -14.3256)
				)
			)
		)
	)
	(zone
		(layers "B.Cu" "In2.Cu" "In4.Cu" "In9.Cu")
		(hatch none 0.5)
		(connect_pads
			(clearance 0)
		)
		(min_thickness 0.25)
		(keepout
			(tracks not_allowed)
			(vias allowed)
			(pads allowed)
			(copperpour not_allowed)
			(footprints allowed)
		)
		(placement
			(enabled no)
			(sheetname "")
		)
		(fill yes
			(thermal_gap 0.5)
			(thermal_bridge_width 0.5)
			(island_removal_mode 0)
		)
		(polygon
			(pts
				(arc
					(start 10.01014 -55.626)
					(mid 9.6266 -55.24246)
					(end 9.24306 -55.626)
				)
				(arc
					(start 9.24306 -56.515)
					(mid 9.62533 -56.898538)
					(end 10.01014 -56.51754)
				)
				(arc
					(start 9.8933 -56.51754)
					(mid 9.6266 -56.781712)
					(end 9.3599 -56.51754)
				)
				(arc
					(start 9.3599 -56.515)
					(mid 9.6266 -56.2483)
					(end 9.8933 -56.515)
				)
				(xy 10.01014 -56.515) (xy 10.01014 -55.62854)
				(arc
					(start 9.8933 -55.62854)
					(mid 9.6266 -55.892712)
					(end 9.3599 -55.62854)
				)
				(arc
					(start 9.3599 -55.626)
					(mid 9.6266 -55.3593)
					(end 9.8933 -55.626)
				)
			)
		)
	)
	(zone
		(layers "B.Cu" "In2.Cu" "In4.Cu" "In9.Cu")
		(hatch none 0.5)
		(connect_pads
			(clearance 0)
		)
		(min_thickness 0.25)
		(keepout
			(tracks not_allowed)
			(vias allowed)
			(pads allowed)
			(copperpour not_allowed)
			(footprints allowed)
		)
		(placement
			(enabled no)
			(sheetname "")
		)
		(fill yes
			(thermal_gap 0.5)
			(thermal_bridge_width 0.5)
			(island_removal_mode 0)
		)
		(polygon
			(pts
				(arc
					(start 14.153134 -46.44898)
					(mid 13.76934 -46.832393)
					(end 14.15288 -47.21606)
				)
				(arc
					(start 15.082266 -47.21606)
					(mid 15.35257 -47.10462)
					(end 15.465806 -46.83506)
				)
				(arc
					(start 15.348966 -46.83506)
					(mid 15.082266 -47.099232)
					(end 14.815566 -46.83506)
				)
				(arc
					(start 14.41958 -46.83506)
					(mid 14.15288 -47.099232)
					(end 13.88618 -46.83506)
				)
				(arc
					(start 13.88618 -46.83252)
					(mid 14.15288 -46.56582)
					(end 14.41958 -46.83252)
				)
				(arc
					(start 14.815566 -46.83252)
					(mid 15.082266 -46.56582)
					(end 15.348966 -46.83252)
				)
				(arc
					(start 15.465806 -46.83252)
					(mid 15.35347 -46.561316)
					(end 15.082266 -46.44898)
				)
			)
		)
	)
	(zone
		(layers "B.Cu" "In2.Cu" "In7.Cu" "In9.Cu")
		(hatch none 0.5)
		(connect_pads
			(clearance 0)
		)
		(min_thickness 0.25)
		(keepout
			(tracks not_allowed)
			(vias allowed)
			(pads allowed)
			(copperpour not_allowed)
			(footprints allowed)
		)
		(placement
			(enabled no)
			(sheetname "")
		)
		(fill yes
			(thermal_gap 0.5)
			(thermal_bridge_width 0.5)
			(island_removal_mode 0)
		)
		(polygon
			(pts
				(arc
					(start 10.61974 -54.0258)
					(mid 9.903458 -54.02707)
					(end 10.61974 -54.02834)
				)
				(arc
					(start 10.5283 -54.02834)
					(mid 10.2616 -54.292512)
					(end 9.9949 -54.02834)
				)
				(arc
					(start 9.9949 -54.0258)
					(mid 10.2616 -53.7591)
					(end 10.5283 -54.0258)
				)
			)
		)
	)
	(zone
		(layers "B.Cu" "In2.Cu" "In7.Cu" "In9.Cu")
		(hatch none 0.5)
		(connect_pads
			(clearance 0)
		)
		(min_thickness 0.25)
		(keepout
			(tracks not_allowed)
			(vias allowed)
			(pads allowed)
			(copperpour not_allowed)
			(footprints allowed)
		)
		(placement
			(enabled no)
			(sheetname "")
		)
		(fill yes
			(thermal_gap 0.5)
			(thermal_bridge_width 0.5)
			(island_removal_mode 0)
		)
		(polygon
			(pts
				(arc
					(start 9.90854 -51.7398)
					(mid 9.192258 -51.74107)
					(end 9.90854 -51.74234)
				)
				(arc
					(start 9.8171 -51.74234)
					(mid 9.5504 -52.006512)
					(end 9.2837 -51.74234)
				)
				(arc
					(start 9.2837 -51.7398)
					(mid 9.5504 -51.4731)
					(end 9.8171 -51.7398)
				)
			)
		)
	)
	(zone
		(layers "B.Cu" "In2.Cu" "In7.Cu" "In9.Cu")
		(hatch none 0.5)
		(connect_pads
			(clearance 0)
		)
		(min_thickness 0.25)
		(keepout
			(tracks not_allowed)
			(vias allowed)
			(pads allowed)
			(copperpour not_allowed)
			(footprints allowed)
		)
		(placement
			(enabled no)
			(sheetname "")
		)
		(fill yes
			(thermal_gap 0.5)
			(thermal_bridge_width 0.5)
			(island_removal_mode 0)
		)
		(polygon
			(pts
				(arc
					(start 78.878176 -29.8958)
					(mid 78.776392 -29.65199)
					(end 78.531466 -29.5529)
				)
				(arc
					(start 77.972666 -29.55925)
					(mid 77.633576 -29.90596)
					(end 77.980286 -30.24505)
				)
				(arc
					(start 78.538832 -30.2387)
					(mid 78.778115 -30.13792)
					(end 78.878176 -29.89834)
				)
				(arc
					(start 78.763876 -29.89834)
					(mid 78.538454 -30.124392)
					(end 78.30693 -29.90469)
				)
				(arc
					(start 78.205076 -29.90469)
					(mid 77.976476 -30.130764)
					(end 77.747876 -29.90469)
				)
				(arc
					(start 77.747876 -29.90215)
					(mid 77.976476 -29.67355)
					(end 78.205076 -29.90215)
				)
				(xy 78.306676 -29.90215) (xy 78.306676 -29.89834)
				(arc
					(start 78.306676 -29.8958)
					(mid 78.535276 -29.6672)
					(end 78.763876 -29.8958)
				)
			)
		)
	)
	(zone
		(layers "B.Cu" "In2.Cu" "In7.Cu" "In9.Cu")
		(hatch none 0.5)
		(connect_pads
			(clearance 0)
		)
		(min_thickness 0.25)
		(keepout
			(tracks not_allowed)
			(vias allowed)
			(pads allowed)
			(copperpour not_allowed)
			(footprints allowed)
		)
		(placement
			(enabled no)
			(sheetname "")
		)
		(fill yes
			(thermal_gap 0.5)
			(thermal_bridge_width 0.5)
			(island_removal_mode 0)
		)
		(polygon
			(pts
				(arc
					(start 78.12024 -30.823154)
					(mid 77.762614 -31.150687)
					(end 78.090014 -31.508446)
				)
				(arc
					(start 78.648814 -31.53283)
					(mid 78.908738 -31.430259)
					(end 79.005938 -31.16834)
				)
				(arc
					(start 78.891384 -31.16834)
					(mid 78.6638 -31.418814)
					(end 78.436216 -31.16834)
				)
				(arc
					(start 78.3336 -31.16834)
					(mid 78.105 -31.394414)
					(end 77.8764 -31.16834)
				)
				(arc
					(start 77.8764 -31.1658)
					(mid 78.105 -30.9372)
					(end 78.3336 -31.1658)
				)
				(arc
					(start 78.43647 -31.1658)
					(mid 78.6638 -30.96155)
					(end 78.89113 -31.1658)
				)
				(arc
					(start 79.005938 -31.1658)
					(mid 78.902991 -30.944337)
					(end 78.678786 -30.847538)
				)
			)
		)
	)
	(zone
		(layers "B.Cu" "In2.Cu" "In7.Cu" "In9.Cu")
		(hatch none 0.5)
		(connect_pads
			(clearance 0)
		)
		(min_thickness 0.25)
		(keepout
			(tracks not_allowed)
			(vias allowed)
			(pads allowed)
			(copperpour not_allowed)
			(footprints allowed)
		)
		(placement
			(enabled no)
			(sheetname "")
		)
		(fill yes
			(thermal_gap 0.5)
			(thermal_bridge_width 0.5)
			(island_removal_mode 0)
		)
		(polygon
			(pts
				(arc
					(start 9.90854 -50.4952)
					(mid 9.192258 -50.49647)
					(end 9.90854 -50.49774)
				)
				(arc
					(start 9.8171 -50.49774)
					(mid 9.5504 -50.761912)
					(end 9.2837 -50.49774)
				)
				(arc
					(start 9.2837 -50.4952)
					(mid 9.5504 -50.2285)
					(end 9.8171 -50.4952)
				)
			)
		)
	)
	(zone
		(layers "B.Cu" "In2.Cu" "In7.Cu" "In9.Cu")
		(hatch none 0.5)
		(connect_pads
			(clearance 0)
		)
		(min_thickness 0.25)
		(keepout
			(tracks not_allowed)
			(vias allowed)
			(pads allowed)
			(copperpour not_allowed)
			(footprints allowed)
		)
		(placement
			(enabled no)
			(sheetname "")
		)
		(fill yes
			(thermal_gap 0.5)
			(thermal_bridge_width 0.5)
			(island_removal_mode 0)
		)
		(polygon
			(pts
				(arc
					(start 10.61974 -52.7812)
					(mid 9.903458 -52.78247)
					(end 10.61974 -52.78374)
				)
				(arc
					(start 10.5283 -52.78374)
					(mid 10.2616 -53.047912)
					(end 9.9949 -52.78374)
				)
				(arc
					(start 9.9949 -52.7812)
					(mid 10.2616 -52.5145)
					(end 10.5283 -52.7812)
				)
			)
		)
	)
	(zone
		(layers "B.Cu" "In4.Cu" "In7.Cu" "In9.Cu")
		(hatch none 0.5)
		(connect_pads
			(clearance 0)
		)
		(min_thickness 0.25)
		(keepout
			(tracks not_allowed)
			(vias allowed)
			(pads allowed)
			(copperpour not_allowed)
			(footprints allowed)
		)
		(placement
			(enabled no)
			(sheetname "")
		)
		(fill yes
			(thermal_gap 0.5)
			(thermal_bridge_width 0.5)
			(island_removal_mode 0)
		)
		(polygon
			(pts
				(arc
					(start 84.586572 -54.01564)
					(mid 84.244434 -53.670216)
					(end 83.895692 -54.009036)
				)
				(arc
					(start 83.885024 -54.567836)
					(mid 84.22386 -54.91988)
					(end 84.575904 -54.581044)
				)
				(xy 84.575904 -54.57698)
				(arc
					(start 84.459064 -54.57698)
					(mid 84.230464 -54.803054)
					(end 84.001864 -54.57698)
				)
				(arc
					(start 84.001864 -54.57444)
					(mid 84.230464 -54.34584)
					(end 84.459064 -54.57444)
				)
				(xy 84.575904 -54.57444) (xy 84.586572 -54.022498) (xy 84.586572 -54.01818)
				(arc
					(start 84.469732 -54.01818)
					(mid 84.241132 -54.244254)
					(end 84.012532 -54.01818)
				)
				(arc
					(start 84.012532 -54.01564)
					(mid 84.241132 -53.78704)
					(end 84.469732 -54.01564)
				)
			)
		)
	)
	(zone
		(layers "B.Cu" "In4.Cu" "In7.Cu" "In9.Cu")
		(hatch none 0.5)
		(connect_pads
			(clearance 0)
		)
		(min_thickness 0.25)
		(keepout
			(tracks not_allowed)
			(vias allowed)
			(pads allowed)
			(copperpour not_allowed)
			(footprints allowed)
		)
		(placement
			(enabled no)
			(sheetname "")
		)
		(fill yes
			(thermal_gap 0.5)
			(thermal_bridge_width 0.5)
			(island_removal_mode 0)
		)
		(polygon
			(pts
				(arc
					(start 88.633808 -53.399182)
					(mid 88.277446 -53.065172)
					(end 87.943436 -53.421534)
				)
				(xy 87.940896 -53.421534) (xy 87.95893 -53.98008)
				(arc
					(start 87.96147 -53.98008)
					(mid 88.310975 -54.314244)
					(end 88.652096 -53.971444)
				)
				(arc
					(start 88.535256 -53.971444)
					(mid 88.306656 -54.197518)
					(end 88.078056 -53.971444)
				)
				(arc
					(start 88.078056 -53.968904)
					(mid 88.306656 -53.740304)
					(end 88.535256 -53.968904)
				)
				(xy 88.652096 -53.968904) (xy 88.651842 -53.957728) (xy 88.654382 -53.957728) (xy 88.636856 -53.412898)
				(arc
					(start 88.517222 -53.412898)
					(mid 88.288622 -53.638972)
					(end 88.060022 -53.412898)
				)
				(arc
					(start 88.060022 -53.410358)
					(mid 88.288622 -53.181758)
					(end 88.517222 -53.410358)
				)
				(xy 88.636602 -53.410358) (xy 88.636348 -53.399436) (xy 88.636094 -53.399182)
			)
		)
	)
	(zone
		(layers "B.Cu" "In4.Cu" "In7.Cu" "In9.Cu")
		(hatch none 0.5)
		(connect_pads
			(clearance 0)
		)
		(min_thickness 0.25)
		(keepout
			(tracks not_allowed)
			(vias allowed)
			(pads allowed)
			(copperpour not_allowed)
			(footprints allowed)
		)
		(placement
			(enabled no)
			(sheetname "")
		)
		(fill yes
			(thermal_gap 0.5)
			(thermal_bridge_width 0.5)
			(island_removal_mode 0)
		)
		(polygon
			(pts
				(arc
					(start 82.0293 -53.0098)
					(mid 81.6864 -52.6669)
					(end 81.3435 -53.0098)
				)
				(arc
					(start 81.3435 -53.593746)
					(mid 81.685003 -53.936897)
					(end 82.0293 -53.59654)
				)
				(arc
					(start 81.915 -53.59654)
					(mid 81.6864 -53.822614)
					(end 81.4578 -53.59654)
				)
				(arc
					(start 81.4578 -53.594)
					(mid 81.6864 -53.3654)
					(end 81.915 -53.594)
				)
				(xy 82.0293 -53.594) (xy 82.0293 -53.01234)
				(arc
					(start 81.915 -53.01234)
					(mid 81.6864 -53.238414)
					(end 81.4578 -53.01234)
				)
				(arc
					(start 81.4578 -53.0098)
					(mid 81.6864 -52.7812)
					(end 81.915 -53.0098)
				)
			)
		)
	)
	(zone
		(layers "B.Cu" "In4.Cu" "In7.Cu" "In9.Cu")
		(hatch none 0.5)
		(connect_pads
			(clearance 0)
		)
		(min_thickness 0.25)
		(keepout
			(tracks not_allowed)
			(vias allowed)
			(pads allowed)
			(copperpour not_allowed)
			(footprints allowed)
		)
		(placement
			(enabled no)
			(sheetname "")
		)
		(fill yes
			(thermal_gap 0.5)
			(thermal_bridge_width 0.5)
			(island_removal_mode 0)
		)
		(polygon
			(pts
				(arc
					(start 86.030054 -54.795674)
					(mid 85.687281 -54.450244)
					(end 85.339174 -54.79034)
				)
				(arc
					(start 85.330538 -55.356506)
					(mid 85.670517 -55.707536)
					(end 86.021418 -55.367428)
				)
				(xy 86.021418 -55.364634)
				(arc
					(start 85.904578 -55.364634)
					(mid 85.675978 -55.590708)
					(end 85.447378 -55.364634)
				)
				(arc
					(start 85.447378 -55.362094)
					(mid 85.675978 -55.133494)
					(end 85.904578 -55.362094)
				)
				(xy 86.021418 -55.362094) (xy 86.030054 -54.801008) (xy 86.030054 -54.798214)
				(arc
					(start 85.913214 -54.798214)
					(mid 85.684614 -55.024288)
					(end 85.456014 -54.798214)
				)
				(arc
					(start 85.456014 -54.795674)
					(mid 85.684614 -54.567074)
					(end 85.913214 -54.795674)
				)
			)
		)
	)
	(zone
		(layers "B.Cu" "In4.Cu" "In7.Cu" "In9.Cu")
		(hatch none 0.5)
		(connect_pads
			(clearance 0)
		)
		(min_thickness 0.25)
		(keepout
			(tracks not_allowed)
			(vias allowed)
			(pads allowed)
			(copperpour not_allowed)
			(footprints allowed)
		)
		(placement
			(enabled no)
			(sheetname "")
		)
		(fill yes
			(thermal_gap 0.5)
			(thermal_bridge_width 0.5)
			(island_removal_mode 0)
		)
		(polygon
			(pts
				(arc
					(start 59.078368 -10.552938)
					(mid 58.694574 -10.936351)
					(end 59.078114 -11.320018)
				)
				(arc
					(start 59.997594 -11.320018)
					(mid 60.267898 -11.208578)
					(end 60.381134 -10.939018)
				)
				(arc
					(start 60.264294 -10.939018)
					(mid 59.997594 -11.20319)
					(end 59.730894 -10.939018)
				)
				(arc
					(start 59.344814 -10.939018)
					(mid 59.078114 -11.20319)
					(end 58.811414 -10.939018)
				)
				(arc
					(start 58.811414 -10.936478)
					(mid 59.078114 -10.669778)
					(end 59.344814 -10.936478)
				)
				(arc
					(start 59.730894 -10.936478)
					(mid 59.997594 -10.669778)
					(end 60.264294 -10.936478)
				)
				(arc
					(start 60.381134 -10.936478)
					(mid 60.268798 -10.665274)
					(end 59.997594 -10.552938)
				)
			)
		)
	)
	(zone
		(layers "B.Cu" "In4.Cu" "In7.Cu" "In9.Cu")
		(hatch none 0.5)
		(connect_pads
			(clearance 0)
		)
		(min_thickness 0.25)
		(keepout
			(tracks not_allowed)
			(vias allowed)
			(pads allowed)
			(copperpour not_allowed)
			(footprints allowed)
		)
		(placement
			(enabled no)
			(sheetname "")
		)
		(fill yes
			(thermal_gap 0.5)
			(thermal_bridge_width 0.5)
			(island_removal_mode 0)
		)
		(polygon
			(pts
				(arc
					(start 90.158316 -53.519578)
					(mid 89.829276 -53.174528)
					(end 89.46896 -53.486812)
				)
				(arc
					(start 89.415874 -54.043326)
					(mid 89.727024 -54.420008)
					(end 90.103706 -54.108858)
				)
				(xy 90.1065 -54.078632)
				(arc
					(start 89.98839 -54.078632)
					(mid 89.75979 -54.304706)
					(end 89.53119 -54.078632)
				)
				(arc
					(start 89.53119 -54.076092)
					(mid 89.75979 -53.847492)
					(end 89.98839 -54.076092)
				)
				(xy 90.106754 -54.076092) (xy 90.156792 -53.552598) (xy 90.158316 -53.522118)
				(arc
					(start 90.041476 -53.522118)
					(mid 89.812876 -53.748192)
					(end 89.584276 -53.522118)
				)
				(arc
					(start 89.584276 -53.519578)
					(mid 89.812876 -53.290978)
					(end 90.041476 -53.519578)
				)
			)
		)
	)
	(zone
		(layers "B.Cu" "In4.Cu" "In7.Cu" "In9.Cu")
		(hatch none 0.5)
		(connect_pads
			(clearance 0)
		)
		(min_thickness 0.25)
		(keepout
			(tracks not_allowed)
			(vias allowed)
			(pads allowed)
			(copperpour not_allowed)
			(footprints allowed)
		)
		(placement
			(enabled no)
			(sheetname "")
		)
		(fill yes
			(thermal_gap 0.5)
			(thermal_bridge_width 0.5)
			(island_removal_mode 0)
		)
		(polygon
			(pts
				(arc
					(start 91.741498 -54.950614)
					(mid 91.562833 -54.6481)
					(end 91.211654 -54.658514)
				)
				(xy 91.210384 -54.656482) (xy 90.73769 -54.954678) (xy 90.73769 -54.954932)
				(arc
					(start 90.73896 -54.956964)
					(mid 90.631264 -55.433468)
					(end 91.107768 -55.541164)
				)
				(xy 91.109038 -55.543196) (xy 91.57081 -55.251604)
				(arc
					(start 91.151964 -55.251604)
					(mid 90.923364 -55.477678)
					(end 90.694764 -55.251604)
				)
				(arc
					(start 90.694764 -55.249064)
					(mid 90.923364 -55.020464)
					(end 91.151964 -55.249064)
				)
				(xy 91.574874 -55.249064) (xy 91.581732 -55.244746)
				(arc
					(start 91.580462 -55.242714)
					(mid 91.697955 -55.118499)
					(end 91.741498 -54.953154)
				)
				(arc
					(start 91.624658 -54.953154)
					(mid 91.396058 -55.179228)
					(end 91.167458 -54.953154)
				)
				(arc
					(start 91.167458 -54.950614)
					(mid 91.396058 -54.722014)
					(end 91.624658 -54.950614)
				)
			)
		)
	)
	(zone
		(layers "B.Cu" "In4.Cu" "In7.Cu" "In9.Cu")
		(hatch none 0.5)
		(connect_pads
			(clearance 0)
		)
		(min_thickness 0.25)
		(keepout
			(tracks not_allowed)
			(vias allowed)
			(pads allowed)
			(copperpour not_allowed)
			(footprints allowed)
		)
		(placement
			(enabled no)
			(sheetname "")
		)
		(fill yes
			(thermal_gap 0.5)
			(thermal_bridge_width 0.5)
			(island_removal_mode 0)
		)
		(polygon
			(pts
				(arc
					(start 86.443058 -53.20157)
					(mid 86.100793 -52.856145)
					(end 85.752178 -53.19522)
				)
				(arc
					(start 85.741764 -53.758592)
					(mid 86.080727 -54.110638)
					(end 86.432644 -53.771546)
				)
				(xy 86.432644 -53.767736)
				(arc
					(start 86.315804 -53.767736)
					(mid 86.087204 -53.99381)
					(end 85.858604 -53.767736)
				)
				(arc
					(start 85.858604 -53.765196)
					(mid 86.087204 -53.536596)
					(end 86.315804 -53.765196)
				)
				(xy 86.432644 -53.765196) (xy 86.443058 -53.20792) (xy 86.443058 -53.20411)
				(arc
					(start 86.326218 -53.20411)
					(mid 86.097618 -53.430184)
					(end 85.869018 -53.20411)
				)
				(arc
					(start 85.869018 -53.20157)
					(mid 86.097618 -52.97297)
					(end 86.326218 -53.20157)
				)
			)
		)
	)
	(zone
		(layers "B.Cu" "In4.Cu" "In7.Cu" "In9.Cu")
		(hatch none 0.5)
		(connect_pads
			(clearance 0)
		)
		(min_thickness 0.25)
		(keepout
			(tracks not_allowed)
			(vias allowed)
			(pads allowed)
			(copperpour not_allowed)
			(footprints allowed)
		)
		(placement
			(enabled no)
			(sheetname "")
		)
		(fill yes
			(thermal_gap 0.5)
			(thermal_bridge_width 0.5)
			(island_removal_mode 0)
		)
		(polygon
			(pts
				(arc
					(start 80.9117 -54.1274)
					(mid 80.5688 -53.7845)
					(end 80.2259 -54.1274)
				)
				(arc
					(start 80.2259 -54.685946)
					(mid 80.567403 -55.029097)
					(end 80.9117 -54.68874)
				)
				(arc
					(start 80.7974 -54.68874)
					(mid 80.5688 -54.914814)
					(end 80.3402 -54.68874)
				)
				(arc
					(start 80.3402 -54.6862)
					(mid 80.5688 -54.4576)
					(end 80.7974 -54.6862)
				)
				(xy 80.9117 -54.6862) (xy 80.9117 -54.12994)
				(arc
					(start 80.7974 -54.12994)
					(mid 80.5688 -54.356014)
					(end 80.3402 -54.12994)
				)
				(arc
					(start 80.3402 -54.1274)
					(mid 80.5688 -53.8988)
					(end 80.7974 -54.1274)
				)
			)
		)
	)
	(zone
		(layers "B.Cu" "In4.Cu" "In7.Cu" "In9.Cu")
		(hatch none 0.5)
		(connect_pads
			(clearance 0)
		)
		(min_thickness 0.25)
		(keepout
			(tracks not_allowed)
			(vias allowed)
			(pads allowed)
			(copperpour not_allowed)
			(footprints allowed)
		)
		(placement
			(enabled no)
			(sheetname "")
		)
		(fill yes
			(thermal_gap 0.5)
			(thermal_bridge_width 0.5)
			(island_removal_mode 0)
		)
		(polygon
			(pts
				(arc
					(start 87.528908 -54.27726)
					(mid 87.186896 -53.931837)
					(end 86.838028 -54.270402)
				)
				(arc
					(start 86.826852 -54.834028)
					(mid 87.165307 -55.186583)
					(end 87.517732 -54.847998)
				)
				(xy 87.517732 -54.84368)
				(arc
					(start 87.400892 -54.84368)
					(mid 87.172292 -55.069754)
					(end 86.943692 -54.84368)
				)
				(arc
					(start 86.943692 -54.84114)
					(mid 87.172292 -54.61254)
					(end 87.400892 -54.84114)
				)
				(xy 87.517986 -54.84114) (xy 87.528908 -54.284118) (xy 87.528908 -54.2798)
				(arc
					(start 87.412068 -54.2798)
					(mid 87.183468 -54.505874)
					(end 86.954868 -54.2798)
				)
				(arc
					(start 86.954868 -54.27726)
					(mid 87.183468 -54.04866)
					(end 87.412068 -54.27726)
				)
			)
		)
	)
	(zone
		(layers "B.Cu" "In4.Cu" "In7.Cu" "In9.Cu")
		(hatch none 0.5)
		(connect_pads
			(clearance 0)
		)
		(min_thickness 0.25)
		(keepout
			(tracks not_allowed)
			(vias allowed)
			(pads allowed)
			(copperpour not_allowed)
			(footprints allowed)
		)
		(placement
			(enabled no)
			(sheetname "")
		)
		(fill yes
			(thermal_gap 0.5)
			(thermal_bridge_width 0.5)
			(island_removal_mode 0)
		)
		(polygon
			(pts
				(arc
					(start 83.389216 -10.02919)
					(mid 83.005422 -10.412603)
					(end 83.388962 -10.79627)
				)
				(arc
					(start 84.310474 -10.79627)
					(mid 84.580778 -10.68483)
					(end 84.694014 -10.41527)
				)
				(arc
					(start 84.577174 -10.41527)
					(mid 84.310474 -10.679442)
					(end 84.043774 -10.41527)
				)
				(arc
					(start 83.655662 -10.41527)
					(mid 83.388962 -10.679442)
					(end 83.122262 -10.41527)
				)
				(arc
					(start 83.122262 -10.41273)
					(mid 83.388962 -10.14603)
					(end 83.655662 -10.41273)
				)
				(arc
					(start 84.043774 -10.41273)
					(mid 84.310474 -10.14603)
					(end 84.577174 -10.41273)
				)
				(arc
					(start 84.694014 -10.41273)
					(mid 84.581678 -10.141526)
					(end 84.310474 -10.02919)
				)
			)
		)
	)
	(zone
		(layer "In1.Cu")
		(hatch none 0.5)
		(connect_pads
			(clearance 0)
		)
		(min_thickness 0.25)
		(keepout
			(tracks not_allowed)
			(vias allowed)
			(pads allowed)
			(copperpour not_allowed)
			(footprints allowed)
		)
		(placement
			(enabled no)
			(sheetname "")
		)
		(fill
			(thermal_gap 0.5)
			(thermal_bridge_width 0.5)
			(island_removal_mode 0)
		)
		(polygon
			(pts
				(xy 75.99172 -4.097528) (xy 76.708 -4.097528) (xy 76.708 -8.293608) (xy 75.99172 -8.293608)
			)
		)
	)
	(zone
		(net "GND")
		(layer "In1.Cu")
		(hatch none 0.5)
		(connect_pads
			(clearance 0.5)
		)
		(min_thickness 0.25)
		(fill yes
			(thermal_gap 0.5)
			(thermal_bridge_width 0.5)
			(island_removal_mode 0)
		)
		(polygon
			(pts
				(arc
					(start 106.000042 -0.763016)
					(mid 105.83247 -0.832426)
					(end 105.76306 -0.999998)
				)
				(arc
					(start 105.76306 -10.700004)
					(mid 105.246685 -11.946643)
					(end 104.000046 -12.463018)
				)
				(arc
					(start 100.000054 -12.463018)
					(mid 98.753415 -11.946643)
					(end 98.23704 -10.700004)
				)
				(xy 98.23704 -5.244592) (xy 97.448624 -5.244592) (xy 88.562942 -5.244592)
				(arc
					(start 88.562942 -10.150094)
					(mid 86.849966 -11.86307)
					(end 85.13699 -10.150094)
				)
				(xy 85.13699 -5.244592) (xy 84.707984 -5.244592) (xy 84.707984 -8.293608) (xy 83.991704 -8.293608)
				(xy 83.991704 -5.244592) (xy 83.707986 -5.244592) (xy 83.707986 -8.293608) (xy 82.991706 -8.293608)
				(xy 82.991706 -5.244592) (xy 80.707992 -5.244592) (xy 80.707992 -8.293608) (xy 79.991712 -8.293608)
				(xy 79.991712 -5.244592) (xy 79.707994 -5.244592) (xy 79.707994 -8.293608) (xy 78.991714 -8.293608)
				(xy 78.991714 -5.244592) (xy 76.708 -5.244592) (xy 76.708 -8.293608) (xy 75.99172 -8.293608) (xy 75.99172 -5.244592)
				(xy 75.708002 -5.244592) (xy 75.708002 -8.293608) (xy 74.991722 -8.293608) (xy 74.991722 -5.244592)
				(xy 72.708008 -5.244592) (xy 72.708008 -8.293608) (xy 71.991728 -8.293608) (xy 71.991728 -5.244592)
				(xy 71.70801 -5.244592) (xy 71.70801 -8.293608) (xy 70.99173 -8.293608) (xy 70.99173 -5.244592)
				(xy 68.708016 -5.244592) (xy 68.708016 -8.293608) (xy 67.991736 -8.293608) (xy 67.991736 -5.244592)
				(xy 67.708018 -5.244592) (xy 67.708018 -8.293608) (xy 66.991738 -8.293608) (xy 66.991738 -5.244592)
				(xy 64.708024 -5.244592) (xy 64.708024 -8.293608) (xy 63.991744 -8.293608) (xy 63.991744 -5.244592)
				(xy 63.708026 -5.244592) (xy 63.708026 -8.293608) (xy 62.991746 -8.293608) (xy 62.991746 -5.244592)
				(xy 60.708032 -5.244592) (xy 60.708032 -8.293608) (xy 59.991752 -8.293608) (xy 59.991752 -5.244592)
				(xy 59.708034 -5.244592) (xy 59.708034 -8.293608) (xy 58.991754 -8.293608) (xy 58.991754 -5.244592)
				(xy 52.708048 -5.244592) (xy 52.708048 -8.293608) (xy 51.991768 -8.293608) (xy 51.991768 -5.244592)
				(xy 51.70805 -5.244592) (xy 51.70805 -8.293608) (xy 50.99177 -8.293608) (xy 50.99177 -5.244592)
				(xy 48.708056 -5.244592) (xy 48.708056 -8.293608) (xy 47.991776 -8.293608) (xy 47.991776 -5.244592)
				(xy 47.708058 -5.244592) (xy 47.708058 -8.293608) (xy 46.991778 -8.293608) (xy 46.991778 -5.244592)
				(xy 44.708064 -5.244592) (xy 44.708064 -8.293608) (xy 43.991784 -8.293608) (xy 43.991784 -5.244592)
				(xy 43.708066 -5.244592) (xy 43.708066 -8.293608) (xy 42.991786 -8.293608) (xy 42.991786 -5.244592)
				(xy 40.708072 -5.244592) (xy 40.708072 -8.293608) (xy 39.991792 -8.293608) (xy 39.991792 -5.244592)
				(xy 39.708074 -5.244592) (xy 39.708074 -8.293608) (xy 38.991794 -8.293608) (xy 38.991794 -5.244592)
				(xy 36.70808 -5.244592) (xy 36.70808 -8.293608) (xy 35.9918 -8.293608) (xy 35.9918 -5.244592) (xy 35.708082 -5.244592)
				(xy 35.708082 -8.293608) (xy 34.991802 -8.293608) (xy 34.991802 -5.244592) (xy 32.708088 -5.244592)
				(xy 32.708088 -8.293608) (xy 31.991808 -8.293608) (xy 31.991808 -5.244592) (xy 31.70809 -5.244592)
				(xy 31.70809 -8.293608) (xy 30.99181 -8.293608) (xy 30.99181 -5.244592) (xy 28.708096 -5.244592)
				(xy 28.708096 -8.293608) (xy 27.991816 -8.293608) (xy 27.991816 -5.244592) (xy 27.708098 -5.244592)
				(xy 27.708098 -8.293608) (xy 26.991818 -8.293608) (xy 26.991818 -5.244592) (xy 24.708104 -5.244592)
				(xy 24.708104 -8.293608) (xy 23.991824 -8.293608) (xy 23.991824 -5.244592) (xy 23.708106 -5.244592)
				(xy 23.708106 -8.293608) (xy 22.991826 -8.293608) (xy 22.991826 -5.244592) (xy 20.708112 -5.244592)
				(xy 20.708112 -8.293608) (xy 19.991832 -8.293608) (xy 19.991832 -5.244592) (xy 19.708114 -5.244592)
				(xy 19.708114 -8.293608) (xy 18.991834 -8.293608) (xy 18.991834 -5.244592) (xy 15.463012 -5.244592)
				(arc
					(start 15.463012 -13.699998)
					(mid 14.946637 -14.946637)
					(end 13.699998 -15.463012)
				)
				(arc
					(start 0.999998 -15.463012)
					(mid 0.832426 -15.532422)
					(end 0.763016 -15.699994)
				)
				(arc
					(start 0.763016 -72.799956)
					(mid 0.832426 -72.967528)
					(end 0.999998 -73.036938)
				)
				(arc
					(start 209.00009 -73.036938)
					(mid 209.167662 -72.967528)
					(end 209.237072 -72.799956)
				)
				(arc
					(start 209.237072 -0.999998)
					(mid 209.167662 -0.832426)
					(end 209.00009 -0.763016)
				)
				(xy 169.9895 -0.763016) (xy 169.9895 -3.604006) (xy 170.7515 -4.366006) (xy 170.7515 -5.031994)
				(xy 170.2435 -5.539994) (xy 170.2435 -10.111994) (xy 167.337994 -13.0175) (xy 156.512006 -13.0175)
				(xy 156.0195 -12.524994) (xy 156.0195 -10.873994) (xy 155.5115 -10.365994) (xy 155.5115 -0.763016)
			)
		)
		(polygon
			(pts
				(arc
					(start 2.31394 -66.220848)
					(mid 1.930273 -65.837562)
					(end 1.54686 -66.221102)
				)
				(arc
					(start 1.54686 -67.178682)
					(mid 1.9304 -67.562222)
					(end 2.31394 -67.178682)
				)
			)
		)
		(polygon
			(pts
				(arc
					(start 9.12114 -65.2018)
					(mid 9.105517 -65.164083)
					(end 9.0678 -65.14846)
				)
				(arc
					(start 8.7122 -65.14846)
					(mid 8.674483 -65.164083)
					(end 8.65886 -65.2018)
				)
				(arc
					(start 8.65886 -65.6082)
					(mid 8.674483 -65.645917)
					(end 8.7122 -65.66154)
				)
				(arc
					(start 9.0678 -65.66154)
					(mid 9.105517 -65.645917)
					(end 9.12114 -65.6082)
				)
			)
		)
		(polygon
			(pts
				(arc
					(start 8.35914 -65.2018)
					(mid 8.343517 -65.164083)
					(end 8.3058 -65.14846)
				)
				(arc
					(start 7.9502 -65.14846)
					(mid 7.912483 -65.164083)
					(end 7.89686 -65.2018)
				)
				(arc
					(start 7.89686 -65.6082)
					(mid 7.912483 -65.645917)
					(end 7.9502 -65.66154)
				)
				(arc
					(start 8.3058 -65.66154)
					(mid 8.343517 -65.645917)
					(end 8.35914 -65.6082)
				)
			)
		)
		(polygon
			(pts
				(arc
					(start 3.8354 -64.7065)
					(mid 3.451733 -64.323214)
					(end 3.06832 -64.706754)
				)
				(arc
					(start 3.06832 -65.664334)
					(mid 3.45186 -66.047874)
					(end 3.8354 -65.664334)
				)
			)
		)
		(polygon
			(pts
				(arc
					(start 9.12114 -64.3128)
					(mid 9.105517 -64.275083)
					(end 9.0678 -64.25946)
				)
				(arc
					(start 8.7122 -64.25946)
					(mid 8.674483 -64.275083)
					(end 8.65886 -64.3128)
				)
				(arc
					(start 8.65886 -64.7192)
					(mid 8.674483 -64.756917)
					(end 8.7122 -64.77254)
				)
				(arc
					(start 9.0678 -64.77254)
					(mid 9.105517 -64.756917)
					(end 9.12114 -64.7192)
				)
			)
		)
		(polygon
			(pts
				(arc
					(start 8.35914 -64.3128)
					(mid 8.343517 -64.275083)
					(end 8.3058 -64.25946)
				)
				(arc
					(start 7.9502 -64.25946)
					(mid 7.912483 -64.275083)
					(end 7.89686 -64.3128)
				)
				(arc
					(start 7.89686 -64.7192)
					(mid 7.912483 -64.756917)
					(end 7.9502 -64.77254)
				)
				(arc
					(start 8.3058 -64.77254)
					(mid 8.343517 -64.756917)
					(end 8.35914 -64.7192)
				)
			)
		)
		(polygon
			(pts
				(arc
					(start 10.01014 -64.515746)
					(mid 9.626473 -64.13246)
					(end 9.24306 -64.516)
				)
				(arc
					(start 9.24306 -65.405)
					(mid 9.6266 -65.78854)
					(end 10.01014 -65.405)
				)
			)
		)
		(polygon
			(pts
				(arc
					(start 9.12114 -63.4238)
					(mid 9.105517 -63.386083)
					(end 9.0678 -63.37046)
				)
				(arc
					(start 8.7122 -63.37046)
					(mid 8.674483 -63.386083)
					(end 8.65886 -63.4238)
				)
				(arc
					(start 8.65886 -63.8302)
					(mid 8.674483 -63.867917)
					(end 8.7122 -63.88354)
				)
				(arc
					(start 9.0678 -63.88354)
					(mid 9.105517 -63.867917)
					(end 9.12114 -63.8302)
				)
			)
		)
		(polygon
			(pts
				(arc
					(start 8.35914 -63.4238)
					(mid 8.343517 -63.386083)
					(end 8.3058 -63.37046)
				)
				(arc
					(start 7.9502 -63.37046)
					(mid 7.912483 -63.386083)
					(end 7.89686 -63.4238)
				)
				(arc
					(start 7.89686 -63.8302)
					(mid 7.912483 -63.867917)
					(end 7.9502 -63.88354)
				)
				(arc
					(start 8.3058 -63.88354)
					(mid 8.343517 -63.867917)
					(end 8.35914 -63.8302)
				)
			)
		)
		(polygon
			(pts
				(arc
					(start 2.31394 -63.221108)
					(mid 1.9304 -62.837568)
					(end 1.54686 -63.221108)
				)
				(arc
					(start 1.54686 -64.178942)
					(mid 1.930527 -64.562228)
					(end 2.31394 -64.178688)
				)
			)
		)
		(polygon
			(pts
				(arc
					(start 9.12114 -62.5348)
					(mid 9.105517 -62.497083)
					(end 9.0678 -62.48146)
				)
				(arc
					(start 8.7122 -62.48146)
					(mid 8.674483 -62.497083)
					(end 8.65886 -62.5348)
				)
				(arc
					(start 8.65886 -62.9412)
					(mid 8.674483 -62.978917)
					(end 8.7122 -62.99454)
				)
				(arc
					(start 9.0678 -62.99454)
					(mid 9.105517 -62.978917)
					(end 9.12114 -62.9412)
				)
			)
		)
		(polygon
			(pts
				(arc
					(start 8.35914 -62.5348)
					(mid 8.343517 -62.497083)
					(end 8.3058 -62.48146)
				)
				(arc
					(start 7.9502 -62.48146)
					(mid 7.912483 -62.497083)
					(end 7.89686 -62.5348)
				)
				(arc
					(start 7.89686 -62.9412)
					(mid 7.912483 -62.978917)
					(end 7.9502 -62.99454)
				)
				(arc
					(start 8.3058 -62.99454)
					(mid 8.343517 -62.978917)
					(end 8.35914 -62.9412)
				)
			)
		)
		(polygon
			(pts
				(arc
					(start 10.009886 -62.727078)
					(mid 9.615678 -62.354714)
					(end 9.243314 -62.748922)
				)
				(xy 9.240774 -62.748922) (xy 9.266174 -63.637668) (xy 9.266428 -63.637922)
				(arc
					(start 9.268714 -63.637922)
					(mid 9.662922 -64.010286)
					(end 10.035286 -63.616078)
				)
				(xy 10.037826 -63.616078) (xy 10.012426 -62.727078)
			)
		)
		(polygon
			(pts
				(arc
					(start 9.12114 -61.6458)
					(mid 9.105517 -61.608083)
					(end 9.0678 -61.59246)
				)
				(arc
					(start 8.7122 -61.59246)
					(mid 8.674483 -61.608083)
					(end 8.65886 -61.6458)
				)
				(arc
					(start 8.65886 -62.0522)
					(mid 8.674483 -62.089917)
					(end 8.7122 -62.10554)
				)
				(arc
					(start 9.0678 -62.10554)
					(mid 9.105517 -62.089917)
					(end 9.12114 -62.0522)
				)
			)
		)
		(polygon
			(pts
				(arc
					(start 8.35914 -61.6458)
					(mid 8.343517 -61.608083)
					(end 8.3058 -61.59246)
				)
				(arc
					(start 7.9502 -61.59246)
					(mid 7.912483 -61.608083)
					(end 7.89686 -61.6458)
				)
				(arc
					(start 7.89686 -62.0522)
					(mid 7.912483 -62.089917)
					(end 7.9502 -62.10554)
				)
				(arc
					(start 8.3058 -62.10554)
					(mid 8.343517 -62.089917)
					(end 8.35914 -62.0522)
				)
			)
		)
		(polygon
			(pts
				(arc
					(start 101.734366 -61.66993)
					(mid 101.189299 -61.660676)
					(end 101.185472 -62.20587)
				)
				(arc
					(start 101.795072 -62.817756)
					(mid 102.337616 -62.818772)
					(end 102.338632 -62.276228)
				)
			)
		)
		(polygon
			(pts
				(arc
					(start 3.8354 -61.706506)
					(mid 3.451733 -61.32322)
					(end 3.06832 -61.70676)
				)
				(arc
					(start 3.06832 -62.66434)
					(mid 3.45186 -63.04788)
					(end 3.8354 -62.66434)
				)
			)
		)
		(polygon
			(pts
				(arc
					(start 9.12114 -60.7568)
					(mid 9.105517 -60.719083)
					(end 9.0678 -60.70346)
				)
				(arc
					(start 8.7122 -60.70346)
					(mid 8.674483 -60.719083)
					(end 8.65886 -60.7568)
				)
				(arc
					(start 8.65886 -61.1632)
					(mid 8.674483 -61.200917)
					(end 8.7122 -61.21654)
				)
				(arc
					(start 9.0678 -61.21654)
					(mid 9.105517 -61.200917)
					(end 9.12114 -61.1632)
				)
			)
		)
		(polygon
			(pts
				(arc
					(start 8.35914 -60.7568)
					(mid 8.343517 -60.719083)
					(end 8.3058 -60.70346)
				)
				(arc
					(start 7.9502 -60.70346)
					(mid 7.912483 -60.719083)
					(end 7.89686 -60.7568)
				)
				(arc
					(start 7.89686 -61.1632)
					(mid 7.912483 -61.200917)
					(end 7.9502 -61.21654)
				)
				(arc
					(start 8.3058 -61.21654)
					(mid 8.343517 -61.200917)
					(end 8.35914 -61.1632)
				)
			)
		)
		(polygon
			(pts
				(arc
					(start 10.01014 -60.959746)
					(mid 9.626473 -60.57646)
					(end 9.24306 -60.96)
				)
				(arc
					(start 9.24306 -61.849)
					(mid 9.6266 -62.23254)
					(end 10.01014 -61.849)
				)
			)
		)
		(polygon
			(pts
				(arc
					(start 99.781106 -60.369704)
					(mid 99.238816 -60.378086)
					(end 99.247198 -60.920376)
				)
				(xy 99.24542 -60.922154) (xy 99.86518 -61.523372) (xy 99.865434 -61.523372)
				(arc
					(start 99.866958 -61.521848)
					(mid 100.409565 -61.513655)
					(end 100.40112 -60.971176)
				)
				(xy 100.402898 -60.969398) (xy 99.782884 -60.367926)
			)
		)
		(polygon
			(pts
				(arc
					(start 81.0514 -60.7187)
					(mid 81.3943 -60.3758)
					(end 81.0514 -60.0329)
				)
				(arc
					(start 80.263746 -60.0329)
					(mid 79.9211 -60.375927)
					(end 80.264 -60.7187)
				)
			)
		)
		(polygon
			(pts
				(arc
					(start 2.31394 -60.22086)
					(mid 1.930273 -59.837574)
					(end 1.54686 -60.221114)
				)
				(arc
					(start 1.54686 -61.178694)
					(mid 1.9304 -61.562234)
					(end 2.31394 -61.178694)
				)
			)
		)
		(polygon
			(pts
				(arc
					(start 9.12114 -59.8678)
					(mid 9.105517 -59.830083)
					(end 9.0678 -59.81446)
				)
				(arc
					(start 8.7122 -59.81446)
					(mid 8.674483 -59.830083)
					(end 8.65886 -59.8678)
				)
				(arc
					(start 8.65886 -60.2742)
					(mid 8.674483 -60.311917)
					(end 8.7122 -60.32754)
				)
				(arc
					(start 9.0678 -60.32754)
					(mid 9.105517 -60.311917)
					(end 9.12114 -60.2742)
				)
			)
		)
		(polygon
			(pts
				(arc
					(start 8.35914 -59.8678)
					(mid 8.343517 -59.830083)
					(end 8.3058 -59.81446)
				)
				(arc
					(start 7.9502 -59.81446)
					(mid 7.912483 -59.830083)
					(end 7.89686 -59.8678)
				)
				(arc
					(start 7.89686 -60.2742)
					(mid 7.912483 -60.311917)
					(end 7.9502 -60.32754)
				)
				(arc
					(start 8.3058 -60.32754)
					(mid 8.343517 -60.311917)
					(end 8.35914 -60.2742)
				)
			)
		)
		(polygon
			(pts
				(arc
					(start 84.348828 -59.595258)
					(mid 84.354625 -59.108766)
					(end 83.868006 -59.106054)
				)
				(arc
					(start 83.309968 -59.661806)
					(mid 83.308952 -60.146946)
					(end 83.794092 -60.147962)
				)
			)
		)
		(polygon
			(pts
				(arc
					(start 9.12114 -58.9788)
					(mid 9.105517 -58.941083)
					(end 9.0678 -58.92546)
				)
				(arc
					(start 8.7122 -58.92546)
					(mid 8.674483 -58.941083)
					(end 8.65886 -58.9788)
				)
				(arc
					(start 8.65886 -59.3852)
					(mid 8.674483 -59.422917)
					(end 8.7122 -59.43854)
				)
				(arc
					(start 9.0678 -59.43854)
					(mid 9.105517 -59.422917)
					(end 9.12114 -59.3852)
				)
			)
		)
		(polygon
			(pts
				(arc
					(start 8.35914 -58.9788)
					(mid 8.343517 -58.941083)
					(end 8.3058 -58.92546)
				)
				(arc
					(start 7.9502 -58.92546)
					(mid 7.912483 -58.941083)
					(end 7.89686 -58.9788)
				)
				(arc
					(start 7.89686 -59.3852)
					(mid 7.912483 -59.422917)
					(end 7.9502 -59.43854)
				)
				(arc
					(start 8.3058 -59.43854)
					(mid 8.343517 -59.422917)
					(end 8.35914 -59.3852)
				)
			)
		)
		(polygon
			(pts
				(arc
					(start 10.009886 -59.171078)
					(mid 9.615678 -58.798714)
					(end 9.243314 -59.192922)
				)
				(xy 9.240774 -59.192922) (xy 9.266174 -60.081668) (xy 9.266428 -60.081922)
				(arc
					(start 9.268714 -60.081922)
					(mid 9.662922 -60.454286)
					(end 10.035286 -60.060078)
				)
				(xy 10.037826 -60.060078) (xy 10.012426 -59.171078)
			)
		)
		(polygon
			(pts
				(xy 150.065994 -58.7375) (xy 148.003006 -58.7375) (xy 147.6375 -59.103006) (xy 147.6375 -61.292994)
				(xy 148.2725 -61.927994) (xy 148.2725 -71.579994) (xy 148.638006 -71.9455) (xy 162.638994 -71.9455)
				(xy 162.7505 -71.833994) (xy 163.0045 -71.579994) (xy 163.0045 -62.532006) (xy 160.225994 -59.7535)
				(xy 151.081994 -59.7535)
			)
		)
		(polygon
			(pts
				(arc
					(start 3.7084 -58.706766)
					(mid 3.32486 -58.323226)
					(end 2.94132 -58.706766)
				)
				(arc
					(start 2.94132 -59.6646)
					(mid 3.324987 -60.047886)
					(end 3.7084 -59.664346)
				)
			)
		)
		(polygon
			(pts
				(arc
					(start 9.12114 -58.0898)
					(mid 9.105517 -58.052083)
					(end 9.0678 -58.03646)
				)
				(arc
					(start 8.7122 -58.03646)
					(mid 8.674483 -58.052083)
					(end 8.65886 -58.0898)
				)
				(arc
					(start 8.65886 -58.4962)
					(mid 8.674483 -58.533917)
					(end 8.7122 -58.54954)
				)
				(arc
					(start 9.0678 -58.54954)
					(mid 9.105517 -58.533917)
					(end 9.12114 -58.4962)
				)
			)
		)
		(polygon
			(pts
				(arc
					(start 8.35914 -58.0898)
					(mid 8.343517 -58.052083)
					(end 8.3058 -58.03646)
				)
				(arc
					(start 7.9502 -58.03646)
					(mid 7.912483 -58.052083)
					(end 7.89686 -58.0898)
				)
				(arc
					(start 7.89686 -58.4962)
					(mid 7.912483 -58.533917)
					(end 7.9502 -58.54954)
				)
				(arc
					(start 8.3058 -58.54954)
					(mid 8.343517 -58.533917)
					(end 8.35914 -58.4962)
				)
			)
		)
		(polygon
			(pts
				(arc
					(start 9.12114 -57.2008)
					(mid 9.105517 -57.163083)
					(end 9.0678 -57.14746)
				)
				(arc
					(start 8.7122 -57.14746)
					(mid 8.674483 -57.163083)
					(end 8.65886 -57.2008)
				)
				(arc
					(start 8.65886 -57.6072)
					(mid 8.674483 -57.644917)
					(end 8.7122 -57.66054)
				)
				(arc
					(start 9.0678 -57.66054)
					(mid 9.105517 -57.644917)
					(end 9.12114 -57.6072)
				)
			)
		)
		(polygon
			(pts
				(arc
					(start 8.35914 -57.2008)
					(mid 8.343517 -57.163083)
					(end 8.3058 -57.14746)
				)
				(arc
					(start 7.9502 -57.14746)
					(mid 7.912483 -57.163083)
					(end 7.89686 -57.2008)
				)
				(arc
					(start 7.89686 -57.6072)
					(mid 7.912483 -57.644917)
					(end 7.9502 -57.66054)
				)
				(arc
					(start 8.3058 -57.66054)
					(mid 8.343517 -57.644917)
					(end 8.35914 -57.6072)
				)
			)
		)
		(polygon
			(pts
				(arc
					(start 10.01014 -57.403746)
					(mid 9.626473 -57.02046)
					(end 9.24306 -57.404)
				)
				(arc
					(start 9.24306 -58.293)
					(mid 9.6266 -58.67654)
					(end 10.01014 -58.293)
				)
			)
		)
		(polygon
			(pts
				(arc
					(start 9.12114 -56.3118)
					(mid 9.105517 -56.274083)
					(end 9.0678 -56.25846)
				)
				(arc
					(start 8.7122 -56.25846)
					(mid 8.674483 -56.274083)
					(end 8.65886 -56.3118)
				)
				(arc
					(start 8.65886 -56.7182)
					(mid 8.674483 -56.755917)
					(end 8.7122 -56.77154)
				)
				(arc
					(start 9.0678 -56.77154)
					(mid 9.105517 -56.755917)
					(end 9.12114 -56.7182)
				)
			)
		)
		(polygon
			(pts
				(arc
					(start 8.35914 -56.3118)
					(mid 8.343517 -56.274083)
					(end 8.3058 -56.25846)
				)
				(arc
					(start 7.9502 -56.25846)
					(mid 7.912483 -56.274083)
					(end 7.89686 -56.3118)
				)
				(arc
					(start 7.89686 -56.7182)
					(mid 7.912483 -56.755917)
					(end 7.9502 -56.77154)
				)
				(arc
					(start 8.3058 -56.77154)
					(mid 8.343517 -56.755917)
					(end 8.35914 -56.7182)
				)
			)
		)
		(polygon
			(pts
				(arc
					(start 9.12114 -55.4228)
					(mid 9.105517 -55.385083)
					(end 9.0678 -55.36946)
				)
				(arc
					(start 8.7122 -55.36946)
					(mid 8.674483 -55.385083)
					(end 8.65886 -55.4228)
				)
				(arc
					(start 8.65886 -55.8292)
					(mid 8.674483 -55.866917)
					(end 8.7122 -55.88254)
				)
				(arc
					(start 9.0678 -55.88254)
					(mid 9.105517 -55.866917)
					(end 9.12114 -55.8292)
				)
			)
		)
		(polygon
			(pts
				(arc
					(start 8.35914 -55.4228)
					(mid 8.343517 -55.385083)
					(end 8.3058 -55.36946)
				)
				(arc
					(start 7.9502 -55.36946)
					(mid 7.912483 -55.385083)
					(end 7.89686 -55.4228)
				)
				(arc
					(start 7.89686 -55.8292)
					(mid 7.912483 -55.866917)
					(end 7.9502 -55.88254)
				)
				(arc
					(start 8.3058 -55.88254)
					(mid 8.343517 -55.866917)
					(end 8.35914 -55.8292)
				)
			)
		)
		(polygon
			(pts
				(arc
					(start 10.01014 -55.625746)
					(mid 9.626473 -55.24246)
					(end 9.24306 -55.626)
				)
				(arc
					(start 9.24306 -56.515)
					(mid 9.6266 -56.89854)
					(end 10.01014 -56.515)
				)
			)
		)
		(polygon
			(pts
				(arc
					(start 83.701636 -55.68061)
					(mid 83.668625 -55.193446)
					(end 83.18119 -55.226204)
				)
				(arc
					(start 82.803746 -55.65902)
					(mid 82.83702 -56.146446)
					(end 83.324446 -56.113172)
				)
			)
		)
		(polygon
			(pts
				(arc
					(start 91.580462 -55.242714)
					(mid 91.688158 -54.76621)
					(end 91.211654 -54.658514)
				)
				(xy 91.210384 -54.656482) (xy 90.73769 -54.954678) (xy 90.73769 -54.954932)
				(arc
					(start 90.73896 -54.956964)
					(mid 90.631264 -55.433468)
					(end 91.107768 -55.541164)
				)
				(xy 91.109038 -55.543196) (xy 91.581732 -55.244746)
			)
		)
		(polygon
			(pts
				(arc
					(start 86.030054 -54.801008)
					(mid 85.689948 -54.450234)
					(end 85.339174 -54.79034)
				)
				(arc
					(start 85.330538 -55.356506)
					(mid 85.670517 -55.707536)
					(end 86.021418 -55.367428)
				)
			)
		)
		(polygon
			(pts
				(arc
					(start 87.528908 -54.284118)
					(mid 87.190326 -53.93182)
					(end 86.838028 -54.270402)
				)
				(arc
					(start 86.826852 -54.834028)
					(mid 87.165307 -55.186583)
					(end 87.517732 -54.847998)
				)
			)
		)
		(polygon
			(pts
				(arc
					(start 80.9117 -54.1274)
					(mid 80.5688 -53.7845)
					(end 80.2259 -54.1274)
				)
				(arc
					(start 80.2259 -54.686454)
					(mid 80.568927 -55.0291)
					(end 80.9117 -54.6862)
				)
			)
		)
		(polygon
			(pts
				(arc
					(start 12.75334 -53.8226)
					(mid 12.737717 -53.784883)
					(end 12.7 -53.76926)
				)
				(arc
					(start 12.3444 -53.76926)
					(mid 12.306683 -53.784883)
					(end 12.29106 -53.8226)
				)
				(arc
					(start 12.29106 -54.229)
					(mid 12.306683 -54.266717)
					(end 12.3444 -54.28234)
				)
				(arc
					(start 12.7 -54.28234)
					(mid 12.737717 -54.266717)
					(end 12.75334 -54.229)
				)
			)
		)
		(polygon
			(pts
				(arc
					(start 11.99134 -53.8226)
					(mid 11.975717 -53.784883)
					(end 11.938 -53.76926)
				)
				(arc
					(start 11.5824 -53.76926)
					(mid 11.544683 -53.784883)
					(end 11.52906 -53.8226)
				)
				(arc
					(start 11.52906 -54.229)
					(mid 11.544683 -54.266717)
					(end 11.5824 -54.28234)
				)
				(arc
					(start 11.938 -54.28234)
					(mid 11.975717 -54.266717)
					(end 11.99134 -54.229)
				)
			)
		)
		(polygon
			(pts
				(arc
					(start 11.22934 -53.8226)
					(mid 11.213717 -53.784883)
					(end 11.176 -53.76926)
				)
				(arc
					(start 10.8204 -53.76926)
					(mid 10.782683 -53.784883)
					(end 10.76706 -53.8226)
				)
				(arc
					(start 10.76706 -54.229)
					(mid 10.782683 -54.266717)
					(end 10.8204 -54.28234)
				)
				(arc
					(start 11.176 -54.28234)
					(mid 11.213717 -54.266717)
					(end 11.22934 -54.229)
				)
			)
		)
		(polygon
			(pts
				(arc
					(start 84.586572 -54.022498)
					(mid 84.247863 -53.670456)
					(end 83.895692 -54.009036)
				)
				(arc
					(start 83.885024 -54.567836)
					(mid 84.22386 -54.91988)
					(end 84.575904 -54.581044)
				)
			)
		)
		(polygon
			(pts
				(arc
					(start 10.2616 -53.66766)
					(mid 10.2616 -54.38394)
					(end 10.2616 -53.66766)
				)
			)
		)
		(polygon
			(pts
				(arc
					(start 90.156792 -53.552598)
					(mid 89.845768 -53.175928)
					(end 89.46896 -53.486812)
				)
				(arc
					(start 89.415874 -54.043326)
					(mid 89.727024 -54.420008)
					(end 90.103706 -54.108858)
				)
			)
		)
		(polygon
			(pts
				(arc
					(start 88.633808 -53.399182)
					(mid 88.277446 -53.065172)
					(end 87.943436 -53.421534)
				)
				(xy 87.940896 -53.421534) (xy 87.95893 -53.98008)
				(arc
					(start 87.96147 -53.98008)
					(mid 88.317832 -54.31409)
					(end 88.651842 -53.957728)
				)
				(xy 88.654382 -53.957728) (xy 88.636348 -53.399436) (xy 88.636094 -53.399182)
			)
		)
		(polygon
			(pts
				(arc
					(start 91.403424 -53.414168)
					(mid 91.076653 -53.050941)
					(end 90.71356 -53.377846)
				)
				(xy 90.71102 -53.377592) (xy 90.681556 -53.93817)
				(arc
					(start 90.684096 -53.938424)
					(mid 91.010994 -54.30139)
					(end 91.37396 -53.974492)
				)
			)
		)
		(polygon
			(pts
				(arc
					(start 86.443058 -53.20792)
					(mid 86.103968 -52.85613)
					(end 85.752178 -53.19522)
				)
				(arc
					(start 85.741764 -53.758592)
					(mid 86.080727 -54.110638)
					(end 86.432644 -53.771546)
				)
			)
		)
		(polygon
			(pts
				(arc
					(start 82.0293 -53.0098)
					(mid 81.6864 -52.6669)
					(end 81.3435 -53.0098)
				)
				(arc
					(start 81.3435 -53.594254)
					(mid 81.686527 -53.9369)
					(end 82.0293 -53.594)
				)
			)
		)
		(polygon
			(pts
				(arc
					(start 9.2202 -52.907946)
					(mid 8.839073 -52.5272)
					(end 8.4582 -52.9082)
				)
				(arc
					(start 8.4582 -53.8988)
					(mid 8.8392 -54.2798)
					(end 9.2202 -53.8988)
				)
			)
		)
		(polygon
			(pts
				(arc
					(start 12.75334 -52.578)
					(mid 12.737717 -52.540283)
					(end 12.7 -52.52466)
				)
				(arc
					(start 12.3444 -52.52466)
					(mid 12.306683 -52.540283)
					(end 12.29106 -52.578)
				)
				(arc
					(start 12.29106 -52.9844)
					(mid 12.306683 -53.022117)
					(end 12.3444 -53.03774)
				)
				(arc
					(start 12.7 -53.03774)
					(mid 12.737717 -53.022117)
					(end 12.75334 -52.9844)
				)
			)
		)
		(polygon
			(pts
				(arc
					(start 11.99134 -52.578)
					(mid 11.975717 -52.540283)
					(end 11.938 -52.52466)
				)
				(arc
					(start 11.5824 -52.52466)
					(mid 11.544683 -52.540283)
					(end 11.52906 -52.578)
				)
				(arc
					(start 11.52906 -52.9844)
					(mid 11.544683 -53.022117)
					(end 11.5824 -53.03774)
				)
				(arc
					(start 11.938 -53.03774)
					(mid 11.975717 -53.022117)
					(end 11.99134 -52.9844)
				)
			)
		)
		(polygon
			(pts
				(arc
					(start 11.22934 -52.578)
					(mid 11.213717 -52.540283)
					(end 11.176 -52.52466)
				)
				(arc
					(start 10.8204 -52.52466)
					(mid 10.782683 -52.540283)
					(end 10.76706 -52.578)
				)
				(arc
					(start 10.76706 -52.9844)
					(mid 10.782683 -53.022117)
					(end 10.8204 -53.03774)
				)
				(arc
					(start 11.176 -53.03774)
					(mid 11.213717 -53.022117)
					(end 11.22934 -52.9844)
				)
			)
		)
		(polygon
			(pts
				(arc
					(start 10.2616 -52.42306)
					(mid 10.2616 -53.13934)
					(end 10.2616 -52.42306)
				)
			)
		)
		(polygon
			(pts
				(arc
					(start 12.04214 -51.5366)
					(mid 12.026517 -51.498883)
					(end 11.9888 -51.48326)
				)
				(arc
					(start 11.6332 -51.48326)
					(mid 11.595483 -51.498883)
					(end 11.57986 -51.5366)
				)
				(arc
					(start 11.57986 -51.943)
					(mid 11.595483 -51.980717)
					(end 11.6332 -51.99634)
				)
				(arc
					(start 11.9888 -51.99634)
					(mid 12.026517 -51.980717)
					(end 12.04214 -51.943)
				)
			)
		)
		(polygon
			(pts
				(arc
					(start 11.28014 -51.5366)
					(mid 11.264517 -51.498883)
					(end 11.2268 -51.48326)
				)
				(arc
					(start 10.8712 -51.48326)
					(mid 10.833483 -51.498883)
					(end 10.81786 -51.5366)
				)
				(arc
					(start 10.81786 -51.943)
					(mid 10.833483 -51.980717)
					(end 10.8712 -51.99634)
				)
				(arc
					(start 11.2268 -51.99634)
					(mid 11.264517 -51.980717)
					(end 11.28014 -51.943)
				)
			)
		)
		(polygon
			(pts
				(arc
					(start 10.51814 -51.5366)
					(mid 10.502517 -51.498883)
					(end 10.4648 -51.48326)
				)
				(arc
					(start 10.1092 -51.48326)
					(mid 10.071483 -51.498883)
					(end 10.05586 -51.5366)
				)
				(arc
					(start 10.05586 -51.943)
					(mid 10.071483 -51.980717)
					(end 10.1092 -51.99634)
				)
				(arc
					(start 10.4648 -51.99634)
					(mid 10.502517 -51.980717)
					(end 10.51814 -51.943)
				)
			)
		)
		(polygon
			(pts
				(arc
					(start 9.5504 -51.38166)
					(mid 9.5504 -52.09794)
					(end 9.5504 -51.38166)
				)
			)
		)
		(polygon
			(pts
				(arc
					(start 8.509 -50.621946)
					(mid 8.127873 -50.2412)
					(end 7.747 -50.6222)
				)
				(arc
					(start 7.747 -51.6128)
					(mid 8.128 -51.9938)
					(end 8.509 -51.6128)
				)
			)
		)
		(polygon
			(pts
				(arc
					(start 12.04214 -50.292)
					(mid 12.026517 -50.254283)
					(end 11.9888 -50.23866)
				)
				(arc
					(start 11.6332 -50.23866)
					(mid 11.595483 -50.254283)
					(end 11.57986 -50.292)
				)
				(arc
					(start 11.57986 -50.6984)
					(mid 11.595483 -50.736117)
					(end 11.6332 -50.75174)
				)
				(arc
					(start 11.9888 -50.75174)
					(mid 12.026517 -50.736117)
					(end 12.04214 -50.6984)
				)
			)
		)
		(polygon
			(pts
				(arc
					(start 11.28014 -50.292)
					(mid 11.264517 -50.254283)
					(end 11.2268 -50.23866)
				)
				(arc
					(start 10.8712 -50.23866)
					(mid 10.833483 -50.254283)
					(end 10.81786 -50.292)
				)
				(arc
					(start 10.81786 -50.6984)
					(mid 10.833483 -50.736117)
					(end 10.8712 -50.75174)
				)
				(arc
					(start 11.2268 -50.75174)
					(mid 11.264517 -50.736117)
					(end 11.28014 -50.6984)
				)
			)
		)
		(polygon
			(pts
				(arc
					(start 10.51814 -50.292)
					(mid 10.502517 -50.254283)
					(end 10.4648 -50.23866)
				)
				(arc
					(start 10.1092 -50.23866)
					(mid 10.071483 -50.254283)
					(end 10.05586 -50.292)
				)
				(arc
					(start 10.05586 -50.6984)
					(mid 10.071483 -50.736117)
					(end 10.1092 -50.75174)
				)
				(arc
					(start 10.4648 -50.75174)
					(mid 10.502517 -50.736117)
					(end 10.51814 -50.6984)
				)
			)
		)
		(polygon
			(pts
				(arc
					(start 9.5504 -50.13706)
					(mid 9.5504 -50.85334)
					(end 9.5504 -50.13706)
				)
			)
		)
		(polygon
			(pts
				(arc
					(start 13.55598 -47.66056)
					(mid 13.17244 -47.27702)
					(end 12.7889 -47.66056)
				)
				(arc
					(start 12.7889 -48.618394)
					(mid 13.172567 -49.00168)
					(end 13.55598 -48.61814)
				)
			)
		)
		(polygon
			(pts
				(arc
					(start 51.041554 -47.64278)
					(mid 50.663729 -47.253654)
					(end 50.274474 -47.63135)
				)
				(arc
					(start 50.262028 -48.49495)
					(mid 50.63998 -48.884078)
					(end 51.029108 -48.506126)
				)
			)
		)
		(polygon
			(pts
				(arc
					(start 15.082266 -47.21606)
					(mid 15.465806 -46.83252)
					(end 15.082266 -46.44898)
				)
				(arc
					(start 14.152626 -46.44898)
					(mid 13.76934 -46.832647)
					(end 14.15288 -47.21606)
				)
			)
		)
		(polygon
			(pts
				(arc
					(start 61.317378 -45.848016)
					(mid 60.910088 -45.489868)
					(end 60.551822 -45.897038)
				)
				(arc
					(start 60.607448 -46.75886)
					(mid 61.014864 -47.117)
					(end 61.373004 -46.709584)
				)
			)
		)
		(polygon
			(pts
				(xy 103.202994 -44.8945) (xy 99.997006 -44.8945) (xy 98.3615 -46.530006) (xy 98.3615 -49.608994)
				(xy 98.854006 -50.1015) (xy 104.091994 -50.1015) (xy 104.472994 -49.7205) (xy 105.077006 -49.7205)
				(xy 105.2195 -49.862994) (xy 105.2195 -51.132994) (xy 105.585006 -51.4985) (xy 106.220006 -51.4985)
				(xy 106.7435 -52.021994) (xy 106.7435 -53.007006) (xy 106.4895 -53.261006) (xy 106.4895 -53.672994)
				(xy 106.855006 -54.0385) (xy 107.393994 -54.0385) (xy 107.8865 -53.545994) (xy 107.8865 -52.910994)
				(xy 108.155994 -52.6415) (xy 108.917994 -52.6415) (xy 110.695994 -50.8635) (xy 111.838994 -50.8635)
				(xy 112.2045 -50.497994) (xy 112.2045 -48.943006) (xy 111.584994 -48.3235) (xy 111.076994 -48.3235)
				(xy 109.044994 -46.2915) (xy 107.266994 -46.2915) (xy 106.885994 -45.9105) (xy 105.712006 -45.9105)
				(xy 105.331006 -46.2915) (xy 104.218994 -46.2915) (xy 103.5685 -45.641006) (xy 103.5685 -45.260006)
			)
		)
		(polygon
			(pts
				(arc
					(start 43.41114 -44.5389)
					(mid 43.79468 -44.15536)
					(end 43.41114 -43.77182)
				)
				(arc
					(start 42.453306 -43.77182)
					(mid 42.07002 -44.155487)
					(end 42.45356 -44.5389)
				)
			)
		)
		(polygon
			(pts
				(arc
					(start 45.007276 -43.53306)
					(mid 44.615103 -43.907837)
					(end 44.98975 -44.30014)
				)
				(arc
					(start 45.947838 -44.32173)
					(mid 46.340014 -43.946826)
					(end 45.96511 -43.55465)
				)
			)
		)
		(polygon
			(pts
				(arc
					(start 49.692052 -37.74567)
					(mid 49.15027 -37.771832)
					(end 49.176432 -38.313614)
				)
				(arc
					(start 49.81321 -38.892226)
					(mid 50.356403 -38.869633)
					(end 50.33137 -38.326568)
				)
			)
		)
		(polygon
			(pts
				(arc
					(start 60.04179 -35.379406)
					(mid 59.658123 -34.99612)
					(end 59.27471 -35.37966)
				)
				(arc
					(start 59.27471 -36.33724)
					(mid 59.65825 -36.72078)
					(end 60.04179 -36.33724)
				)
			)
		)
		(polygon
			(pts
				(arc
					(start 53.479954 -35.696652)
					(mid 53.862478 -35.311969)
					(end 53.477668 -34.929572)
				)
				(arc
					(start 52.52339 -34.93262)
					(mid 52.14112 -35.31743)
					(end 52.52593 -35.6997)
				)
			)
		)
		(polygon
			(pts
				(arc
					(start 52.16652 -34.47034)
					(mid 52.55006 -34.0868)
					(end 52.16652 -33.70326)
				)
				(arc
					(start 51.282092 -33.70326)
					(mid 50.898806 -34.086927)
					(end 51.282346 -34.47034)
				)
			)
		)
		(polygon
			(pts
				(arc
					(start 78.12024 -30.823154)
					(mid 77.762614 -31.150687)
					(end 78.090014 -31.508446)
				)
				(arc
					(start 78.648814 -31.53283)
					(mid 79.006446 -31.20517)
					(end 78.678786 -30.847538)
				)
			)
		)
		(polygon
			(pts
				(arc
					(start 78.538832 -30.2387)
					(mid 78.878175 -29.892117)
					(end 78.531466 -29.5529)
				)
				(arc
					(start 77.972666 -29.55925)
					(mid 77.633576 -29.90596)
					(end 77.980286 -30.24505)
				)
			)
		)
		(polygon
			(pts
				(arc
					(start 38.65372 -29.336746)
					(mid 38.270053 -28.95346)
					(end 37.88664 -29.337)
				)
				(arc
					(start 37.88664 -30.2006)
					(mid 38.27018 -30.58414)
					(end 38.65372 -30.2006)
				)
			)
		)
		(polygon
			(pts
				(arc
					(start 53.535326 -28.897834)
					(mid 53.151786 -28.514294)
					(end 52.768246 -28.897834)
				)
				(arc
					(start 52.768246 -29.827474)
					(mid 53.151913 -30.21076)
					(end 53.535326 -29.82722)
				)
			)
		)
		(polygon
			(pts
				(arc
					(start 69.52234 -27.52344)
					(mid 69.140705 -27.138123)
					(end 68.75526 -27.51963)
				)
				(arc
					(start 68.75145 -28.403296)
					(mid 69.133212 -28.788614)
					(end 69.51853 -28.406852)
				)
			)
		)
		(polygon
			(pts
				(xy 109.552994 -26.0985) (xy 108.252006 -26.0985) (xy 107.5055 -26.845006) (xy 107.5055 -27.734006)
				(xy 107.109006 -28.1305) (xy 104.345994 -28.1305) (xy 104.091994 -27.8765) (xy 99.743006 -27.8765)
				(xy 98.8695 -28.750006) (xy 98.8695 -30.655006) (xy 98.3615 -31.163006) (xy 98.3615 -32.082994)
				(xy 98.727006 -32.4485) (xy 99.108006 -32.4485) (xy 99.616006 -32.9565) (xy 100.251006 -32.9565)
				(xy 100.505006 -33.2105) (xy 103.329994 -33.2105) (xy 104.2035 -32.336994) (xy 104.2035 -31.066994)
				(xy 105.107994 -30.1625) (xy 105.585006 -30.1625) (xy 105.6005 -30.177994) (xy 105.6005 -31.066994)
				(xy 106.474006 -31.9405) (xy 107.871006 -31.9405) (xy 108.2675 -32.336994) (xy 108.633006 -32.7025)
				(xy 109.171994 -32.7025) (xy 109.425994 -32.4485) (xy 110.157006 -32.4485) (xy 110.919006 -33.2105)
				(xy 111.457994 -33.2105) (xy 111.838994 -32.8295) (xy 112.473994 -32.8295) (xy 113.4745 -31.828994)
				(xy 113.4745 -29.766006) (xy 111.711994 -28.0035) (xy 110.187994 -28.0035) (xy 109.7915 -27.607006)
				(xy 109.7915 -26.337006)
			)
		)
		(polygon
			(pts
				(arc
					(start 50.25263 -20.79498)
					(mid 50.63617 -20.41144)
					(end 50.25263 -20.0279)
				)
				(arc
					(start 49.294796 -20.0279)
					(mid 48.91151 -20.411567)
					(end 49.29505 -20.79498)
				)
			)
		)
		(polygon
			(pts
				(arc
					(start 21.053044 -15.872206)
					(mid 21.43633 -15.488539)
					(end 21.05279 -15.105126)
				)
				(arc
					(start 20.09521 -15.105126)
					(mid 19.71167 -15.488666)
					(end 20.09521 -15.872206)
				)
			)
		)
		(polygon
			(pts
				(arc
					(start 64.389 -15.0876)
					(mid 64.77 -14.7066)
					(end 64.389 -14.3256)
				)
				(arc
					(start 63.626746 -14.3256)
					(mid 63.246 -14.706727)
					(end 63.627 -15.0876)
				)
			)
		)
		(polygon
			(pts
				(arc
					(start 73.7108 -15.09014)
					(mid 74.09434 -14.7066)
					(end 73.7108 -14.32306)
				)
				(arc
					(start 72.846946 -14.32306)
					(mid 72.46366 -14.706727)
					(end 72.8472 -15.09014)
				)
			)
		)
		(polygon
			(pts
				(arc
					(start 66.548254 -15.0622)
					(mid 66.929 -14.681073)
					(end 66.548 -14.3002)
				)
				(arc
					(start 65.786 -14.3002)
					(mid 65.405 -14.6812)
					(end 65.786 -15.0622)
				)
			)
		)
		(polygon
			(pts
				(arc
					(start 68.834 -14.98854)
					(mid 69.21754 -14.605)
					(end 68.834 -14.22146)
				)
				(arc
					(start 68.071746 -14.22146)
					(mid 67.68846 -14.605127)
					(end 68.072 -14.98854)
				)
			)
		)
		(polygon
			(pts
				(arc
					(start 81.077054 -14.96314)
					(mid 81.46034 -14.579473)
					(end 81.0768 -14.19606)
				)
				(arc
					(start 80.2132 -14.19606)
					(mid 79.82966 -14.5796)
					(end 80.2132 -14.96314)
				)
			)
		)
		(polygon
			(pts
				(arc
					(start 78.2828 -14.96314)
					(mid 78.66634 -14.5796)
					(end 78.2828 -14.19606)
				)
				(arc
					(start 77.418946 -14.19606)
					(mid 77.03566 -14.579727)
					(end 77.4192 -14.96314)
				)
			)
		)
		(polygon
			(pts
				(arc
					(start 34.290254 -14.96314)
					(mid 34.67354 -14.579473)
					(end 34.29 -14.19606)
				)
				(arc
					(start 33.4264 -14.19606)
					(mid 33.04286 -14.5796)
					(end 33.4264 -14.96314)
				)
			)
		)
		(polygon
			(pts
				(arc
					(start 30.277054 -14.96314)
					(mid 30.66034 -14.579473)
					(end 30.2768 -14.19606)
				)
				(arc
					(start 29.4132 -14.19606)
					(mid 29.02966 -14.5796)
					(end 29.4132 -14.96314)
				)
			)
		)
		(polygon
			(pts
				(arc
					(start 64.64554 -13.7922)
					(mid 64.629917 -13.754483)
					(end 64.5922 -13.73886)
				)
				(arc
					(start 64.1858 -13.73886)
					(mid 64.148083 -13.754483)
					(end 64.13246 -13.7922)
				)
				(arc
					(start 64.13246 -14.1478)
					(mid 64.148083 -14.185517)
					(end 64.1858 -14.20114)
				)
				(arc
					(start 64.5922 -14.20114)
					(mid 64.629917 -14.185517)
					(end 64.64554 -14.1478)
				)
			)
		)
		(polygon
			(pts
				(arc
					(start 63.88354 -13.7922)
					(mid 63.867917 -13.754483)
					(end 63.8302 -13.73886)
				)
				(arc
					(start 63.4238 -13.73886)
					(mid 63.386083 -13.754483)
					(end 63.37046 -13.7922)
				)
				(arc
					(start 63.37046 -14.1478)
					(mid 63.386083 -14.185517)
					(end 63.4238 -14.20114)
				)
				(arc
					(start 63.8302 -14.20114)
					(mid 63.867917 -14.185517)
					(end 63.88354 -14.1478)
				)
			)
		)
		(polygon
			(pts
				(arc
					(start 83.1596 -14.32814)
					(mid 83.54314 -13.9446)
					(end 83.1596 -13.56106)
				)
				(arc
					(start 82.295746 -13.56106)
					(mid 81.91246 -13.944727)
					(end 82.296 -14.32814)
				)
			)
		)
		(polygon
			(pts
				(arc
					(start 53.010054 -14.32814)
					(mid 53.39334 -13.944473)
					(end 53.0098 -13.56106)
				)
				(arc
					(start 52.1462 -13.56106)
					(mid 51.76266 -13.9446)
					(end 52.1462 -14.32814)
				)
			)
		)
		(polygon
			(pts
				(arc
					(start 50.2158 -14.1986)
					(mid 50.5968 -13.8176)
					(end 50.2158 -13.4366)
				)
				(arc
					(start 49.453546 -13.4366)
					(mid 49.0728 -13.817727)
					(end 49.4538 -14.1986)
				)
			)
		)
		(polygon
			(pts
				(arc
					(start 46.177454 -14.1986)
					(mid 46.5582 -13.817473)
					(end 46.1772 -13.4366)
				)
				(arc
					(start 45.466 -13.4366)
					(mid 45.085 -13.8176)
					(end 45.466 -14.1986)
				)
			)
		)
		(polygon
			(pts
				(arc
					(start 42.281856 -14.20114)
					(mid 42.665142 -13.817473)
					(end 42.281602 -13.43406)
				)
				(arc
					(start 41.418002 -13.43406)
					(mid 41.034462 -13.8176)
					(end 41.418002 -14.20114)
				)
			)
		)
		(polygon
			(pts
				(arc
					(start 38.281864 -14.20114)
					(mid 38.66515 -13.817473)
					(end 38.28161 -13.43406)
				)
				(arc
					(start 37.41801 -13.43406)
					(mid 37.03447 -13.8176)
					(end 37.41801 -14.20114)
				)
			)
		)
		(polygon
			(pts
				(arc
					(start 26.276554 -14.20114)
					(mid 26.65984 -13.817473)
					(end 26.2763 -13.43406)
				)
				(arc
					(start 25.4127 -13.43406)
					(mid 25.02916 -13.8176)
					(end 25.4127 -14.20114)
				)
			)
		)
		(polygon
			(pts
				(arc
					(start 22.5298 -14.20114)
					(mid 22.91334 -13.8176)
					(end 22.5298 -13.43406)
				)
				(arc
					(start 21.665946 -13.43406)
					(mid 21.28266 -13.817727)
					(end 21.6662 -14.20114)
				)
			)
		)
		(polygon
			(pts
				(arc
					(start 48.184054 -14.1732)
					(mid 48.5648 -13.792073)
					(end 48.1838 -13.4112)
				)
				(arc
					(start 47.46371 -13.4112)
					(mid 47.08271 -13.7922)
					(end 47.46371 -14.1732)
				)
			)
		)
		(polygon
			(pts
				(arc
					(start 64.64554 -13.0302)
					(mid 64.629917 -12.992483)
					(end 64.5922 -12.97686)
				)
				(arc
					(start 64.1858 -12.97686)
					(mid 64.148083 -12.992483)
					(end 64.13246 -13.0302)
				)
				(arc
					(start 64.13246 -13.3858)
					(mid 64.148083 -13.423517)
					(end 64.1858 -13.43914)
				)
				(arc
					(start 64.5922 -13.43914)
					(mid 64.629917 -13.423517)
					(end 64.64554 -13.3858)
				)
			)
		)
		(polygon
			(pts
				(arc
					(start 63.88354 -13.0302)
					(mid 63.867917 -12.992483)
					(end 63.8302 -12.97686)
				)
				(arc
					(start 63.4238 -12.97686)
					(mid 63.386083 -12.992483)
					(end 63.37046 -13.0302)
				)
				(arc
					(start 63.37046 -13.3858)
					(mid 63.386083 -13.423517)
					(end 63.4238 -13.43914)
				)
				(arc
					(start 63.8302 -13.43914)
					(mid 63.867917 -13.423517)
					(end 63.88354 -13.3858)
				)
			)
		)
		(polygon
			(pts
				(arc
					(start 53.24094 -13.0302)
					(mid 53.225317 -12.992483)
					(end 53.1876 -12.97686)
				)
				(arc
					(start 52.7812 -12.97686)
					(mid 52.743483 -12.992483)
					(end 52.72786 -13.0302)
				)
				(arc
					(start 52.72786 -13.3858)
					(mid 52.743483 -13.423517)
					(end 52.7812 -13.43914)
				)
				(arc
					(start 53.1876 -13.43914)
					(mid 53.225317 -13.423517)
					(end 53.24094 -13.3858)
				)
			)
		)
		(polygon
			(pts
				(arc
					(start 52.47894 -13.0302)
					(mid 52.463317 -12.992483)
					(end 52.4256 -12.97686)
				)
				(arc
					(start 52.0192 -12.97686)
					(mid 51.981483 -12.992483)
					(end 51.96586 -13.0302)
				)
				(arc
					(start 51.96586 -13.3858)
					(mid 51.981483 -13.423517)
					(end 52.0192 -13.43914)
				)
				(arc
					(start 52.4256 -13.43914)
					(mid 52.463317 -13.423517)
					(end 52.47894 -13.3858)
				)
			)
		)
		(polygon
			(pts
				(arc
					(start 50.47234 -12.9032)
					(mid 50.456717 -12.865483)
					(end 50.419 -12.84986)
				)
				(arc
					(start 50.0126 -12.84986)
					(mid 49.974883 -12.865483)
					(end 49.95926 -12.9032)
				)
				(arc
					(start 49.95926 -13.2588)
					(mid 49.974883 -13.296517)
					(end 50.0126 -13.31214)
				)
				(arc
					(start 50.419 -13.31214)
					(mid 50.456717 -13.296517)
					(end 50.47234 -13.2588)
				)
			)
		)
		(polygon
			(pts
				(arc
					(start 49.71034 -12.9032)
					(mid 49.694717 -12.865483)
					(end 49.657 -12.84986)
				)
				(arc
					(start 49.2506 -12.84986)
					(mid 49.212883 -12.865483)
					(end 49.19726 -12.9032)
				)
				(arc
					(start 49.19726 -13.2588)
					(mid 49.212883 -13.296517)
					(end 49.2506 -13.31214)
				)
				(arc
					(start 49.657 -13.31214)
					(mid 49.694717 -13.296517)
					(end 49.71034 -13.2588)
				)
			)
		)
		(polygon
			(pts
				(arc
					(start 53.24094 -12.2682)
					(mid 53.225317 -12.230483)
					(end 53.1876 -12.21486)
				)
				(arc
					(start 52.7812 -12.21486)
					(mid 52.743483 -12.230483)
					(end 52.72786 -12.2682)
				)
				(arc
					(start 52.72786 -12.6238)
					(mid 52.743483 -12.661517)
					(end 52.7812 -12.67714)
				)
				(arc
					(start 53.1876 -12.67714)
					(mid 53.225317 -12.661517)
					(end 53.24094 -12.6238)
				)
			)
		)
		(polygon
			(pts
				(arc
					(start 52.47894 -12.2682)
					(mid 52.463317 -12.230483)
					(end 52.4256 -12.21486)
				)
				(arc
					(start 52.0192 -12.21486)
					(mid 51.981483 -12.230483)
					(end 51.96586 -12.2682)
				)
				(arc
					(start 51.96586 -12.6238)
					(mid 51.981483 -12.661517)
					(end 52.0192 -12.67714)
				)
				(arc
					(start 52.4256 -12.67714)
					(mid 52.463317 -12.661517)
					(end 52.47894 -12.6238)
				)
			)
		)
		(polygon
			(pts
				(arc
					(start 44.211494 -12.98194)
					(mid 44.59478 -12.598273)
					(end 44.21124 -12.21486)
				)
				(arc
					(start 43.25366 -12.21486)
					(mid 42.87012 -12.5984)
					(end 43.25366 -12.98194)
				)
			)
		)
		(polygon
			(pts
				(arc
					(start 50.47234 -12.1412)
					(mid 50.456717 -12.103483)
					(end 50.419 -12.08786)
				)
				(arc
					(start 50.0126 -12.08786)
					(mid 49.974883 -12.103483)
					(end 49.95926 -12.1412)
				)
				(arc
					(start 49.95926 -12.4968)
					(mid 49.974883 -12.534517)
					(end 50.0126 -12.55014)
				)
				(arc
					(start 50.419 -12.55014)
					(mid 50.456717 -12.534517)
					(end 50.47234 -12.4968)
				)
			)
		)
		(polygon
			(pts
				(arc
					(start 49.71034 -12.1412)
					(mid 49.694717 -12.103483)
					(end 49.657 -12.08786)
				)
				(arc
					(start 49.2506 -12.08786)
					(mid 49.212883 -12.103483)
					(end 49.19726 -12.1412)
				)
				(arc
					(start 49.19726 -12.4968)
					(mid 49.212883 -12.534517)
					(end 49.2506 -12.55014)
				)
				(arc
					(start 49.657 -12.55014)
					(mid 49.694717 -12.534517)
					(end 49.71034 -12.4968)
				)
			)
		)
		(polygon
			(pts
				(arc
					(start 40.40124 -12.73048)
					(mid 40.78478 -12.34694)
					(end 40.40124 -11.9634)
				)
				(arc
					(start 39.443406 -11.9634)
					(mid 39.06012 -12.347067)
					(end 39.44366 -12.73048)
				)
			)
		)
		(polygon
			(pts
				(arc
					(start 59.997594 -11.320018)
					(mid 60.381134 -10.936478)
					(end 59.997594 -10.552938)
				)
				(arc
					(start 59.07786 -10.552938)
					(mid 58.694574 -10.936605)
					(end 59.078114 -11.320018)
				)
			)
		)
		(polygon
			(pts
				(arc
					(start 84.310474 -10.79627)
					(mid 84.694014 -10.41273)
					(end 84.310474 -10.02919)
				)
				(arc
					(start 83.388708 -10.02919)
					(mid 83.005422 -10.412857)
					(end 83.388962 -10.79627)
				)
			)
		)
		(polygon
			(pts
				(arc
					(start 80.328516 -10.7188)
					(mid 80.712056 -10.33526)
					(end 80.328516 -9.95172)
				)
				(arc
					(start 79.370682 -9.95172)
					(mid 78.987396 -10.335387)
					(end 79.370936 -10.7188)
				)
			)
		)
		(polygon
			(pts
				(arc
					(start 76.328524 -10.668)
					(mid 76.712064 -10.28446)
					(end 76.328524 -9.90092)
				)
				(arc
					(start 75.37069 -9.90092)
					(mid 74.987404 -10.284587)
					(end 75.370944 -10.668)
				)
			)
		)
		(polygon
			(pts
				(arc
					(start 72.328532 -10.668)
					(mid 72.712072 -10.28446)
					(end 72.328532 -9.90092)
				)
				(arc
					(start 71.370698 -9.90092)
					(mid 70.987412 -10.284587)
					(end 71.370952 -10.668)
				)
			)
		)
		(polygon
			(pts
				(arc
					(start 68.303394 -10.668)
					(mid 68.68668 -10.284333)
					(end 68.30314 -9.90092)
				)
				(arc
					(start 67.34556 -9.90092)
					(mid 66.96202 -10.28446)
					(end 67.34556 -10.668)
				)
			)
		)
		(polygon
			(pts
				(arc
					(start 50.310542 -10.64387)
					(mid 50.694082 -10.26033)
					(end 50.310542 -9.87679)
				)
				(arc
					(start 49.388776 -9.87679)
					(mid 49.00549 -10.260457)
					(end 49.38903 -10.64387)
				)
			)
		)
		(polygon
			(pts
				(arc
					(start 62.328044 -10.634218)
					(mid 62.71133 -10.250551)
					(end 62.32779 -9.867138)
				)
				(arc
					(start 61.40831 -9.867138)
					(mid 61.02477 -10.250678)
					(end 61.40831 -10.634218)
				)
			)
		)
		(polygon
			(pts
				(arc
					(start 48.327818 -10.634218)
					(mid 48.711358 -10.250678)
					(end 48.327818 -9.867138)
				)
				(arc
					(start 47.408084 -9.867138)
					(mid 47.024798 -10.250805)
					(end 47.408338 -10.634218)
				)
			)
		)
		(polygon
			(pts
				(arc
					(start 44.327826 -10.634218)
					(mid 44.711366 -10.250678)
					(end 44.327826 -9.867138)
				)
				(arc
					(start 43.408092 -9.867138)
					(mid 43.024806 -10.250805)
					(end 43.408346 -10.634218)
				)
			)
		)
		(polygon
			(pts
				(arc
					(start 40.327834 -10.634218)
					(mid 40.711374 -10.250678)
					(end 40.327834 -9.867138)
				)
				(arc
					(start 39.4081 -9.867138)
					(mid 39.024814 -10.250805)
					(end 39.408354 -10.634218)
				)
			)
		)
		(polygon
			(pts
				(arc
					(start 36.328096 -10.634218)
					(mid 36.711382 -10.250551)
					(end 36.327842 -9.867138)
				)
				(arc
					(start 35.408362 -9.867138)
					(mid 35.024822 -10.250678)
					(end 35.408362 -10.634218)
				)
			)
		)
		(polygon
			(pts
				(arc
					(start 32.328104 -10.634218)
					(mid 32.71139 -10.250551)
					(end 32.32785 -9.867138)
				)
				(arc
					(start 31.40837 -9.867138)
					(mid 31.02483 -10.250678)
					(end 31.40837 -10.634218)
				)
			)
		)
		(polygon
			(pts
				(arc
					(start 28.328112 -10.634218)
					(mid 28.711398 -10.250551)
					(end 28.327858 -9.867138)
				)
				(arc
					(start 27.408378 -9.867138)
					(mid 27.024838 -10.250678)
					(end 27.408378 -10.634218)
				)
			)
		)
		(polygon
			(pts
				(arc
					(start 24.327866 -10.634218)
					(mid 24.711406 -10.250678)
					(end 24.327866 -9.867138)
				)
				(arc
					(start 23.408132 -9.867138)
					(mid 23.024846 -10.250805)
					(end 23.408386 -10.634218)
				)
			)
		)
		(polygon
			(pts
				(arc
					(start 20.327874 -10.634218)
					(mid 20.711414 -10.250678)
					(end 20.327874 -9.867138)
				)
				(arc
					(start 19.40814 -9.867138)
					(mid 19.024854 -10.250805)
					(end 19.408394 -10.634218)
				)
			)
		)
	)
	(zone
		(layer "In1.Cu")
		(hatch none 0.5)
		(connect_pads
			(clearance 0)
		)
		(min_thickness 0.25)
		(keepout
			(tracks not_allowed)
			(vias allowed)
			(pads allowed)
			(copperpour not_allowed)
			(footprints allowed)
		)
		(placement
			(enabled no)
			(sheetname "")
		)
		(fill
			(thermal_gap 0.5)
			(thermal_bridge_width 0.5)
			(island_removal_mode 0)
		)
		(polygon
			(pts
				(arc
					(start 64.5922 -13.43914)
					(mid 64.629917 -13.423517)
					(end 64.64554 -13.3858)
				)
				(arc
					(start 64.64554 -13.0302)
					(mid 64.629917 -12.992483)
					(end 64.5922 -12.97686)
				)
				(arc
					(start 64.1858 -12.97686)
					(mid 64.148083 -12.992483)
					(end 64.13246 -13.0302)
				)
				(arc
					(start 64.13246 -13.3858)
					(mid 64.148083 -13.423517)
					(end 64.1858 -13.43914)
				)
			)
		)
	)
	(zone
		(layer "In1.Cu")
		(hatch none 0.5)
		(connect_pads
			(clearance 0)
		)
		(min_thickness 0.25)
		(keepout
			(tracks not_allowed)
			(vias allowed)
			(pads allowed)
			(copperpour not_allowed)
			(footprints allowed)
		)
		(placement
			(enabled no)
			(sheetname "")
		)
		(fill
			(thermal_gap 0.5)
			(thermal_bridge_width 0.5)
			(island_removal_mode 0)
		)
		(polygon
			(pts
				(xy 78.991714 -4.097528) (xy 79.707994 -4.097528) (xy 79.707994 -8.293608) (xy 78.991714 -8.293608)
			)
		)
	)
	(zone
		(layer "In1.Cu")
		(hatch none 0.5)
		(connect_pads
			(clearance 0)
		)
		(min_thickness 0.25)
		(keepout
			(tracks not_allowed)
			(vias allowed)
			(pads allowed)
			(copperpour not_allowed)
			(footprints allowed)
		)
		(placement
			(enabled no)
			(sheetname "")
		)
		(fill
			(thermal_gap 0.5)
			(thermal_bridge_width 0.5)
			(island_removal_mode 0)
		)
		(polygon
			(pts
				(arc
					(start 10.05586 -50.6984)
					(mid 10.071483 -50.736117)
					(end 10.1092 -50.75174)
				)
				(arc
					(start 10.4648 -50.75174)
					(mid 10.502517 -50.736117)
					(end 10.51814 -50.6984)
				)
				(arc
					(start 10.51814 -50.292)
					(mid 10.502517 -50.254283)
					(end 10.4648 -50.23866)
				)
				(arc
					(start 10.1092 -50.23866)
					(mid 10.071483 -50.254283)
					(end 10.05586 -50.292)
				)
			)
		)
	)
	(zone
		(layer "In1.Cu")
		(hatch none 0.5)
		(connect_pads
			(clearance 0)
		)
		(min_thickness 0.25)
		(keepout
			(tracks not_allowed)
			(vias allowed)
			(pads allowed)
			(copperpour not_allowed)
			(footprints allowed)
		)
		(placement
			(enabled no)
			(sheetname "")
		)
		(fill
			(thermal_gap 0.5)
			(thermal_bridge_width 0.5)
			(island_removal_mode 0)
		)
		(polygon
			(pts
				(arc
					(start 49.657 -13.31214)
					(mid 49.694717 -13.296517)
					(end 49.71034 -13.2588)
				)
				(arc
					(start 49.71034 -12.9032)
					(mid 49.694717 -12.865483)
					(end 49.657 -12.84986)
				)
				(arc
					(start 49.2506 -12.84986)
					(mid 49.212883 -12.865483)
					(end 49.19726 -12.9032)
				)
				(arc
					(start 49.19726 -13.2588)
					(mid 49.212883 -13.296517)
					(end 49.2506 -13.31214)
				)
			)
		)
	)
	(zone
		(layer "In1.Cu")
		(hatch none 0.5)
		(connect_pads
			(clearance 0)
		)
		(min_thickness 0.25)
		(keepout
			(tracks not_allowed)
			(vias allowed)
			(pads allowed)
			(copperpour not_allowed)
			(footprints allowed)
		)
		(placement
			(enabled no)
			(sheetname "")
		)
		(fill
			(thermal_gap 0.5)
			(thermal_bridge_width 0.5)
			(island_removal_mode 0)
		)
		(polygon
			(pts
				(xy 18.991834 -4.097528) (xy 19.708114 -4.097528) (xy 19.708114 -8.293608) (xy 18.991834 -8.293608)
			)
		)
	)
	(zone
		(layer "In1.Cu")
		(hatch none 0.5)
		(connect_pads
			(clearance 0)
		)
		(min_thickness 0.25)
		(keepout
			(tracks not_allowed)
			(vias allowed)
			(pads allowed)
			(copperpour not_allowed)
			(footprints allowed)
		)
		(placement
			(enabled no)
			(sheetname "")
		)
		(fill
			(thermal_gap 0.5)
			(thermal_bridge_width 0.5)
			(island_removal_mode 0)
		)
		(polygon
			(pts
				(arc
					(start 7.89686 -64.7192)
					(mid 7.912483 -64.756917)
					(end 7.9502 -64.77254)
				)
				(arc
					(start 8.3058 -64.77254)
					(mid 8.343517 -64.756917)
					(end 8.35914 -64.7192)
				)
				(arc
					(start 8.35914 -64.3128)
					(mid 8.343517 -64.275083)
					(end 8.3058 -64.25946)
				)
				(arc
					(start 7.9502 -64.25946)
					(mid 7.912483 -64.275083)
					(end 7.89686 -64.3128)
				)
			)
		)
	)
	(zone
		(layer "In1.Cu")
		(hatch none 0.5)
		(connect_pads
			(clearance 0)
		)
		(min_thickness 0.25)
		(keepout
			(tracks not_allowed)
			(vias allowed)
			(pads allowed)
			(copperpour not_allowed)
			(footprints allowed)
		)
		(placement
			(enabled no)
			(sheetname "")
		)
		(fill
			(thermal_gap 0.5)
			(thermal_bridge_width 0.5)
			(island_removal_mode 0)
		)
		(polygon
			(pts
				(arc
					(start 8.65886 -61.1632)
					(mid 8.674483 -61.200917)
					(end 8.7122 -61.21654)
				)
				(arc
					(start 9.0678 -61.21654)
					(mid 9.105517 -61.200917)
					(end 9.12114 -61.1632)
				)
				(arc
					(start 9.12114 -60.7568)
					(mid 9.105517 -60.719083)
					(end 9.0678 -60.70346)
				)
				(arc
					(start 8.7122 -60.70346)
					(mid 8.674483 -60.719083)
					(end 8.65886 -60.7568)
				)
			)
		)
	)
	(zone
		(layer "In1.Cu")
		(hatch none 0.5)
		(connect_pads
			(clearance 0)
		)
		(min_thickness 0.25)
		(keepout
			(tracks not_allowed)
			(vias allowed)
			(pads allowed)
			(copperpour not_allowed)
			(footprints allowed)
		)
		(placement
			(enabled no)
			(sheetname "")
		)
		(fill
			(thermal_gap 0.5)
			(thermal_bridge_width 0.5)
			(island_removal_mode 0)
		)
		(polygon
			(pts
				(arc
					(start 8.65886 -63.8302)
					(mid 8.674483 -63.867917)
					(end 8.7122 -63.88354)
				)
				(arc
					(start 9.0678 -63.88354)
					(mid 9.105517 -63.867917)
					(end 9.12114 -63.8302)
				)
				(arc
					(start 9.12114 -63.4238)
					(mid 9.105517 -63.386083)
					(end 9.0678 -63.37046)
				)
				(arc
					(start 8.7122 -63.37046)
					(mid 8.674483 -63.386083)
					(end 8.65886 -63.4238)
				)
			)
		)
	)
	(zone
		(layer "In1.Cu")
		(hatch none 0.5)
		(connect_pads
			(clearance 0)
		)
		(min_thickness 0.25)
		(keepout
			(tracks not_allowed)
			(vias allowed)
			(pads allowed)
			(copperpour not_allowed)
			(footprints allowed)
		)
		(placement
			(enabled no)
			(sheetname "")
		)
		(fill
			(thermal_gap 0.5)
			(thermal_bridge_width 0.5)
			(island_removal_mode 0)
		)
		(polygon
			(pts
				(arc
					(start 52.7812 -12.21486)
					(mid 52.743483 -12.230483)
					(end 52.72786 -12.2682)
				)
				(arc
					(start 52.72786 -12.6238)
					(mid 52.743483 -12.661517)
					(end 52.7812 -12.67714)
				)
				(arc
					(start 53.1876 -12.67714)
					(mid 53.225317 -12.661517)
					(end 53.24094 -12.6238)
				)
				(arc
					(start 53.24094 -12.2682)
					(mid 53.225317 -12.230483)
					(end 53.1876 -12.21486)
				)
			)
		)
	)
	(zone
		(layer "In1.Cu")
		(hatch none 0.5)
		(connect_pads
			(clearance 0)
		)
		(min_thickness 0.25)
		(keepout
			(tracks not_allowed)
			(vias allowed)
			(pads allowed)
			(copperpour not_allowed)
			(footprints allowed)
		)
		(placement
			(enabled no)
			(sheetname "")
		)
		(fill
			(thermal_gap 0.5)
			(thermal_bridge_width 0.5)
			(island_removal_mode 0)
		)
		(polygon
			(pts
				(xy 22.991826 -4.097528) (xy 23.708106 -4.097528) (xy 23.708106 -8.293608) (xy 22.991826 -8.293608)
			)
		)
	)
	(zone
		(layer "In1.Cu")
		(hatch none 0.5)
		(connect_pads
			(clearance 0)
		)
		(min_thickness 0.25)
		(keepout
			(tracks not_allowed)
			(vias allowed)
			(pads allowed)
			(copperpour not_allowed)
			(footprints allowed)
		)
		(placement
			(enabled no)
			(sheetname "")
		)
		(fill
			(thermal_gap 0.5)
			(thermal_bridge_width 0.5)
			(island_removal_mode 0)
		)
		(polygon
			(pts
				(xy 50.99177 -4.097528) (xy 51.70805 -4.097528) (xy 51.70805 -8.293608) (xy 50.99177 -8.293608)
			)
		)
	)
	(zone
		(layer "In1.Cu")
		(hatch none 0.5)
		(connect_pads
			(clearance 0)
		)
		(min_thickness 0.25)
		(keepout
			(tracks not_allowed)
			(vias allowed)
			(pads allowed)
			(copperpour not_allowed)
			(footprints allowed)
		)
		(placement
			(enabled no)
			(sheetname "")
		)
		(fill
			(thermal_gap 0.5)
			(thermal_bridge_width 0.5)
			(island_removal_mode 0)
		)
		(polygon
			(pts
				(arc
					(start 50.419 -13.31214)
					(mid 50.456717 -13.296517)
					(end 50.47234 -13.2588)
				)
				(arc
					(start 50.47234 -12.9032)
					(mid 50.456717 -12.865483)
					(end 50.419 -12.84986)
				)
				(arc
					(start 50.0126 -12.84986)
					(mid 49.974883 -12.865483)
					(end 49.95926 -12.9032)
				)
				(arc
					(start 49.95926 -13.2588)
					(mid 49.974883 -13.296517)
					(end 50.0126 -13.31214)
				)
			)
		)
	)
	(zone
		(layer "In1.Cu")
		(hatch none 0.5)
		(connect_pads
			(clearance 0)
		)
		(min_thickness 0.25)
		(keepout
			(tracks not_allowed)
			(vias allowed)
			(pads allowed)
			(copperpour not_allowed)
			(footprints allowed)
		)
		(placement
			(enabled no)
			(sheetname "")
		)
		(fill
			(thermal_gap 0.5)
			(thermal_bridge_width 0.5)
			(island_removal_mode 0)
		)
		(polygon
			(pts
				(arc
					(start 10.76706 -54.229)
					(mid 10.782683 -54.266717)
					(end 10.8204 -54.28234)
				)
				(arc
					(start 11.176 -54.28234)
					(mid 11.213717 -54.266717)
					(end 11.22934 -54.229)
				)
				(arc
					(start 11.22934 -53.8226)
					(mid 11.213717 -53.784883)
					(end 11.176 -53.76926)
				)
				(arc
					(start 10.8204 -53.76926)
					(mid 10.782683 -53.784883)
					(end 10.76706 -53.8226)
				)
			)
		)
	)
	(zone
		(layer "In1.Cu")
		(hatch none 0.5)
		(connect_pads
			(clearance 0)
		)
		(min_thickness 0.25)
		(keepout
			(tracks not_allowed)
			(vias allowed)
			(pads allowed)
			(copperpour not_allowed)
			(footprints allowed)
		)
		(placement
			(enabled no)
			(sheetname "")
		)
		(fill
			(thermal_gap 0.5)
			(thermal_bridge_width 0.5)
			(island_removal_mode 0)
		)
		(polygon
			(pts
				(arc
					(start 8.65886 -62.0522)
					(mid 8.674483 -62.089917)
					(end 8.7122 -62.10554)
				)
				(arc
					(start 9.0678 -62.10554)
					(mid 9.105517 -62.089917)
					(end 9.12114 -62.0522)
				)
				(arc
					(start 9.12114 -61.6458)
					(mid 9.105517 -61.608083)
					(end 9.0678 -61.59246)
				)
				(arc
					(start 8.7122 -61.59246)
					(mid 8.674483 -61.608083)
					(end 8.65886 -61.6458)
				)
			)
		)
	)
	(zone
		(layer "In1.Cu")
		(hatch none 0.5)
		(connect_pads
			(clearance 0)
		)
		(min_thickness 0.25)
		(keepout
			(tracks not_allowed)
			(vias allowed)
			(pads allowed)
			(copperpour not_allowed)
			(footprints allowed)
		)
		(placement
			(enabled no)
			(sheetname "")
		)
		(fill
			(thermal_gap 0.5)
			(thermal_bridge_width 0.5)
			(island_removal_mode 0)
		)
		(polygon
			(pts
				(arc
					(start 7.89686 -60.2742)
					(mid 7.912483 -60.311917)
					(end 7.9502 -60.32754)
				)
				(arc
					(start 8.3058 -60.32754)
					(mid 8.343517 -60.311917)
					(end 8.35914 -60.2742)
				)
				(arc
					(start 8.35914 -59.8678)
					(mid 8.343517 -59.830083)
					(end 8.3058 -59.81446)
				)
				(arc
					(start 7.9502 -59.81446)
					(mid 7.912483 -59.830083)
					(end 7.89686 -59.8678)
				)
			)
		)
	)
	(zone
		(layer "In1.Cu")
		(hatch none 0.5)
		(connect_pads
			(clearance 0)
		)
		(min_thickness 0.25)
		(keepout
			(tracks not_allowed)
			(vias allowed)
			(pads allowed)
			(copperpour not_allowed)
			(footprints allowed)
		)
		(placement
			(enabled no)
			(sheetname "")
		)
		(fill
			(thermal_gap 0.5)
			(thermal_bridge_width 0.5)
			(island_removal_mode 0)
		)
		(polygon
			(pts
				(arc
					(start 64.5922 -14.20114)
					(mid 64.629917 -14.185517)
					(end 64.64554 -14.1478)
				)
				(arc
					(start 64.64554 -13.7922)
					(mid 64.629917 -13.754483)
					(end 64.5922 -13.73886)
				)
				(arc
					(start 64.1858 -13.73886)
					(mid 64.148083 -13.754483)
					(end 64.13246 -13.7922)
				)
				(arc
					(start 64.13246 -14.1478)
					(mid 64.148083 -14.185517)
					(end 64.1858 -14.20114)
				)
			)
		)
	)
	(zone
		(layer "In1.Cu")
		(hatch none 0.5)
		(connect_pads
			(clearance 0)
		)
		(min_thickness 0.25)
		(keepout
			(tracks not_allowed)
			(vias allowed)
			(pads allowed)
			(copperpour not_allowed)
			(footprints allowed)
		)
		(placement
			(enabled no)
			(sheetname "")
		)
		(fill
			(thermal_gap 0.5)
			(thermal_bridge_width 0.5)
			(island_removal_mode 0)
		)
		(polygon
			(pts
				(arc
					(start 10.76706 -52.9844)
					(mid 10.782683 -53.022117)
					(end 10.8204 -53.03774)
				)
				(arc
					(start 11.176 -53.03774)
					(mid 11.213717 -53.022117)
					(end 11.22934 -52.9844)
				)
				(arc
					(start 11.22934 -52.578)
					(mid 11.213717 -52.540283)
					(end 11.176 -52.52466)
				)
				(arc
					(start 10.8204 -52.52466)
					(mid 10.782683 -52.540283)
					(end 10.76706 -52.578)
				)
			)
		)
	)
	(zone
		(layer "In1.Cu")
		(hatch none 0.5)
		(connect_pads
			(clearance 0)
		)
		(min_thickness 0.25)
		(keepout
			(tracks not_allowed)
			(vias allowed)
			(pads allowed)
			(copperpour not_allowed)
			(footprints allowed)
		)
		(placement
			(enabled no)
			(sheetname "")
		)
		(fill
			(thermal_gap 0.5)
			(thermal_bridge_width 0.5)
			(island_removal_mode 0)
		)
		(polygon
			(pts
				(arc
					(start 12.29106 -52.9844)
					(mid 12.306683 -53.022117)
					(end 12.3444 -53.03774)
				)
				(arc
					(start 12.7 -53.03774)
					(mid 12.737717 -53.022117)
					(end 12.75334 -52.9844)
				)
				(arc
					(start 12.75334 -52.578)
					(mid 12.737717 -52.540283)
					(end 12.7 -52.52466)
				)
				(arc
					(start 12.3444 -52.52466)
					(mid 12.306683 -52.540283)
					(end 12.29106 -52.578)
				)
			)
		)
	)
	(zone
		(layer "In1.Cu")
		(hatch none 0.5)
		(connect_pads
			(clearance 0)
		)
		(min_thickness 0.25)
		(keepout
			(tracks not_allowed)
			(vias allowed)
			(pads allowed)
			(copperpour not_allowed)
			(footprints allowed)
		)
		(placement
			(enabled no)
			(sheetname "")
		)
		(fill
			(thermal_gap 0.5)
			(thermal_bridge_width 0.5)
			(island_removal_mode 0)
		)
		(polygon
			(pts
				(xy 27.991816 -4.097528) (xy 28.708096 -4.097528) (xy 28.708096 -8.293608) (xy 27.991816 -8.293608)
			)
		)
	)
	(zone
		(layer "In1.Cu")
		(hatch none 0.5)
		(connect_pads
			(clearance 0)
		)
		(min_thickness 0.25)
		(keepout
			(tracks not_allowed)
			(vias allowed)
			(pads allowed)
			(copperpour not_allowed)
			(footprints allowed)
		)
		(placement
			(enabled no)
			(sheetname "")
		)
		(fill
			(thermal_gap 0.5)
			(thermal_bridge_width 0.5)
			(island_removal_mode 0)
		)
		(polygon
			(pts
				(xy 38.991794 -4.097528) (xy 39.708074 -4.097528) (xy 39.708074 -8.293608) (xy 38.991794 -8.293608)
			)
		)
	)
	(zone
		(net "PV_VDDR")
		(layer "In1.Cu")
		(hatch none 0.5)
		(connect_pads
			(clearance 0.5)
		)
		(min_thickness 0.25)
		(fill yes
			(thermal_gap 0.5)
			(thermal_bridge_width 0.5)
			(island_removal_mode 0)
		)
		(polygon
			(pts
				(xy 100.154994 -45.2755) (xy 98.7425 -46.687994) (xy 98.7425 -49.451006) (xy 99.011994 -49.7205)
				(xy 103.934006 -49.7205) (xy 104.2035 -49.451006) (xy 104.315006 -49.3395) (xy 105.234994 -49.3395)
				(xy 105.6005 -49.705006) (xy 105.6005 -50.975006) (xy 105.742994 -51.1175) (xy 106.377994 -51.1175)
				(xy 107.1245 -51.864006) (xy 107.1245 -53.164994) (xy 106.8705 -53.418994) (xy 106.8705 -53.515006)
				(xy 107.012994 -53.6575) (xy 107.236006 -53.6575) (xy 107.5055 -53.388006) (xy 107.5055 -52.753006)
				(xy 107.998006 -52.2605) (xy 108.760006 -52.2605) (xy 109.1565 -51.864006) (xy 110.538006 -50.4825)
				(xy 111.681006 -50.4825) (xy 111.8235 -50.340006) (xy 111.8235 -49.100994) (xy 111.427006 -48.7045)
				(xy 110.919006 -48.7045) (xy 108.887006 -46.6725) (xy 107.109006 -46.6725) (xy 106.728006 -46.2915)
				(xy 105.869994 -46.2915) (xy 105.488994 -46.6725) (xy 104.061006 -46.6725) (xy 103.1875 -45.798994)
				(xy 103.1875 -45.417994) (xy 103.045006 -45.2755)
			)
		)
	)
	(zone
		(layer "In1.Cu")
		(hatch none 0.5)
		(connect_pads
			(clearance 0)
		)
		(min_thickness 0.25)
		(keepout
			(tracks not_allowed)
			(vias allowed)
			(pads allowed)
			(copperpour not_allowed)
			(footprints allowed)
		)
		(placement
			(enabled no)
			(sheetname "")
		)
		(fill
			(thermal_gap 0.5)
			(thermal_bridge_width 0.5)
			(island_removal_mode 0)
		)
		(polygon
			(pts
				(arc
					(start 10.81786 -50.6984)
					(mid 10.833483 -50.736117)
					(end 10.8712 -50.75174)
				)
				(arc
					(start 11.2268 -50.75174)
					(mid 11.264517 -50.736117)
					(end 11.28014 -50.6984)
				)
				(arc
					(start 11.28014 -50.292)
					(mid 11.264517 -50.254283)
					(end 11.2268 -50.23866)
				)
				(arc
					(start 10.8712 -50.23866)
					(mid 10.833483 -50.254283)
					(end 10.81786 -50.292)
				)
			)
		)
	)
	(zone
		(layer "In1.Cu")
		(hatch none 0.5)
		(connect_pads
			(clearance 0)
		)
		(min_thickness 0.25)
		(keepout
			(tracks not_allowed)
			(vias allowed)
			(pads allowed)
			(copperpour not_allowed)
			(footprints allowed)
		)
		(placement
			(enabled no)
			(sheetname "")
		)
		(fill
			(thermal_gap 0.5)
			(thermal_bridge_width 0.5)
			(island_removal_mode 0)
		)
		(polygon
			(pts
				(arc
					(start 8.65886 -59.3852)
					(mid 8.674483 -59.422917)
					(end 8.7122 -59.43854)
				)
				(arc
					(start 9.0678 -59.43854)
					(mid 9.105517 -59.422917)
					(end 9.12114 -59.3852)
				)
				(arc
					(start 9.12114 -58.9788)
					(mid 9.105517 -58.941083)
					(end 9.0678 -58.92546)
				)
				(arc
					(start 8.7122 -58.92546)
					(mid 8.674483 -58.941083)
					(end 8.65886 -58.9788)
				)
			)
		)
	)
	(zone
		(layer "In1.Cu")
		(hatch none 0.5)
		(connect_pads
			(clearance 0)
		)
		(min_thickness 0.25)
		(keepout
			(tracks not_allowed)
			(vias allowed)
			(pads allowed)
			(copperpour not_allowed)
			(footprints allowed)
		)
		(placement
			(enabled no)
			(sheetname "")
		)
		(fill
			(thermal_gap 0.5)
			(thermal_bridge_width 0.5)
			(island_removal_mode 0)
		)
		(polygon
			(pts
				(arc
					(start 7.89686 -59.3852)
					(mid 7.912483 -59.422917)
					(end 7.9502 -59.43854)
				)
				(arc
					(start 8.3058 -59.43854)
					(mid 8.343517 -59.422917)
					(end 8.35914 -59.3852)
				)
				(arc
					(start 8.35914 -58.9788)
					(mid 8.343517 -58.941083)
					(end 8.3058 -58.92546)
				)
				(arc
					(start 7.9502 -58.92546)
					(mid 7.912483 -58.941083)
					(end 7.89686 -58.9788)
				)
			)
		)
	)
	(zone
		(layer "In1.Cu")
		(hatch none 0.5)
		(connect_pads
			(clearance 0)
		)
		(min_thickness 0.25)
		(keepout
			(tracks not_allowed)
			(vias allowed)
			(pads allowed)
			(copperpour not_allowed)
			(footprints allowed)
		)
		(placement
			(enabled no)
			(sheetname "")
		)
		(fill
			(thermal_gap 0.5)
			(thermal_bridge_width 0.5)
			(island_removal_mode 0)
		)
		(polygon
			(pts
				(arc
					(start 63.8302 -13.43914)
					(mid 63.867917 -13.423517)
					(end 63.88354 -13.3858)
				)
				(arc
					(start 63.88354 -13.0302)
					(mid 63.867917 -12.992483)
					(end 63.8302 -12.97686)
				)
				(arc
					(start 63.4238 -12.97686)
					(mid 63.386083 -12.992483)
					(end 63.37046 -13.0302)
				)
				(arc
					(start 63.37046 -13.3858)
					(mid 63.386083 -13.423517)
					(end 63.4238 -13.43914)
				)
			)
		)
	)
	(zone
		(layer "In1.Cu")
		(hatch none 0.5)
		(connect_pads
			(clearance 0)
		)
		(min_thickness 0.25)
		(keepout
			(tracks not_allowed)
			(vias allowed)
			(pads allowed)
			(copperpour not_allowed)
			(footprints allowed)
		)
		(placement
			(enabled no)
			(sheetname "")
		)
		(fill
			(thermal_gap 0.5)
			(thermal_bridge_width 0.5)
			(island_removal_mode 0)
		)
		(polygon
			(pts
				(arc
					(start 52.0192 -12.21486)
					(mid 51.981483 -12.230483)
					(end 51.96586 -12.2682)
				)
				(arc
					(start 51.96586 -12.6238)
					(mid 51.981483 -12.661517)
					(end 52.0192 -12.67714)
				)
				(arc
					(start 52.4256 -12.67714)
					(mid 52.463317 -12.661517)
					(end 52.47894 -12.6238)
				)
				(arc
					(start 52.47894 -12.2682)
					(mid 52.463317 -12.230483)
					(end 52.4256 -12.21486)
				)
			)
		)
	)
	(zone
		(layer "In1.Cu")
		(hatch none 0.5)
		(connect_pads
			(clearance 0)
		)
		(min_thickness 0.25)
		(keepout
			(tracks not_allowed)
			(vias allowed)
			(pads allowed)
			(copperpour not_allowed)
			(footprints allowed)
		)
		(placement
			(enabled no)
			(sheetname "")
		)
		(fill
			(thermal_gap 0.5)
			(thermal_bridge_width 0.5)
			(island_removal_mode 0)
		)
		(polygon
			(pts
				(arc
					(start 52.7812 -12.97686)
					(mid 52.743483 -12.992483)
					(end 52.72786 -13.0302)
				)
				(arc
					(start 52.72786 -13.3858)
					(mid 52.743483 -13.423517)
					(end 52.7812 -13.43914)
				)
				(arc
					(start 53.1876 -13.43914)
					(mid 53.225317 -13.423517)
					(end 53.24094 -13.3858)
				)
				(arc
					(start 53.24094 -13.0302)
					(mid 53.225317 -12.992483)
					(end 53.1876 -12.97686)
				)
			)
		)
	)
	(zone
		(layer "In1.Cu")
		(hatch none 0.5)
		(connect_pads
			(clearance 0)
		)
		(min_thickness 0.25)
		(keepout
			(tracks not_allowed)
			(vias allowed)
			(pads allowed)
			(copperpour not_allowed)
			(footprints allowed)
		)
		(placement
			(enabled no)
			(sheetname "")
		)
		(fill
			(thermal_gap 0.5)
			(thermal_bridge_width 0.5)
			(island_removal_mode 0)
		)
		(polygon
			(pts
				(arc
					(start 8.65886 -65.6082)
					(mid 8.674483 -65.645917)
					(end 8.7122 -65.66154)
				)
				(arc
					(start 9.0678 -65.66154)
					(mid 9.105517 -65.645917)
					(end 9.12114 -65.6082)
				)
				(arc
					(start 9.12114 -65.2018)
					(mid 9.105517 -65.164083)
					(end 9.0678 -65.14846)
				)
				(arc
					(start 8.7122 -65.14846)
					(mid 8.674483 -65.164083)
					(end 8.65886 -65.2018)
				)
			)
		)
	)
	(zone
		(layer "In1.Cu")
		(hatch none 0.5)
		(connect_pads
			(clearance 0)
		)
		(min_thickness 0.25)
		(keepout
			(tracks not_allowed)
			(vias allowed)
			(pads allowed)
			(copperpour not_allowed)
			(footprints allowed)
		)
		(placement
			(enabled no)
			(sheetname "")
		)
		(fill
			(thermal_gap 0.5)
			(thermal_bridge_width 0.5)
			(island_removal_mode 0)
		)
		(polygon
			(pts
				(arc
					(start 63.8302 -14.20114)
					(mid 63.867917 -14.185517)
					(end 63.88354 -14.1478)
				)
				(arc
					(start 63.88354 -13.7922)
					(mid 63.867917 -13.754483)
					(end 63.8302 -13.73886)
				)
				(arc
					(start 63.4238 -13.73886)
					(mid 63.386083 -13.754483)
					(end 63.37046 -13.7922)
				)
				(arc
					(start 63.37046 -14.1478)
					(mid 63.386083 -14.185517)
					(end 63.4238 -14.20114)
				)
			)
		)
	)
	(zone
		(layer "In1.Cu")
		(hatch none 0.5)
		(connect_pads
			(clearance 0)
		)
		(min_thickness 0.25)
		(keepout
			(tracks not_allowed)
			(vias allowed)
			(pads allowed)
			(copperpour not_allowed)
			(footprints allowed)
		)
		(placement
			(enabled no)
			(sheetname "")
		)
		(fill
			(thermal_gap 0.5)
			(thermal_bridge_width 0.5)
			(island_removal_mode 0)
		)
		(polygon
			(pts
				(arc
					(start 12.29106 -54.229)
					(mid 12.306683 -54.266717)
					(end 12.3444 -54.28234)
				)
				(arc
					(start 12.7 -54.28234)
					(mid 12.737717 -54.266717)
					(end 12.75334 -54.229)
				)
				(arc
					(start 12.75334 -53.8226)
					(mid 12.737717 -53.784883)
					(end 12.7 -53.76926)
				)
				(arc
					(start 12.3444 -53.76926)
					(mid 12.306683 -53.784883)
					(end 12.29106 -53.8226)
				)
			)
		)
	)
	(zone
		(layer "In1.Cu")
		(hatch none 0.5)
		(connect_pads
			(clearance 0)
		)
		(min_thickness 0.25)
		(keepout
			(tracks not_allowed)
			(vias allowed)
			(pads allowed)
			(copperpour not_allowed)
			(footprints allowed)
		)
		(placement
			(enabled no)
			(sheetname "")
		)
		(fill
			(thermal_gap 0.5)
			(thermal_bridge_width 0.5)
			(island_removal_mode 0)
		)
		(polygon
			(pts
				(arc
					(start 7.89686 -65.6082)
					(mid 7.912483 -65.645917)
					(end 7.9502 -65.66154)
				)
				(arc
					(start 8.3058 -65.66154)
					(mid 8.343517 -65.645917)
					(end 8.35914 -65.6082)
				)
				(arc
					(start 8.35914 -65.2018)
					(mid 8.343517 -65.164083)
					(end 8.3058 -65.14846)
				)
				(arc
					(start 7.9502 -65.14846)
					(mid 7.912483 -65.164083)
					(end 7.89686 -65.2018)
				)
			)
		)
	)
	(zone
		(layer "In1.Cu")
		(hatch none 0.5)
		(connect_pads
			(clearance 0)
		)
		(min_thickness 0.25)
		(keepout
			(tracks not_allowed)
			(vias allowed)
			(pads allowed)
			(copperpour not_allowed)
			(footprints allowed)
		)
		(placement
			(enabled no)
			(sheetname "")
		)
		(fill
			(thermal_gap 0.5)
			(thermal_bridge_width 0.5)
			(island_removal_mode 0)
		)
		(polygon
			(pts
				(arc
					(start 8.65886 -64.7192)
					(mid 8.674483 -64.756917)
					(end 8.7122 -64.77254)
				)
				(arc
					(start 9.0678 -64.77254)
					(mid 9.105517 -64.756917)
					(end 9.12114 -64.7192)
				)
				(arc
					(start 9.12114 -64.3128)
					(mid 9.105517 -64.275083)
					(end 9.0678 -64.25946)
				)
				(arc
					(start 8.7122 -64.25946)
					(mid 8.674483 -64.275083)
					(end 8.65886 -64.3128)
				)
			)
		)
	)
	(zone
		(layer "In1.Cu")
		(hatch none 0.5)
		(connect_pads
			(clearance 0)
		)
		(min_thickness 0.25)
		(keepout
			(tracks not_allowed)
			(vias allowed)
			(pads allowed)
			(copperpour not_allowed)
			(footprints allowed)
		)
		(placement
			(enabled no)
			(sheetname "")
		)
		(fill
			(thermal_gap 0.5)
			(thermal_bridge_width 0.5)
			(island_removal_mode 0)
		)
		(polygon
			(pts
				(xy 67.991736 -4.097528) (xy 68.708016 -4.097528) (xy 68.708016 -8.293608) (xy 67.991736 -8.293608)
			)
		)
	)
	(zone
		(layer "In1.Cu")
		(hatch none 0.5)
		(connect_pads
			(clearance 0)
		)
		(min_thickness 0.25)
		(keepout
			(tracks not_allowed)
			(vias allowed)
			(pads allowed)
			(copperpour not_allowed)
			(footprints allowed)
		)
		(placement
			(enabled no)
			(sheetname "")
		)
		(fill
			(thermal_gap 0.5)
			(thermal_bridge_width 0.5)
			(island_removal_mode 0)
		)
		(polygon
			(pts
				(arc
					(start 50.419 -12.55014)
					(mid 50.456717 -12.534517)
					(end 50.47234 -12.4968)
				)
				(arc
					(start 50.47234 -12.1412)
					(mid 50.456717 -12.103483)
					(end 50.419 -12.08786)
				)
				(arc
					(start 50.0126 -12.08786)
					(mid 49.974883 -12.103483)
					(end 49.95926 -12.1412)
				)
				(arc
					(start 49.95926 -12.4968)
					(mid 49.974883 -12.534517)
					(end 50.0126 -12.55014)
				)
			)
		)
	)
	(zone
		(layer "In1.Cu")
		(hatch none 0.5)
		(connect_pads
			(clearance 0)
		)
		(min_thickness 0.25)
		(keepout
			(tracks not_allowed)
			(vias allowed)
			(pads allowed)
			(copperpour not_allowed)
			(footprints allowed)
		)
		(placement
			(enabled no)
			(sheetname "")
		)
		(fill
			(thermal_gap 0.5)
			(thermal_bridge_width 0.5)
			(island_removal_mode 0)
		)
		(polygon
			(pts
				(arc
					(start 8.65886 -58.4962)
					(mid 8.674483 -58.533917)
					(end 8.7122 -58.54954)
				)
				(arc
					(start 9.0678 -58.54954)
					(mid 9.105517 -58.533917)
					(end 9.12114 -58.4962)
				)
				(arc
					(start 9.12114 -58.0898)
					(mid 9.105517 -58.052083)
					(end 9.0678 -58.03646)
				)
				(arc
					(start 8.7122 -58.03646)
					(mid 8.674483 -58.052083)
					(end 8.65886 -58.0898)
				)
			)
		)
	)
	(zone
		(layer "In1.Cu")
		(hatch none 0.5)
		(connect_pads
			(clearance 0)
		)
		(min_thickness 0.25)
		(keepout
			(tracks not_allowed)
			(vias allowed)
			(pads allowed)
			(copperpour not_allowed)
			(footprints allowed)
		)
		(placement
			(enabled no)
			(sheetname "")
		)
		(fill
			(thermal_gap 0.5)
			(thermal_bridge_width 0.5)
			(island_removal_mode 0)
		)
		(polygon
			(pts
				(xy 51.991768 -4.097528) (xy 52.708048 -4.097528) (xy 52.708048 -8.293608) (xy 51.991768 -8.293608)
			)
		)
	)
	(zone
		(layer "In1.Cu")
		(hatch none 0.5)
		(connect_pads
			(clearance 0)
		)
		(min_thickness 0.25)
		(keepout
			(tracks not_allowed)
			(vias allowed)
			(pads allowed)
			(copperpour not_allowed)
			(footprints allowed)
		)
		(placement
			(enabled no)
			(sheetname "")
		)
		(fill
			(thermal_gap 0.5)
			(thermal_bridge_width 0.5)
			(island_removal_mode 0)
		)
		(polygon
			(pts
				(arc
					(start 10.05586 -51.943)
					(mid 10.071483 -51.980717)
					(end 10.1092 -51.99634)
				)
				(arc
					(start 10.4648 -51.99634)
					(mid 10.502517 -51.980717)
					(end 10.51814 -51.943)
				)
				(arc
					(start 10.51814 -51.5366)
					(mid 10.502517 -51.498883)
					(end 10.4648 -51.48326)
				)
				(arc
					(start 10.1092 -51.48326)
					(mid 10.071483 -51.498883)
					(end 10.05586 -51.5366)
				)
			)
		)
	)
	(zone
		(layer "In1.Cu")
		(hatch none 0.5)
		(connect_pads
			(clearance 0)
		)
		(min_thickness 0.25)
		(keepout
			(tracks not_allowed)
			(vias allowed)
			(pads allowed)
			(copperpour not_allowed)
			(footprints allowed)
		)
		(placement
			(enabled no)
			(sheetname "")
		)
		(fill
			(thermal_gap 0.5)
			(thermal_bridge_width 0.5)
			(island_removal_mode 0)
		)
		(polygon
			(pts
				(xy 70.99173 -4.097528) (xy 71.70801 -4.097528) (xy 71.70801 -8.293608) (xy 70.99173 -8.293608)
			)
		)
	)
	(zone
		(layer "In1.Cu")
		(hatch none 0.5)
		(connect_pads
			(clearance 0)
		)
		(min_thickness 0.25)
		(keepout
			(tracks not_allowed)
			(vias allowed)
			(pads allowed)
			(copperpour not_allowed)
			(footprints allowed)
		)
		(placement
			(enabled no)
			(sheetname "")
		)
		(fill
			(thermal_gap 0.5)
			(thermal_bridge_width 0.5)
			(island_removal_mode 0)
		)
		(polygon
			(pts
				(arc
					(start 7.89686 -62.0522)
					(mid 7.912483 -62.089917)
					(end 7.9502 -62.10554)
				)
				(arc
					(start 8.3058 -62.10554)
					(mid 8.343517 -62.089917)
					(end 8.35914 -62.0522)
				)
				(arc
					(start 8.35914 -61.6458)
					(mid 8.343517 -61.608083)
					(end 8.3058 -61.59246)
				)
				(arc
					(start 7.9502 -61.59246)
					(mid 7.912483 -61.608083)
					(end 7.89686 -61.6458)
				)
			)
		)
	)
	(zone
		(layer "In1.Cu")
		(hatch none 0.5)
		(connect_pads
			(clearance 0)
		)
		(min_thickness 0.25)
		(keepout
			(tracks not_allowed)
			(vias allowed)
			(pads allowed)
			(copperpour not_allowed)
			(footprints allowed)
		)
		(placement
			(enabled no)
			(sheetname "")
		)
		(fill
			(thermal_gap 0.5)
			(thermal_bridge_width 0.5)
			(island_removal_mode 0)
		)
		(polygon
			(pts
				(xy 58.991754 -4.097528) (xy 59.708034 -4.097528) (xy 59.708034 -8.293608) (xy 58.991754 -8.293608)
			)
		)
	)
	(zone
		(layer "In1.Cu")
		(hatch none 0.5)
		(connect_pads
			(clearance 0)
		)
		(min_thickness 0.25)
		(keepout
			(tracks not_allowed)
			(vias allowed)
			(pads allowed)
			(copperpour not_allowed)
			(footprints allowed)
		)
		(placement
			(enabled no)
			(sheetname "")
		)
		(fill
			(thermal_gap 0.5)
			(thermal_bridge_width 0.5)
			(island_removal_mode 0)
		)
		(polygon
			(pts
				(arc
					(start 7.89686 -55.8292)
					(mid 7.912483 -55.866917)
					(end 7.9502 -55.88254)
				)
				(arc
					(start 8.3058 -55.88254)
					(mid 8.343517 -55.866917)
					(end 8.35914 -55.8292)
				)
				(arc
					(start 8.35914 -55.4228)
					(mid 8.343517 -55.385083)
					(end 8.3058 -55.36946)
				)
				(arc
					(start 7.9502 -55.36946)
					(mid 7.912483 -55.385083)
					(end 7.89686 -55.4228)
				)
			)
		)
	)
	(zone
		(layer "In1.Cu")
		(hatch none 0.5)
		(connect_pads
			(clearance 0)
		)
		(min_thickness 0.25)
		(keepout
			(tracks not_allowed)
			(vias allowed)
			(pads allowed)
			(copperpour not_allowed)
			(footprints allowed)
		)
		(placement
			(enabled no)
			(sheetname "")
		)
		(fill
			(thermal_gap 0.5)
			(thermal_bridge_width 0.5)
			(island_removal_mode 0)
		)
		(polygon
			(pts
				(xy 59.991752 -4.097528) (xy 60.708032 -4.097528) (xy 60.708032 -8.293608) (xy 59.991752 -8.293608)
			)
		)
	)
	(zone
		(layer "In1.Cu")
		(hatch none 0.5)
		(connect_pads
			(clearance 0)
		)
		(min_thickness 0.25)
		(keepout
			(tracks not_allowed)
			(vias allowed)
			(pads allowed)
			(copperpour not_allowed)
			(footprints allowed)
		)
		(placement
			(enabled no)
			(sheetname "")
		)
		(fill
			(thermal_gap 0.5)
			(thermal_bridge_width 0.5)
			(island_removal_mode 0)
		)
		(polygon
			(pts
				(arc
					(start 7.89686 -58.4962)
					(mid 7.912483 -58.533917)
					(end 7.9502 -58.54954)
				)
				(arc
					(start 8.3058 -58.54954)
					(mid 8.343517 -58.533917)
					(end 8.35914 -58.4962)
				)
				(arc
					(start 8.35914 -58.0898)
					(mid 8.343517 -58.052083)
					(end 8.3058 -58.03646)
				)
				(arc
					(start 7.9502 -58.03646)
					(mid 7.912483 -58.052083)
					(end 7.89686 -58.0898)
				)
			)
		)
	)
	(zone
		(layer "In1.Cu")
		(hatch none 0.5)
		(connect_pads
			(clearance 0)
		)
		(min_thickness 0.25)
		(keepout
			(tracks not_allowed)
			(vias allowed)
			(pads allowed)
			(copperpour not_allowed)
			(footprints allowed)
		)
		(placement
			(enabled no)
			(sheetname "")
		)
		(fill
			(thermal_gap 0.5)
			(thermal_bridge_width 0.5)
			(island_removal_mode 0)
		)
		(polygon
			(pts
				(arc
					(start 11.57986 -51.943)
					(mid 11.595483 -51.980717)
					(end 11.6332 -51.99634)
				)
				(arc
					(start 11.9888 -51.99634)
					(mid 12.026517 -51.980717)
					(end 12.04214 -51.943)
				)
				(arc
					(start 12.04214 -51.5366)
					(mid 12.026517 -51.498883)
					(end 11.9888 -51.48326)
				)
				(arc
					(start 11.6332 -51.48326)
					(mid 11.595483 -51.498883)
					(end 11.57986 -51.5366)
				)
			)
		)
	)
	(zone
		(layer "In1.Cu")
		(hatch none 0.5)
		(connect_pads
			(clearance 0)
		)
		(min_thickness 0.25)
		(keepout
			(tracks not_allowed)
			(vias allowed)
			(pads allowed)
			(copperpour not_allowed)
			(footprints allowed)
		)
		(placement
			(enabled no)
			(sheetname "")
		)
		(fill
			(thermal_gap 0.5)
			(thermal_bridge_width 0.5)
			(island_removal_mode 0)
		)
		(polygon
			(pts
				(arc
					(start 7.89686 -57.6072)
					(mid 7.912483 -57.644917)
					(end 7.9502 -57.66054)
				)
				(arc
					(start 8.3058 -57.66054)
					(mid 8.343517 -57.644917)
					(end 8.35914 -57.6072)
				)
				(arc
					(start 8.35914 -57.2008)
					(mid 8.343517 -57.163083)
					(end 8.3058 -57.14746)
				)
				(arc
					(start 7.9502 -57.14746)
					(mid 7.912483 -57.163083)
					(end 7.89686 -57.2008)
				)
			)
		)
	)
	(zone
		(layer "In1.Cu")
		(hatch none 0.5)
		(connect_pads
			(clearance 0)
		)
		(min_thickness 0.25)
		(keepout
			(tracks not_allowed)
			(vias allowed)
			(pads allowed)
			(copperpour not_allowed)
			(footprints allowed)
		)
		(placement
			(enabled no)
			(sheetname "")
		)
		(fill
			(thermal_gap 0.5)
			(thermal_bridge_width 0.5)
			(island_removal_mode 0)
		)
		(polygon
			(pts
				(arc
					(start 10.81786 -51.943)
					(mid 10.833483 -51.980717)
					(end 10.8712 -51.99634)
				)
				(arc
					(start 11.2268 -51.99634)
					(mid 11.264517 -51.980717)
					(end 11.28014 -51.943)
				)
				(arc
					(start 11.28014 -51.5366)
					(mid 11.264517 -51.498883)
					(end 11.2268 -51.48326)
				)
				(arc
					(start 10.8712 -51.48326)
					(mid 10.833483 -51.498883)
					(end 10.81786 -51.5366)
				)
			)
		)
	)
	(zone
		(layer "In1.Cu")
		(hatch none 0.5)
		(connect_pads
			(clearance 0)
		)
		(min_thickness 0.25)
		(keepout
			(tracks not_allowed)
			(vias allowed)
			(pads allowed)
			(copperpour not_allowed)
			(footprints allowed)
		)
		(placement
			(enabled no)
			(sheetname "")
		)
		(fill
			(thermal_gap 0.5)
			(thermal_bridge_width 0.5)
			(island_removal_mode 0)
		)
		(polygon
			(pts
				(arc
					(start 11.57986 -50.6984)
					(mid 11.595483 -50.736117)
					(end 11.6332 -50.75174)
				)
				(arc
					(start 11.9888 -50.75174)
					(mid 12.026517 -50.736117)
					(end 12.04214 -50.6984)
				)
				(arc
					(start 12.04214 -50.292)
					(mid 12.026517 -50.254283)
					(end 11.9888 -50.23866)
				)
				(arc
					(start 11.6332 -50.23866)
					(mid 11.595483 -50.254283)
					(end 11.57986 -50.292)
				)
			)
		)
	)
	(zone
		(layer "In1.Cu")
		(hatch none 0.5)
		(connect_pads
			(clearance 0)
		)
		(min_thickness 0.25)
		(keepout
			(tracks not_allowed)
			(vias allowed)
			(pads allowed)
			(copperpour not_allowed)
			(footprints allowed)
		)
		(placement
			(enabled no)
			(sheetname "")
		)
		(fill
			(thermal_gap 0.5)
			(thermal_bridge_width 0.5)
			(island_removal_mode 0)
		)
		(polygon
			(pts
				(xy 35.9918 -4.097528) (xy 36.70808 -4.097528) (xy 36.70808 -8.293608) (xy 35.9918 -8.293608)
			)
		)
	)
	(zone
		(layer "In1.Cu")
		(hatch none 0.5)
		(connect_pads
			(clearance 0)
		)
		(min_thickness 0.25)
		(keepout
			(tracks not_allowed)
			(vias allowed)
			(pads allowed)
			(copperpour not_allowed)
			(footprints allowed)
		)
		(placement
			(enabled no)
			(sheetname "")
		)
		(fill
			(thermal_gap 0.5)
			(thermal_bridge_width 0.5)
			(island_removal_mode 0)
		)
		(polygon
			(pts
				(xy 39.991792 -4.097528) (xy 40.708072 -4.097528) (xy 40.708072 -8.293608) (xy 39.991792 -8.293608)
			)
		)
	)
	(zone
		(layer "In1.Cu")
		(hatch none 0.5)
		(connect_pads
			(clearance 0)
		)
		(min_thickness 0.25)
		(keepout
			(tracks not_allowed)
			(vias allowed)
			(pads allowed)
			(copperpour not_allowed)
			(footprints allowed)
		)
		(placement
			(enabled no)
			(sheetname "")
		)
		(fill
			(thermal_gap 0.5)
			(thermal_bridge_width 0.5)
			(island_removal_mode 0)
		)
		(polygon
			(pts
				(xy 30.99181 -4.097528) (xy 31.70809 -4.097528) (xy 31.70809 -8.293608) (xy 30.99181 -8.293608)
			)
		)
	)
	(zone
		(layer "In1.Cu")
		(hatch none 0.5)
		(connect_pads
			(clearance 0)
		)
		(min_thickness 0.25)
		(keepout
			(tracks not_allowed)
			(vias allowed)
			(pads allowed)
			(copperpour not_allowed)
			(footprints allowed)
		)
		(placement
			(enabled no)
			(sheetname "")
		)
		(fill
			(thermal_gap 0.5)
			(thermal_bridge_width 0.5)
			(island_removal_mode 0)
		)
		(polygon
			(pts
				(xy 34.991802 -4.097528) (xy 35.708082 -4.097528) (xy 35.708082 -8.293608) (xy 34.991802 -8.293608)
			)
		)
	)
	(zone
		(layer "In1.Cu")
		(hatch none 0.5)
		(connect_pads
			(clearance 0)
		)
		(min_thickness 0.25)
		(keepout
			(tracks not_allowed)
			(vias allowed)
			(pads allowed)
			(copperpour not_allowed)
			(footprints allowed)
		)
		(placement
			(enabled no)
			(sheetname "")
		)
		(fill
			(thermal_gap 0.5)
			(thermal_bridge_width 0.5)
			(island_removal_mode 0)
		)
		(polygon
			(pts
				(xy 83.991704 -4.097528) (xy 84.707984 -4.097528) (xy 84.707984 -8.293608) (xy 83.991704 -8.293608)
			)
		)
	)
	(zone
		(layer "In1.Cu")
		(hatch none 0.5)
		(connect_pads
			(clearance 0)
		)
		(min_thickness 0.25)
		(keepout
			(tracks not_allowed)
			(vias allowed)
			(pads allowed)
			(copperpour not_allowed)
			(footprints allowed)
		)
		(placement
			(enabled no)
			(sheetname "")
		)
		(fill
			(thermal_gap 0.5)
			(thermal_bridge_width 0.5)
			(island_removal_mode 0)
		)
		(polygon
			(pts
				(xy 23.991824 -4.097528) (xy 24.708104 -4.097528) (xy 24.708104 -8.293608) (xy 23.991824 -8.293608)
			)
		)
	)
	(zone
		(layer "In1.Cu")
		(hatch none 0.5)
		(connect_pads
			(clearance 0)
		)
		(min_thickness 0.25)
		(keepout
			(tracks not_allowed)
			(vias allowed)
			(pads allowed)
			(copperpour not_allowed)
			(footprints allowed)
		)
		(placement
			(enabled no)
			(sheetname "")
		)
		(fill
			(thermal_gap 0.5)
			(thermal_bridge_width 0.5)
			(island_removal_mode 0)
		)
		(polygon
			(pts
				(arc
					(start 8.65886 -62.9412)
					(mid 8.674483 -62.978917)
					(end 8.7122 -62.99454)
				)
				(arc
					(start 9.0678 -62.99454)
					(mid 9.105517 -62.978917)
					(end 9.12114 -62.9412)
				)
				(arc
					(start 9.12114 -62.5348)
					(mid 9.105517 -62.497083)
					(end 9.0678 -62.48146)
				)
				(arc
					(start 8.7122 -62.48146)
					(mid 8.674483 -62.497083)
					(end 8.65886 -62.5348)
				)
			)
		)
	)
	(zone
		(layer "In1.Cu")
		(hatch none 0.5)
		(connect_pads
			(clearance 0)
		)
		(min_thickness 0.25)
		(keepout
			(tracks not_allowed)
			(vias allowed)
			(pads allowed)
			(copperpour not_allowed)
			(footprints allowed)
		)
		(placement
			(enabled no)
			(sheetname "")
		)
		(fill
			(thermal_gap 0.5)
			(thermal_bridge_width 0.5)
			(island_removal_mode 0)
		)
		(polygon
			(pts
				(arc
					(start 7.89686 -56.7182)
					(mid 7.912483 -56.755917)
					(end 7.9502 -56.77154)
				)
				(arc
					(start 8.3058 -56.77154)
					(mid 8.343517 -56.755917)
					(end 8.35914 -56.7182)
				)
				(arc
					(start 8.35914 -56.3118)
					(mid 8.343517 -56.274083)
					(end 8.3058 -56.25846)
				)
				(arc
					(start 7.9502 -56.25846)
					(mid 7.912483 -56.274083)
					(end 7.89686 -56.3118)
				)
			)
		)
	)
	(zone
		(layer "In1.Cu")
		(hatch none 0.5)
		(connect_pads
			(clearance 0)
		)
		(min_thickness 0.25)
		(keepout
			(tracks not_allowed)
			(vias allowed)
			(pads allowed)
			(copperpour not_allowed)
			(footprints allowed)
		)
		(placement
			(enabled no)
			(sheetname "")
		)
		(fill
			(thermal_gap 0.5)
			(thermal_bridge_width 0.5)
			(island_removal_mode 0)
		)
		(polygon
			(pts
				(arc
					(start 8.65886 -60.2742)
					(mid 8.674483 -60.311917)
					(end 8.7122 -60.32754)
				)
				(arc
					(start 9.0678 -60.32754)
					(mid 9.105517 -60.311917)
					(end 9.12114 -60.2742)
				)
				(arc
					(start 9.12114 -59.8678)
					(mid 9.105517 -59.830083)
					(end 9.0678 -59.81446)
				)
				(arc
					(start 8.7122 -59.81446)
					(mid 8.674483 -59.830083)
					(end 8.65886 -59.8678)
				)
			)
		)
	)
	(zone
		(layer "In1.Cu")
		(hatch none 0.5)
		(connect_pads
			(clearance 0)
		)
		(min_thickness 0.25)
		(keepout
			(tracks not_allowed)
			(vias allowed)
			(pads allowed)
			(copperpour not_allowed)
			(footprints allowed)
		)
		(placement
			(enabled no)
			(sheetname "")
		)
		(fill
			(thermal_gap 0.5)
			(thermal_bridge_width 0.5)
			(island_removal_mode 0)
		)
		(polygon
			(pts
				(xy 79.991712 -4.097528) (xy 80.707992 -4.097528) (xy 80.707992 -8.293608) (xy 79.991712 -8.293608)
			)
		)
	)
	(zone
		(net "PV_VDDR")
		(layer "In1.Cu")
		(hatch none 0.5)
		(connect_pads
			(clearance 0.5)
		)
		(min_thickness 0.25)
		(fill yes
			(thermal_gap 0.5)
			(thermal_bridge_width 0.5)
			(island_removal_mode 0)
		)
		(polygon
			(pts
				(xy 148.160994 -59.1185) (xy 148.0185 -59.260994) (xy 148.0185 -61.135006) (xy 148.6535 -61.770006)
				(xy 148.6535 -71.422006) (xy 148.795994 -71.5645) (xy 162.481006 -71.5645) (xy 162.6235 -71.422006)
				(xy 162.6235 -62.689994) (xy 161.703766 -61.770006) (xy 160.068006 -60.1345) (xy 150.924006 -60.1345)
				(xy 149.908006 -59.1185)
			)
		)
	)
	(zone
		(layer "In1.Cu")
		(hatch none 0.5)
		(connect_pads
			(clearance 0)
		)
		(min_thickness 0.25)
		(keepout
			(tracks not_allowed)
			(vias allowed)
			(pads allowed)
			(copperpour not_allowed)
			(footprints allowed)
		)
		(placement
			(enabled no)
			(sheetname "")
		)
		(fill
			(thermal_gap 0.5)
			(thermal_bridge_width 0.5)
			(island_removal_mode 0)
		)
		(polygon
			(pts
				(arc
					(start 52.0192 -12.97686)
					(mid 51.981483 -12.992483)
					(end 51.96586 -13.0302)
				)
				(arc
					(start 51.96586 -13.3858)
					(mid 51.981483 -13.423517)
					(end 52.0192 -13.43914)
				)
				(arc
					(start 52.4256 -13.43914)
					(mid 52.463317 -13.423517)
					(end 52.47894 -13.3858)
				)
				(arc
					(start 52.47894 -13.0302)
					(mid 52.463317 -12.992483)
					(end 52.4256 -12.97686)
				)
			)
		)
	)
	(zone
		(layer "In1.Cu")
		(hatch none 0.5)
		(connect_pads
			(clearance 0)
		)
		(min_thickness 0.25)
		(keepout
			(tracks not_allowed)
			(vias allowed)
			(pads allowed)
			(copperpour not_allowed)
			(footprints allowed)
		)
		(placement
			(enabled no)
			(sheetname "")
		)
		(fill
			(thermal_gap 0.5)
			(thermal_bridge_width 0.5)
			(island_removal_mode 0)
		)
		(polygon
			(pts
				(xy 62.991746 -4.097528) (xy 63.708026 -4.097528) (xy 63.708026 -8.293608) (xy 62.991746 -8.293608)
			)
		)
	)
	(zone
		(layer "In1.Cu")
		(hatch none 0.5)
		(connect_pads
			(clearance 0)
		)
		(min_thickness 0.25)
		(keepout
			(tracks not_allowed)
			(vias allowed)
			(pads allowed)
			(copperpour not_allowed)
			(footprints allowed)
		)
		(placement
			(enabled no)
			(sheetname "")
		)
		(fill
			(thermal_gap 0.5)
			(thermal_bridge_width 0.5)
			(island_removal_mode 0)
		)
		(polygon
			(pts
				(arc
					(start 49.657 -12.55014)
					(mid 49.694717 -12.534517)
					(end 49.71034 -12.4968)
				)
				(arc
					(start 49.71034 -12.1412)
					(mid 49.694717 -12.103483)
					(end 49.657 -12.08786)
				)
				(arc
					(start 49.2506 -12.08786)
					(mid 49.212883 -12.103483)
					(end 49.19726 -12.1412)
				)
				(arc
					(start 49.19726 -12.4968)
					(mid 49.212883 -12.534517)
					(end 49.2506 -12.55014)
				)
			)
		)
	)
	(zone
		(layer "In1.Cu")
		(hatch none 0.5)
		(connect_pads
			(clearance 0)
		)
		(min_thickness 0.25)
		(keepout
			(tracks not_allowed)
			(vias allowed)
			(pads allowed)
			(copperpour not_allowed)
			(footprints allowed)
		)
		(placement
			(enabled no)
			(sheetname "")
		)
		(fill
			(thermal_gap 0.5)
			(thermal_bridge_width 0.5)
			(island_removal_mode 0)
		)
		(polygon
			(pts
				(arc
					(start 11.52906 -52.9844)
					(mid 11.544683 -53.022117)
					(end 11.5824 -53.03774)
				)
				(arc
					(start 11.938 -53.03774)
					(mid 11.975717 -53.022117)
					(end 11.99134 -52.9844)
				)
				(arc
					(start 11.99134 -52.578)
					(mid 11.975717 -52.540283)
					(end 11.938 -52.52466)
				)
				(arc
					(start 11.5824 -52.52466)
					(mid 11.544683 -52.540283)
					(end 11.52906 -52.578)
				)
			)
		)
	)
	(zone
		(layer "In1.Cu")
		(hatch none 0.5)
		(connect_pads
			(clearance 0)
		)
		(min_thickness 0.25)
		(keepout
			(tracks not_allowed)
			(vias allowed)
			(pads allowed)
			(copperpour not_allowed)
			(footprints allowed)
		)
		(placement
			(enabled no)
			(sheetname "")
		)
		(fill
			(thermal_gap 0.5)
			(thermal_bridge_width 0.5)
			(island_removal_mode 0)
		)
		(polygon
			(pts
				(xy 42.991786 -4.097528) (xy 43.708066 -4.097528) (xy 43.708066 -8.293608) (xy 42.991786 -8.293608)
			)
		)
	)
	(zone
		(net "PV_VDDR")
		(layer "In1.Cu")
		(hatch none 0.5)
		(connect_pads
			(clearance 0.5)
		)
		(min_thickness 0.25)
		(fill yes
			(thermal_gap 0.5)
			(thermal_bridge_width 0.5)
			(island_removal_mode 0)
		)
		(polygon
			(pts
				(xy 155.8925 -0.763016) (xy 155.8925 -10.208006) (xy 156.4005 -10.716006) (xy 156.4005 -12.367006)
				(xy 156.669994 -12.6365) (xy 167.180006 -12.6365) (xy 169.1005 -10.716006) (xy 169.8625 -9.954006)
				(xy 169.8625 -5.382006) (xy 170.3705 -4.874006) (xy 170.3705 -4.523994) (xy 169.6085 -3.761994)
				(xy 169.6085 -0.763016)
			)
		)
	)
	(zone
		(layer "In1.Cu")
		(hatch none 0.5)
		(connect_pads
			(clearance 0)
		)
		(min_thickness 0.25)
		(keepout
			(tracks not_allowed)
			(vias allowed)
			(pads allowed)
			(copperpour not_allowed)
			(footprints allowed)
		)
		(placement
			(enabled no)
			(sheetname "")
		)
		(fill
			(thermal_gap 0.5)
			(thermal_bridge_width 0.5)
			(island_removal_mode 0)
		)
		(polygon
			(pts
				(xy 71.991728 -4.097528) (xy 72.708008 -4.097528) (xy 72.708008 -8.293608) (xy 71.991728 -8.293608)
			)
		)
	)
	(zone
		(layer "In1.Cu")
		(hatch none 0.5)
		(connect_pads
			(clearance 0)
		)
		(min_thickness 0.25)
		(keepout
			(tracks not_allowed)
			(vias allowed)
			(pads allowed)
			(copperpour not_allowed)
			(footprints allowed)
		)
		(placement
			(enabled no)
			(sheetname "")
		)
		(fill
			(thermal_gap 0.5)
			(thermal_bridge_width 0.5)
			(island_removal_mode 0)
		)
		(polygon
			(pts
				(xy 82.991706 -4.097528) (xy 83.707986 -4.097528) (xy 83.707986 -8.293608) (xy 82.991706 -8.293608)
			)
		)
	)
	(zone
		(layer "In1.Cu")
		(hatch none 0.5)
		(connect_pads
			(clearance 0)
		)
		(min_thickness 0.25)
		(keepout
			(tracks not_allowed)
			(vias allowed)
			(pads allowed)
			(copperpour not_allowed)
			(footprints allowed)
		)
		(placement
			(enabled no)
			(sheetname "")
		)
		(fill
			(thermal_gap 0.5)
			(thermal_bridge_width 0.5)
			(island_removal_mode 0)
		)
		(polygon
			(pts
				(arc
					(start 8.65886 -57.6072)
					(mid 8.674483 -57.644917)
					(end 8.7122 -57.66054)
				)
				(arc
					(start 9.0678 -57.66054)
					(mid 9.105517 -57.644917)
					(end 9.12114 -57.6072)
				)
				(arc
					(start 9.12114 -57.2008)
					(mid 9.105517 -57.163083)
					(end 9.0678 -57.14746)
				)
				(arc
					(start 8.7122 -57.14746)
					(mid 8.674483 -57.163083)
					(end 8.65886 -57.2008)
				)
			)
		)
	)
	(zone
		(layer "In1.Cu")
		(hatch none 0.5)
		(connect_pads
			(clearance 0)
		)
		(min_thickness 0.25)
		(keepout
			(tracks not_allowed)
			(vias allowed)
			(pads allowed)
			(copperpour not_allowed)
			(footprints allowed)
		)
		(placement
			(enabled no)
			(sheetname "")
		)
		(fill
			(thermal_gap 0.5)
			(thermal_bridge_width 0.5)
			(island_removal_mode 0)
		)
		(polygon
			(pts
				(arc
					(start 7.89686 -63.8302)
					(mid 7.912483 -63.867917)
					(end 7.9502 -63.88354)
				)
				(arc
					(start 8.3058 -63.88354)
					(mid 8.343517 -63.867917)
					(end 8.35914 -63.8302)
				)
				(arc
					(start 8.35914 -63.4238)
					(mid 8.343517 -63.386083)
					(end 8.3058 -63.37046)
				)
				(arc
					(start 7.9502 -63.37046)
					(mid 7.912483 -63.386083)
					(end 7.89686 -63.4238)
				)
			)
		)
	)
	(zone
		(layer "In1.Cu")
		(hatch none 0.5)
		(connect_pads
			(clearance 0)
		)
		(min_thickness 0.25)
		(keepout
			(tracks not_allowed)
			(vias allowed)
			(pads allowed)
			(copperpour not_allowed)
			(footprints allowed)
		)
		(placement
			(enabled no)
			(sheetname "")
		)
		(fill
			(thermal_gap 0.5)
			(thermal_bridge_width 0.5)
			(island_removal_mode 0)
		)
		(polygon
			(pts
				(xy 66.991738 -4.097528) (xy 67.708018 -4.097528) (xy 67.708018 -8.293608) (xy 66.991738 -8.293608)
			)
		)
	)
	(zone
		(layer "In1.Cu")
		(hatch none 0.5)
		(connect_pads
			(clearance 0)
		)
		(min_thickness 0.25)
		(keepout
			(tracks not_allowed)
			(vias allowed)
			(pads allowed)
			(copperpour not_allowed)
			(footprints allowed)
		)
		(placement
			(enabled no)
			(sheetname "")
		)
		(fill
			(thermal_gap 0.5)
			(thermal_bridge_width 0.5)
			(island_removal_mode 0)
		)
		(polygon
			(pts
				(xy 47.991776 -4.097528) (xy 48.708056 -4.097528) (xy 48.708056 -8.293608) (xy 47.991776 -8.293608)
			)
		)
	)
	(zone
		(layer "In1.Cu")
		(hatch none 0.5)
		(connect_pads
			(clearance 0)
		)
		(min_thickness 0.25)
		(keepout
			(tracks not_allowed)
			(vias allowed)
			(pads allowed)
			(copperpour not_allowed)
			(footprints allowed)
		)
		(placement
			(enabled no)
			(sheetname "")
		)
		(fill
			(thermal_gap 0.5)
			(thermal_bridge_width 0.5)
			(island_removal_mode 0)
		)
		(polygon
			(pts
				(arc
					(start 8.65886 -55.8292)
					(mid 8.674483 -55.866917)
					(end 8.7122 -55.88254)
				)
				(arc
					(start 9.0678 -55.88254)
					(mid 9.105517 -55.866917)
					(end 9.12114 -55.8292)
				)
				(arc
					(start 9.12114 -55.4228)
					(mid 9.105517 -55.385083)
					(end 9.0678 -55.36946)
				)
				(arc
					(start 8.7122 -55.36946)
					(mid 8.674483 -55.385083)
					(end 8.65886 -55.4228)
				)
			)
		)
	)
	(zone
		(layer "In1.Cu")
		(hatch none 0.5)
		(connect_pads
			(clearance 0)
		)
		(min_thickness 0.25)
		(keepout
			(tracks not_allowed)
			(vias allowed)
			(pads allowed)
			(copperpour not_allowed)
			(footprints allowed)
		)
		(placement
			(enabled no)
			(sheetname "")
		)
		(fill
			(thermal_gap 0.5)
			(thermal_bridge_width 0.5)
			(island_removal_mode 0)
		)
		(polygon
			(pts
				(xy 26.991818 -4.097528) (xy 27.708098 -4.097528) (xy 27.708098 -8.293608) (xy 26.991818 -8.293608)
			)
		)
	)
	(zone
		(layer "In1.Cu")
		(hatch none 0.5)
		(connect_pads
			(clearance 0)
		)
		(min_thickness 0.25)
		(keepout
			(tracks not_allowed)
			(vias allowed)
			(pads allowed)
			(copperpour not_allowed)
			(footprints allowed)
		)
		(placement
			(enabled no)
			(sheetname "")
		)
		(fill
			(thermal_gap 0.5)
			(thermal_bridge_width 0.5)
			(island_removal_mode 0)
		)
		(polygon
			(pts
				(xy 19.991832 -4.097528) (xy 20.708112 -4.097528) (xy 20.708112 -8.293608) (xy 19.991832 -8.293608)
			)
		)
	)
	(zone
		(layer "In1.Cu")
		(hatch none 0.5)
		(connect_pads
			(clearance 0)
		)
		(min_thickness 0.25)
		(keepout
			(tracks not_allowed)
			(vias allowed)
			(pads allowed)
			(copperpour not_allowed)
			(footprints allowed)
		)
		(placement
			(enabled no)
			(sheetname "")
		)
		(fill
			(thermal_gap 0.5)
			(thermal_bridge_width 0.5)
			(island_removal_mode 0)
		)
		(polygon
			(pts
				(xy 63.991744 -4.097528) (xy 64.708024 -4.097528) (xy 64.708024 -8.293608) (xy 63.991744 -8.293608)
			)
		)
	)
	(zone
		(layer "In1.Cu")
		(hatch none 0.5)
		(connect_pads
			(clearance 0)
		)
		(min_thickness 0.25)
		(keepout
			(tracks not_allowed)
			(vias allowed)
			(pads allowed)
			(copperpour not_allowed)
			(footprints allowed)
		)
		(placement
			(enabled no)
			(sheetname "")
		)
		(fill
			(thermal_gap 0.5)
			(thermal_bridge_width 0.5)
			(island_removal_mode 0)
		)
		(polygon
			(pts
				(arc
					(start 11.52906 -54.229)
					(mid 11.544683 -54.266717)
					(end 11.5824 -54.28234)
				)
				(arc
					(start 11.938 -54.28234)
					(mid 11.975717 -54.266717)
					(end 11.99134 -54.229)
				)
				(arc
					(start 11.99134 -53.8226)
					(mid 11.975717 -53.784883)
					(end 11.938 -53.76926)
				)
				(arc
					(start 11.5824 -53.76926)
					(mid 11.544683 -53.784883)
					(end 11.52906 -53.8226)
				)
			)
		)
	)
	(zone
		(layer "In1.Cu")
		(hatch none 0.5)
		(connect_pads
			(clearance 0)
		)
		(min_thickness 0.25)
		(keepout
			(tracks not_allowed)
			(vias allowed)
			(pads allowed)
			(copperpour not_allowed)
			(footprints allowed)
		)
		(placement
			(enabled no)
			(sheetname "")
		)
		(fill
			(thermal_gap 0.5)
			(thermal_bridge_width 0.5)
			(island_removal_mode 0)
		)
		(polygon
			(pts
				(xy 74.991722 -4.097528) (xy 75.708002 -4.097528) (xy 75.708002 -8.293608) (xy 74.991722 -8.293608)
			)
		)
	)
	(zone
		(layer "In1.Cu")
		(hatch none 0.5)
		(connect_pads
			(clearance 0)
		)
		(min_thickness 0.25)
		(keepout
			(tracks not_allowed)
			(vias allowed)
			(pads allowed)
			(copperpour not_allowed)
			(footprints allowed)
		)
		(placement
			(enabled no)
			(sheetname "")
		)
		(fill
			(thermal_gap 0.5)
			(thermal_bridge_width 0.5)
			(island_removal_mode 0)
		)
		(polygon
			(pts
				(xy 43.991784 -4.097528) (xy 44.708064 -4.097528) (xy 44.708064 -8.293608) (xy 43.991784 -8.293608)
			)
		)
	)
	(zone
		(layer "In1.Cu")
		(hatch none 0.5)
		(connect_pads
			(clearance 0)
		)
		(min_thickness 0.25)
		(keepout
			(tracks not_allowed)
			(vias allowed)
			(pads allowed)
			(copperpour not_allowed)
			(footprints allowed)
		)
		(placement
			(enabled no)
			(sheetname "")
		)
		(fill
			(thermal_gap 0.5)
			(thermal_bridge_width 0.5)
			(island_removal_mode 0)
		)
		(polygon
			(pts
				(xy 31.991808 -4.097528) (xy 32.708088 -4.097528) (xy 32.708088 -8.293608) (xy 31.991808 -8.293608)
			)
		)
	)
	(zone
		(layer "In1.Cu")
		(hatch none 0.5)
		(connect_pads
			(clearance 0)
		)
		(min_thickness 0.25)
		(keepout
			(tracks not_allowed)
			(vias allowed)
			(pads allowed)
			(copperpour not_allowed)
			(footprints allowed)
		)
		(placement
			(enabled no)
			(sheetname "")
		)
		(fill
			(thermal_gap 0.5)
			(thermal_bridge_width 0.5)
			(island_removal_mode 0)
		)
		(polygon
			(pts
				(xy 46.991778 -4.097528) (xy 47.708058 -4.097528) (xy 47.708058 -8.293608) (xy 46.991778 -8.293608)
			)
		)
	)
	(zone
		(net "PV_VDDR")
		(layer "In1.Cu")
		(hatch none 0.5)
		(connect_pads
			(clearance 0.5)
		)
		(min_thickness 0.25)
		(fill yes
			(thermal_gap 0.5)
			(thermal_bridge_width 0.5)
			(island_removal_mode 0)
		)
		(polygon
			(pts
				(xy 108.409994 -26.4795) (xy 107.8865 -27.002994) (xy 107.8865 -27.891994) (xy 107.266994 -28.5115)
				(xy 104.188006 -28.5115) (xy 103.934006 -28.2575) (xy 99.900994 -28.2575) (xy 99.2505 -28.907994)
				(xy 99.2505 -30.812994) (xy 98.7425 -31.320994) (xy 98.7425 -31.925006) (xy 98.884994 -32.0675)
				(xy 99.265994 -32.0675) (xy 99.773994 -32.5755) (xy 100.408994 -32.5755) (xy 100.662994 -32.8295)
				(xy 103.172006 -32.8295) (xy 103.8225 -32.179006) (xy 103.8225 -30.909006) (xy 104.950006 -29.7815)
				(xy 105.742994 -29.7815) (xy 105.9815 -30.020006) (xy 105.9815 -30.909006) (xy 106.631994 -31.5595)
				(xy 108.028994 -31.5595) (xy 108.790994 -32.3215) (xy 109.014006 -32.3215) (xy 109.268006 -32.0675)
				(xy 110.314994 -32.0675) (xy 111.076994 -32.8295) (xy 111.300006 -32.8295) (xy 111.681006 -32.4485)
				(xy 112.316006 -32.4485) (xy 113.0935 -31.671006) (xy 113.0935 -29.923994) (xy 111.554006 -28.3845)
				(xy 110.030006 -28.3845) (xy 109.4105 -27.764994) (xy 109.4105 -26.494994) (xy 109.395006 -26.4795)
			)
		)
	)
	(zone
		(layer "In1.Cu")
		(hatch none 0.5)
		(connect_pads
			(clearance 0)
		)
		(min_thickness 0.25)
		(keepout
			(tracks not_allowed)
			(vias allowed)
			(pads allowed)
			(copperpour not_allowed)
			(footprints allowed)
		)
		(placement
			(enabled no)
			(sheetname "")
		)
		(fill
			(thermal_gap 0.5)
			(thermal_bridge_width 0.5)
			(island_removal_mode 0)
		)
		(polygon
			(pts
				(arc
					(start 8.65886 -56.7182)
					(mid 8.674483 -56.755917)
					(end 8.7122 -56.77154)
				)
				(arc
					(start 9.0678 -56.77154)
					(mid 9.105517 -56.755917)
					(end 9.12114 -56.7182)
				)
				(arc
					(start 9.12114 -56.3118)
					(mid 9.105517 -56.274083)
					(end 9.0678 -56.25846)
				)
				(arc
					(start 8.7122 -56.25846)
					(mid 8.674483 -56.274083)
					(end 8.65886 -56.3118)
				)
			)
		)
	)
	(zone
		(layer "In1.Cu")
		(hatch none 0.5)
		(connect_pads
			(clearance 0)
		)
		(min_thickness 0.25)
		(keepout
			(tracks not_allowed)
			(vias allowed)
			(pads allowed)
			(copperpour not_allowed)
			(footprints allowed)
		)
		(placement
			(enabled no)
			(sheetname "")
		)
		(fill
			(thermal_gap 0.5)
			(thermal_bridge_width 0.5)
			(island_removal_mode 0)
		)
		(polygon
			(pts
				(arc
					(start 7.89686 -62.9412)
					(mid 7.912483 -62.978917)
					(end 7.9502 -62.99454)
				)
				(arc
					(start 8.3058 -62.99454)
					(mid 8.343517 -62.978917)
					(end 8.35914 -62.9412)
				)
				(arc
					(start 8.35914 -62.5348)
					(mid 8.343517 -62.497083)
					(end 8.3058 -62.48146)
				)
				(arc
					(start 7.9502 -62.48146)
					(mid 7.912483 -62.497083)
					(end 7.89686 -62.5348)
				)
			)
		)
	)
	(zone
		(layer "In1.Cu")
		(hatch none 0.5)
		(connect_pads
			(clearance 0)
		)
		(min_thickness 0.25)
		(keepout
			(tracks not_allowed)
			(vias allowed)
			(pads allowed)
			(copperpour not_allowed)
			(footprints allowed)
		)
		(placement
			(enabled no)
			(sheetname "")
		)
		(fill
			(thermal_gap 0.5)
			(thermal_bridge_width 0.5)
			(island_removal_mode 0)
		)
		(polygon
			(pts
				(arc
					(start 7.89686 -61.1632)
					(mid 7.912483 -61.200917)
					(end 7.9502 -61.21654)
				)
				(arc
					(start 8.3058 -61.21654)
					(mid 8.343517 -61.200917)
					(end 8.35914 -61.1632)
				)
				(arc
					(start 8.35914 -60.7568)
					(mid 8.343517 -60.719083)
					(end 8.3058 -60.70346)
				)
				(arc
					(start 7.9502 -60.70346)
					(mid 7.912483 -60.719083)
					(end 7.89686 -60.7568)
				)
			)
		)
	)
	(zone
		(net "PV_VDDR")
		(layer "In2.Cu")
		(hatch none 0.5)
		(connect_pads
			(clearance 0.5)
		)
		(min_thickness 0.25)
		(fill yes
			(thermal_gap 0.5)
			(thermal_bridge_width 0.5)
			(island_removal_mode 0)
		)
		(polygon
			(pts
				(xy 167.005 -13.081) (xy 170.053 -10.033) (xy 170.053 -8.636) (xy 170.688 -8.001) (xy 170.688 -5.207)
				(xy 170.307 -4.826) (xy 170.307 -3.683) (xy 170.307 -3.048) (xy 169.672 -2.413) (xy 156.845 -2.413)
				(xy 155.829 -3.429) (xy 155.829 -4.064) (xy 155.829 -9.525) (xy 156.718 -10.414) (xy 156.718 -12.573)
				(xy 157.226 -13.081)
			)
		)
	)
	(zone
		(net "P1V35")
		(layer "In2.Cu")
		(hatch none 0.5)
		(connect_pads
			(clearance 0.5)
		)
		(min_thickness 0.25)
		(fill yes
			(thermal_gap 0.5)
			(thermal_bridge_width 0.5)
			(island_removal_mode 0)
		)
		(polygon
			(pts
				(xy 90.805 -25.654) (xy 94.615 -25.654) (xy 96.393 -27.432) (xy 97.409 -27.432) (xy 97.663 -27.686)
				(xy 97.663 -34.163) (xy 96.901 -34.925) (xy 96.012 -35.814) (xy 94.996 -35.814) (xy 94.742 -35.56)
				(xy 94.742 -34.925) (xy 93.472 -33.655) (xy 93.091 -33.655) (xy 92.329 -32.893) (xy 92.329 -32.639)
				(xy 92.329 -28.575) (xy 90.551 -26.797) (xy 90.551 -25.908)
			)
		)
	)
	(zone
		(layer "In2.Cu")
		(hatch none 0.5)
		(connect_pads
			(clearance 0)
		)
		(min_thickness 0.25)
		(keepout
			(tracks not_allowed)
			(vias allowed)
			(pads allowed)
			(copperpour not_allowed)
			(footprints allowed)
		)
		(placement
			(enabled no)
			(sheetname "")
		)
		(fill
			(thermal_gap 0.5)
			(thermal_bridge_width 0.5)
			(island_removal_mode 0)
		)
		(polygon
			(pts
				(arc
					(start 80.2132 -14.19606)
					(mid 79.82966 -14.5796)
					(end 80.2132 -14.96314)
				)
				(xy 80.438498 -14.96314) (xy 80.438498 -14.903704)
				(arc
					(start 80.345788 -14.810994)
					(mid 80.024623 -14.391023)
					(end 80.444594 -14.712188)
				)
				(xy 80.578198 -14.845792) (xy 80.578198 -14.96314) (xy 80.768698 -14.96314) (xy 80.768698 -14.788896)
				(arc
					(start 80.845406 -14.712188)
					(mid 81.265377 -14.391023)
					(end 80.944212 -14.810994)
				)
				(xy 80.908398 -14.846808) (xy 80.908398 -14.96314)
				(arc
					(start 81.076546 -14.96314)
					(mid 81.46034 -14.579727)
					(end 81.0768 -14.19606)
				)
			)
		)
	)
	(zone
		(net "P3V3_STBY")
		(layer "In2.Cu")
		(hatch none 0.5)
		(connect_pads
			(clearance 0.5)
		)
		(min_thickness 0.25)
		(fill yes
			(thermal_gap 0.5)
			(thermal_bridge_width 0.5)
			(island_removal_mode 0)
		)
		(polygon
			(pts
				(xy 52.451 -52.4764) (xy 52.451 -52.324) (xy 50.673 -50.546) (xy 50.2666 -50.546) (xy 49.022 -50.546)
				(xy 47.879 -49.403) (xy 44.6278 -49.403) (xy 44.4119 -49.1871) (xy 43.1419 -47.9171) (xy 43.1419 -47.879)
				(xy 42.926 -47.6631) (xy 42.926 -46.482) (xy 42.672 -46.228) (xy 42.672 -45.339) (xy 42.418 -45.085)
				(xy 42.291 -45.085) (xy 41.783 -45.085) (xy 41.656 -45.085) (xy 41.275 -45.466) (xy 41.275 -45.593)
				(xy 41.275 -48.133) (xy 44.196 -51.054) (xy 46.101 -51.054) (xy 46.6598 -51.6128) (xy 46.8122 -51.6128)
				(xy 50.1396 -51.6128) (xy 51.2191 -52.6923) (xy 52.2351 -52.6923)
			)
		)
	)
	(zone
		(layer "In2.Cu")
		(hatch none 0.5)
		(connect_pads
			(clearance 0)
		)
		(min_thickness 0.25)
		(keepout
			(tracks not_allowed)
			(vias allowed)
			(pads allowed)
			(copperpour not_allowed)
			(footprints allowed)
		)
		(placement
			(enabled no)
			(sheetname "")
		)
		(fill
			(thermal_gap 0.5)
			(thermal_bridge_width 0.5)
			(island_removal_mode 0)
		)
		(polygon
			(pts
				(arc
					(start 33.4264 -14.19606)
					(mid 33.04286 -14.5796)
					(end 33.4264 -14.96314)
				)
				(xy 33.58515 -14.96314) (xy 33.58515 -14.837156)
				(arc
					(start 33.558988 -14.810994)
					(mid 33.237823 -14.391023)
					(end 33.657794 -14.712188)
				)
				(xy 33.72485 -14.779244) (xy 33.72485 -14.96314) (xy 33.91535 -14.96314) (xy 33.91535 -14.855444)
				(xy 33.99155 -14.779244)
				(arc
					(start 34.058606 -14.712188)
					(mid 34.478577 -14.391023)
					(end 34.157412 -14.810994)
				)
				(xy 34.112962 -14.855444) (xy 34.05505 -14.913356) (xy 34.05505 -14.96314)
				(arc
					(start 34.289746 -14.96314)
					(mid 34.67354 -14.579727)
					(end 34.29 -14.19606)
				)
			)
		)
	)
	(zone
		(net "PV_VDDR")
		(layer "In2.Cu")
		(hatch none 0.5)
		(connect_pads
			(clearance 0.5)
		)
		(min_thickness 0.25)
		(fill yes
			(thermal_gap 0.5)
			(thermal_bridge_width 0.5)
			(island_removal_mode 0)
		)
		(polygon
			(pts
				(xy 209.169 -44.323) (xy 209.169 -3.683) (xy 206.9465 -1.4605) (xy 193.4845 -1.4605) (xy 191.008 -3.937)
				(xy 191.008 -7.874) (xy 191.008 -8.636) (xy 191.008 -17.907) (xy 184.277 -24.638) (xy 184.277 -44.577)
				(xy 191.008 -51.308) (xy 191.897 -52.197) (xy 195.072 -55.372) (xy 195.072 -60.325) (xy 195.072 -65.659)
				(xy 195.072 -66.167) (xy 195.072 -67.818) (xy 195.707 -68.453) (xy 201.803 -68.453) (xy 203.2 -67.056)
				(xy 203.2 -65.786) (xy 203.2 -54.229) (xy 209.169 -48.26) (xy 209.169 -45.593)
			)
		)
		(polygon
			(pts
				(xy 199.644 -52.705) (xy 199.644 -55.88) (xy 199.771 -56.007) (xy 200.152 -56.388) (xy 200.914 -56.388)
				(xy 201.295 -56.007) (xy 201.295 -52.959) (xy 201.422 -52.832) (xy 201.93 -52.832) (xy 202.057 -52.705)
				(xy 202.184 -52.578) (xy 202.311 -52.451) (xy 202.311 -51.816) (xy 202.311 -51.562) (xy 202.184 -51.435)
				(xy 202.184 -49.53) (xy 203.581 -48.133) (xy 203.581 -47.244) (xy 203.2 -46.863) (xy 202.819 -46.863)
				(xy 200.025 -46.863) (xy 199.644 -46.863) (xy 198.755 -47.752) (xy 198.755 -48.133) (xy 198.755 -48.26)
				(xy 198.755 -51.308) (xy 198.755 -51.816)
			)
		)
	)
	(zone
		(net "P3V3_STBY")
		(layer "In2.Cu")
		(hatch none 0.5)
		(connect_pads
			(clearance 0.5)
		)
		(min_thickness 0.25)
		(fill yes
			(thermal_gap 0.5)
			(thermal_bridge_width 0.5)
			(island_removal_mode 0)
		)
		(polygon
			(pts
				(xy 84.836 -65.151) (xy 87.757 -68.072) (xy 87.757 -68.834) (xy 87.757 -68.961) (xy 87.503 -69.215)
				(xy 80.899 -69.215) (xy 79.375 -67.691) (xy 78.232 -67.691) (xy 77.089 -68.834) (xy 74.295 -68.834)
				(xy 73.279 -67.818) (xy 72.517 -67.818) (xy 71.4375 -68.8975) (xy 71.374 -68.8975) (xy 67.31 -68.8975)
				(xy 66.7385 -69.469) (xy 65.786 -69.469) (xy 64.897 -69.469) (xy 64.008 -68.58) (xy 63.754 -68.326)
				(xy 63.754 -67.945) (xy 63.754 -67.31) (xy 64.135 -66.929) (xy 65.278 -65.786) (xy 68.58 -65.786)
				(xy 68.707 -65.659) (xy 69.215 -65.151) (xy 70.7644 -65.151) (xy 71.5518 -64.3636) (xy 72.4916 -64.3636)
				(xy 73.025 -64.897) (xy 75.057 -64.897) (xy 75.692 -64.262) (xy 75.819 -64.135) (xy 76.2 -64.135)
				(xy 76.962 -64.897) (xy 84.582 -64.897)
			)
		)
	)
	(zone
		(layer "In2.Cu")
		(hatch none 0.5)
		(connect_pads
			(clearance 0)
		)
		(min_thickness 0.25)
		(keepout
			(tracks not_allowed)
			(vias allowed)
			(pads allowed)
			(copperpour not_allowed)
			(footprints allowed)
		)
		(placement
			(enabled no)
			(sheetname "")
		)
		(fill
			(thermal_gap 0.5)
			(thermal_bridge_width 0.5)
			(island_removal_mode 0)
		)
		(polygon
			(pts
				(arc
					(start 59.078368 -10.552938)
					(mid 58.694574 -10.936351)
					(end 59.078114 -11.320018)
				)
				(xy 59.302904 -11.320018) (xy 59.302904 -11.260074)
				(arc
					(start 59.210702 -11.167872)
					(mid 58.889537 -10.747901)
					(end 59.309508 -11.069066)
				)
				(xy 59.442604 -11.202162) (xy 59.442604 -11.320018) (xy 59.633104 -11.320018) (xy 59.633104 -11.202162)
				(arc
					(start 59.7662 -11.069066)
					(mid 60.186171 -10.747901)
					(end 59.865006 -11.167872)
				)
				(xy 59.830716 -11.202162) (xy 59.772804 -11.260074) (xy 59.772804 -11.320018)
				(arc
					(start 59.997594 -11.320018)
					(mid 60.381134 -10.936478)
					(end 59.997594 -10.552938)
				)
			)
		)
	)
	(zone
		(net "PVCCP")
		(layer "In2.Cu")
		(hatch none 0.5)
		(connect_pads
			(clearance 0.5)
		)
		(min_thickness 0.25)
		(fill yes
			(thermal_gap 0.5)
			(thermal_bridge_width 0.5)
			(island_removal_mode 0)
		)
		(polygon
			(pts
				(xy 110.998 -40.64) (xy 110.49 -40.132) (xy 109.728 -40.132) (xy 109.601 -40.005) (xy 106.807 -40.005)
				(xy 106.553 -39.751) (xy 105.156 -39.751) (xy 105.029 -39.624) (xy 104.648 -39.243) (xy 104.648 -38.608)
				(xy 104.394 -38.354) (xy 104.013 -38.354) (xy 103.505 -38.354) (xy 102.616 -37.465) (xy 102.616 -37.211)
				(xy 102.489 -37.084) (xy 102.108 -37.084) (xy 101.981 -36.957) (xy 100.584 -36.957) (xy 100.457 -37.084)
				(xy 100.457 -37.338) (xy 99.949 -37.846) (xy 99.695 -37.846) (xy 99.441 -38.1) (xy 99.441 -41.148)
				(xy 99.695 -41.402) (xy 99.949 -41.402) (xy 102.489 -41.402) (xy 102.616 -41.275) (xy 102.743 -41.148)
				(xy 108.712 -41.148) (xy 108.966 -41.402) (xy 110.617 -41.402) (xy 110.998 -41.021)
			)
		)
	)
	(zone
		(layer "In2.Cu")
		(hatch none 0.5)
		(connect_pads
			(clearance 0)
		)
		(min_thickness 0.25)
		(keepout
			(tracks not_allowed)
			(vias allowed)
			(pads allowed)
			(copperpour not_allowed)
			(footprints allowed)
		)
		(placement
			(enabled no)
			(sheetname "")
		)
		(fill
			(thermal_gap 0.5)
			(thermal_bridge_width 0.5)
			(island_removal_mode 0)
		)
		(polygon
			(pts
				(arc
					(start 83.389216 -10.02919)
					(mid 83.104696 -10.15525)
					(end 83.0072 -10.45083)
				)
				(arc
					(start 83.125056 -10.45083)
					(mid 83.630671 -10.300487)
					(end 83.19008 -10.59053)
				)
				(arc
					(start 83.04911 -10.59053)
					(mid 83.146097 -10.709595)
					(end 83.282028 -10.78103)
				)
				(xy 83.843368 -10.78103)
				(arc
					(start 84.07908 -10.545318)
					(mid 84.499051 -10.224153)
					(end 84.177886 -10.644124)
				)
				(xy 84.02574 -10.79627)
				(arc
					(start 84.310474 -10.79627)
					(mid 84.694014 -10.41273)
					(end 84.310474 -10.02919)
				)
			)
		)
	)
	(zone
		(layer "In2.Cu")
		(hatch none 0.5)
		(connect_pads
			(clearance 0)
		)
		(min_thickness 0.25)
		(keepout
			(tracks not_allowed)
			(vias allowed)
			(pads allowed)
			(copperpour not_allowed)
			(footprints allowed)
		)
		(placement
			(enabled no)
			(sheetname "")
		)
		(fill
			(thermal_gap 0.5)
			(thermal_bridge_width 0.5)
			(island_removal_mode 0)
		)
		(polygon
			(pts
				(arc
					(start 91.632786 -55.202074)
					(mid 91.668956 -54.738999)
					(end 91.211654 -54.658514)
				)
				(xy 91.210384 -54.656482) (xy 90.73769 -54.954678) (xy 90.73769 -54.954932)
				(arc
					(start 90.73896 -54.956964)
					(mid 90.631264 -55.433468)
					(end 91.107768 -55.541164)
				)
				(xy 91.109038 -55.543196) (xy 91.216226 -55.475632)
				(arc
					(start 91.114626 -55.374032)
					(mid 90.699567 -55.202154)
					(end 91.148662 -55.210456)
				)
				(xy 91.337384 -55.399178) (xy 91.517978 -55.284878)
				(arc
					(start 91.411806 -55.178706)
					(mid 91.306101 -54.740419)
					(end 91.550236 -55.119524)
				)
			)
		)
	)
	(zone
		(net "P3V3")
		(layer "In2.Cu")
		(hatch none 0.5)
		(connect_pads
			(clearance 0.5)
		)
		(min_thickness 0.25)
		(fill yes
			(thermal_gap 0.5)
			(thermal_bridge_width 0.5)
			(island_removal_mode 0)
		)
		(polygon
			(pts
				(xy 49.7586 -15.5194) (xy 52.1716 -15.5194) (xy 55.9816 -19.3294) (xy 55.9816 -23.114) (xy 57.404 -24.5364)
				(xy 57.404 -25.3238) (xy 57.404 -27.686) (xy 57.404 -32.893) (xy 58.039 -33.528) (xy 58.039 -34.036)
				(xy 57.785 -34.29) (xy 56.6674 -34.29) (xy 55.7784 -33.401) (xy 55.7784 -29.3624) (xy 55.7784 -26.162)
				(xy 55.7657 -26.1493) (xy 55.7657 -25.2857) (xy 54.356 -23.876) (xy 54.356 -20.2946) (xy 51.2064 -17.145)
				(xy 51.0794 -17.018) (xy 49.784 -17.018) (xy 49.53 -16.764) (xy 49.53 -15.748)
			)
		)
	)
	(zone
		(layer "In2.Cu")
		(hatch none 0.5)
		(connect_pads
			(clearance 0)
		)
		(min_thickness 0.25)
		(keepout
			(tracks not_allowed)
			(vias allowed)
			(pads allowed)
			(copperpour not_allowed)
			(footprints allowed)
		)
		(placement
			(enabled no)
			(sheetname "")
		)
		(fill
			(thermal_gap 0.5)
			(thermal_bridge_width 0.5)
			(island_removal_mode 0)
		)
		(polygon
			(pts
				(arc
					(start 87.528908 -54.284118)
					(mid 87.190326 -53.93182)
					(end 86.838028 -54.270402)
				)
				(xy 86.83625 -54.356254)
				(arc
					(start 86.968838 -54.356254)
					(mid 87.35698 -54.128264)
					(end 87.072978 -54.477412)
				)
				(xy 87.06739 -54.483254) (xy 87.014558 -54.483254) (xy 86.83371 -54.483254) (xy 86.832186 -54.559454)
				(xy 86.840314 -54.559454) (xy 86.92769 -54.559454) (xy 86.980522 -54.559454) (xy 87.017606 -54.596538)
				(arc
					(start 87.061802 -54.640988)
					(mid 87.333953 -55.002801)
					(end 86.97214 -54.73065)
				)
				(xy 86.92769 -54.686454) (xy 86.840314 -54.686454) (xy 86.829646 -54.697122)
				(arc
					(start 86.826852 -54.834028)
					(mid 87.165307 -55.186583)
					(end 87.517732 -54.847998)
				)
				(xy 87.522812 -54.596538) (xy 87.523574 -54.559454)
			)
		)
	)
	(zone
		(layer "In2.Cu")
		(hatch none 0.5)
		(connect_pads
			(clearance 0)
		)
		(min_thickness 0.25)
		(keepout
			(tracks not_allowed)
			(vias allowed)
			(pads allowed)
			(copperpour not_allowed)
			(footprints allowed)
		)
		(placement
			(enabled no)
			(sheetname "")
		)
		(fill
			(thermal_gap 0.5)
			(thermal_bridge_width 0.5)
			(island_removal_mode 0)
		)
		(polygon
			(pts
				(xy 52.907946 -35.60064) (xy 52.907946 -35.69843) (xy 53.098446 -35.697922) (xy 53.098446 -35.594798)
				(arc
					(start 53.247544 -35.4457)
					(mid 53.667515 -35.124535)
					(end 53.34635 -35.544506)
				)
				(xy 53.238146 -35.65271) (xy 53.238146 -35.697414)
				(arc
					(start 53.479954 -35.696652)
					(mid 53.862478 -35.311969)
					(end 53.477668 -34.929572)
				)
				(arc
					(start 52.52339 -34.93262)
					(mid 52.14112 -35.31743)
					(end 52.52593 -35.6997)
				)
				(xy 52.768246 -35.698938) (xy 52.768246 -35.658552)
				(arc
					(start 52.657248 -35.547554)
					(mid 52.336083 -35.127583)
					(end 52.756054 -35.448748)
				)
			)
		)
	)
	(zone
		(layer "In2.Cu")
		(hatch none 0.5)
		(connect_pads
			(clearance 0)
		)
		(min_thickness 0.25)
		(keepout
			(tracks not_allowed)
			(vias allowed)
			(pads allowed)
			(copperpour not_allowed)
			(footprints allowed)
		)
		(placement
			(enabled no)
			(sheetname "")
		)
		(fill
			(thermal_gap 0.5)
			(thermal_bridge_width 0.5)
			(island_removal_mode 0)
		)
		(polygon
			(pts
				(arc
					(start 43.25366 -12.21486)
					(mid 42.87012 -12.5984)
					(end 43.25366 -12.98194)
				)
				(arc
					(start 44.210986 -12.98194)
					(mid 44.59478 -12.598527)
					(end 44.21124 -12.21486)
				)
				(xy 43.9674 -12.21486) (xy 43.9674 -12.255754) (xy 44.025312 -12.313666)
				(arc
					(start 44.078652 -12.367006)
					(mid 44.399817 -12.786977)
					(end 43.979846 -12.465812)
				)
				(xy 43.8277 -12.313666) (xy 43.8277 -12.21486) (xy 43.6372 -12.21486) (xy 43.6372 -12.313666)
				(arc
					(start 43.485054 -12.465812)
					(mid 43.065083 -12.786977)
					(end 43.386248 -12.367006)
				)
				(xy 43.4975 -12.255754) (xy 43.4975 -12.21486)
			)
		)
	)
	(zone
		(layer "In2.Cu")
		(hatch none 0.5)
		(connect_pads
			(clearance 0)
		)
		(min_thickness 0.25)
		(keepout
			(tracks not_allowed)
			(vias allowed)
			(pads allowed)
			(copperpour not_allowed)
			(footprints allowed)
		)
		(placement
			(enabled no)
			(sheetname "")
		)
		(fill
			(thermal_gap 0.5)
			(thermal_bridge_width 0.5)
			(island_removal_mode 0)
		)
		(polygon
			(pts
				(arc
					(start 49.295304 -20.0279)
					(mid 48.91151 -20.411313)
					(end 49.29505 -20.79498)
				)
				(xy 49.53889 -20.79498) (xy 49.53889 -20.754086)
				(arc
					(start 49.427638 -20.642834)
					(mid 49.106473 -20.222863)
					(end 49.526444 -20.544028)
				)
				(xy 49.67859 -20.696174) (xy 49.67859 -20.79498) (xy 49.86909 -20.79498) (xy 49.86909 -20.696174)
				(arc
					(start 50.021236 -20.544028)
					(mid 50.441207 -20.222863)
					(end 50.120042 -20.642834)
				)
				(xy 50.00879 -20.754086) (xy 50.00879 -20.79498)
				(arc
					(start 50.25263 -20.79498)
					(mid 50.63617 -20.41144)
					(end 50.25263 -20.0279)
				)
			)
		)
	)
	(zone
		(layer "In2.Cu")
		(hatch none 0.5)
		(connect_pads
			(clearance 0)
		)
		(min_thickness 0.25)
		(keepout
			(tracks not_allowed)
			(vias allowed)
			(pads allowed)
			(copperpour not_allowed)
			(footprints allowed)
		)
		(placement
			(enabled no)
			(sheetname "")
		)
		(fill
			(thermal_gap 0.5)
			(thermal_bridge_width 0.5)
			(island_removal_mode 0)
		)
		(polygon
			(pts
				(arc
					(start 45.466 -13.4366)
					(mid 45.085 -13.8176)
					(end 45.466 -14.1986)
				)
				(xy 45.61205 -14.1986) (xy 45.61205 -14.062456)
				(arc
					(start 45.598588 -14.048994)
					(mid 45.277423 -13.629023)
					(end 45.697394 -13.950188)
				)
				(xy 45.75175 -14.004544) (xy 45.75175 -14.1986) (xy 45.94225 -14.1986) (xy 45.94225 -13.953744)
				(arc
					(start 45.945806 -13.950188)
					(mid 46.35059 -13.614971)
					(end 46.08195 -14.066774)
				)
				(xy 46.08195 -14.1986)
				(arc
					(start 46.176946 -14.1986)
					(mid 46.5582 -13.817727)
					(end 46.1772 -13.4366)
				)
			)
		)
	)
	(zone
		(layer "In2.Cu")
		(hatch none 0.5)
		(connect_pads
			(clearance 0)
		)
		(min_thickness 0.25)
		(keepout
			(tracks not_allowed)
			(vias allowed)
			(pads allowed)
			(copperpour not_allowed)
			(footprints allowed)
		)
		(placement
			(enabled no)
			(sheetname "")
		)
		(fill
			(thermal_gap 0.5)
			(thermal_bridge_width 0.5)
			(island_removal_mode 0)
		)
		(polygon
			(pts
				(arc
					(start 68.072254 -14.22146)
					(mid 67.68846 -14.604873)
					(end 68.072 -14.98854)
				)
				(xy 68.25615 -14.98854) (xy 68.25615 -14.887956)
				(arc
					(start 68.204588 -14.836394)
					(mid 67.883423 -14.416423)
					(end 68.303394 -14.737588)
				)
				(xy 68.39585 -14.830044) (xy 68.39585 -14.98854) (xy 68.58635 -14.98854) (xy 68.58635 -14.753844)
				(arc
					(start 68.602606 -14.737588)
					(mid 69.012565 -14.406916)
					(end 68.72605 -14.84884)
				)
				(xy 68.72605 -14.98854)
				(arc
					(start 68.834 -14.98854)
					(mid 69.21754 -14.605)
					(end 68.834 -14.22146)
				)
			)
		)
	)
	(zone
		(net "P1V1")
		(layer "In2.Cu")
		(hatch none 0.5)
		(connect_pads
			(clearance 0.5)
		)
		(min_thickness 0.25)
		(fill yes
			(thermal_gap 0.5)
			(thermal_bridge_width 0.5)
			(island_removal_mode 0)
		)
		(polygon
			(pts
				(xy 96.52 -36.83) (xy 97.409 -36.83) (xy 97.917 -37.338) (xy 98.425 -37.846) (xy 98.425 -41.9862)
				(xy 97.155 -43.2562) (xy 97.155 -43.561) (xy 97.409 -43.815) (xy 98.425 -43.815) (xy 98.679 -44.069)
				(xy 98.679 -44.45) (xy 98.679 -44.958) (xy 98.298 -45.339) (xy 98.298 -50.419) (xy 99.568 -51.689)
				(xy 100.203 -52.324) (xy 100.3935 -52.5145) (xy 100.838 -52.959) (xy 100.965 -53.086) (xy 101.092 -53.213)
				(xy 101.092 -57.15) (xy 101.092 -58.166) (xy 97.155 -62.103) (xy 94.615 -62.103) (xy 94.361 -61.849)
				(xy 94.361 -60.833) (xy 94.361 -58.42) (xy 94.361 -58.166) (xy 92.5449 -56.3499) (xy 92.5449 -55.9689)
				(xy 92.5449 -49.9999) (xy 92.2782 -49.7332) (xy 91.9988 -49.4538) (xy 91.9988 -44.3992) (xy 91.9988 -43.8404)
				(xy 92.7862 -43.053) (xy 92.7862 -41.656) (xy 93.2688 -41.1734) (xy 93.2688 -40.9575) (xy 93.2688 -40.4622)
				(xy 93.2815 -40.4495) (xy 93.2815 -39.9415) (xy 94.869 -38.354) (xy 95.377 -38.354) (xy 96.139 -38.354)
				(xy 96.266 -38.227) (xy 96.266 -37.084)
			)
		)
	)
	(zone
		(layer "In2.Cu")
		(hatch none 0.5)
		(connect_pads
			(clearance 0)
		)
		(min_thickness 0.25)
		(keepout
			(tracks not_allowed)
			(vias allowed)
			(pads allowed)
			(copperpour not_allowed)
			(footprints allowed)
		)
		(placement
			(enabled no)
			(sheetname "")
		)
		(fill
			(thermal_gap 0.5)
			(thermal_bridge_width 0.5)
			(island_removal_mode 0)
		)
		(polygon
			(pts
				(xy 22.21865 -14.029944)
				(arc
					(start 22.298406 -13.950188)
					(mid 22.718377 -13.629023)
					(end 22.397212 -14.048994)
				)
				(xy 22.365462 -14.080744) (xy 22.30755 -14.138656) (xy 22.30755 -14.20114)
				(arc
					(start 22.5298 -14.20114)
					(mid 22.91334 -13.8176)
					(end 22.5298 -13.43406)
				)
				(arc
					(start 21.666454 -13.43406)
					(mid 21.28266 -13.817473)
					(end 21.6662 -14.20114)
				)
				(xy 21.83765 -14.20114) (xy 21.83765 -14.087856)
				(arc
					(start 21.798788 -14.048994)
					(mid 21.477623 -13.629023)
					(end 21.897594 -13.950188)
				)
				(xy 21.97735 -14.029944) (xy 21.97735 -14.20114) (xy 22.16785 -14.20114) (xy 22.16785 -14.080744)
			)
		)
	)
	(zone
		(layer "In2.Cu")
		(hatch none 0.5)
		(connect_pads
			(clearance 0)
		)
		(min_thickness 0.25)
		(keepout
			(tracks not_allowed)
			(vias allowed)
			(pads allowed)
			(copperpour not_allowed)
			(footprints allowed)
		)
		(placement
			(enabled no)
			(sheetname "")
		)
		(fill
			(thermal_gap 0.5)
			(thermal_bridge_width 0.5)
			(island_removal_mode 0)
		)
		(polygon
			(pts
				(arc
					(start 86.443058 -53.20792)
					(mid 86.103968 -52.85613)
					(end 85.752178 -53.19522)
				)
				(xy 85.750146 -53.3019)
				(arc
					(start 85.892132 -53.3019)
					(mid 86.26332 -53.043983)
					(end 85.987128 -53.401722)
				)
				(xy 85.960204 -53.4289) (xy 85.907372 -53.4289) (xy 85.74786 -53.4289) (xy 85.746336 -53.5051) (xy 85.864192 -53.5051)
				(xy 85.917024 -53.5051) (xy 85.954108 -53.542184)
				(arc
					(start 85.976714 -53.565044)
					(mid 86.248865 -53.926857)
					(end 85.887052 -53.654706)
				)
				(xy 85.864192 -53.6321) (xy 85.74405 -53.6321)
				(arc
					(start 85.741764 -53.758592)
					(mid 86.080727 -54.110638)
					(end 86.432644 -53.771546)
				)
				(xy 86.43747 -53.5051)
			)
		)
	)
	(zone
		(layer "In2.Cu")
		(hatch none 0.5)
		(connect_pads
			(clearance 0)
		)
		(min_thickness 0.25)
		(keepout
			(tracks not_allowed)
			(vias allowed)
			(pads allowed)
			(copperpour not_allowed)
			(footprints allowed)
		)
		(placement
			(enabled no)
			(sheetname "")
		)
		(fill
			(thermal_gap 0.5)
			(thermal_bridge_width 0.5)
			(island_removal_mode 0)
		)
		(polygon
			(pts
				(arc
					(start 82.0293 -53.0098)
					(mid 81.6864 -52.6669)
					(end 81.3435 -53.0098)
				)
				(xy 81.3435 -53.086)
				(arc
					(start 81.470754 -53.086)
					(mid 81.858143 -52.859027)
					(end 81.581752 -53.213)
				)
				(xy 81.569306 -53.2257) (xy 81.3435 -53.2257) (xy 81.3435 -53.4162)
				(arc
					(start 81.542636 -53.4162)
					(mid 81.883708 -53.708899)
					(end 81.461102 -53.5559)
				)
				(xy 81.3435 -53.5559)
				(arc
					(start 81.3435 -53.593746)
					(mid 81.686273 -53.9369)
					(end 82.0293 -53.594)
				)
			)
		)
	)
	(zone
		(net "GND")
		(layer "In2.Cu")
		(hatch none 0.5)
		(connect_pads
			(clearance 0.5)
		)
		(min_thickness 0.25)
		(fill yes
			(thermal_gap 0.5)
			(thermal_bridge_width 0.5)
			(island_removal_mode 0)
		)
		(polygon
			(pts
				(xy 203.708 -65.913) (xy 203.708 -61.214) (xy 203.708 -54.356) (xy 206.502 -51.562) (xy 208.788 -51.562)
				(xy 209.169 -51.943) (xy 209.169 -52.197) (xy 209.169 -53.213) (xy 209.169 -59.309) (xy 209.169 -72.771)
				(xy 208.915 -73.025) (xy 195.961 -73.025) (xy 195.072 -72.136) (xy 195.072 -69.088) (xy 195.326 -68.834)
				(xy 195.58 -68.834) (xy 195.707 -68.834) (xy 202.184 -68.834) (xy 203.708 -67.31)
			)
		)
	)
	(zone
		(layer "In2.Cu")
		(hatch none 0.5)
		(connect_pads
			(clearance 0)
		)
		(min_thickness 0.25)
		(keepout
			(tracks not_allowed)
			(vias allowed)
			(pads allowed)
			(copperpour not_allowed)
			(footprints allowed)
		)
		(placement
			(enabled no)
			(sheetname "")
		)
		(fill
			(thermal_gap 0.5)
			(thermal_bridge_width 0.5)
			(island_removal_mode 0)
		)
		(polygon
			(pts
				(arc
					(start 41.418002 -13.43406)
					(mid 41.034462 -13.8176)
					(end 41.418002 -14.20114)
				)
				(xy 41.61155 -14.20114) (xy 41.61155 -14.109954)
				(arc
					(start 41.55059 -14.048994)
					(mid 41.229425 -13.629023)
					(end 41.649396 -13.950188)
				)
				(xy 41.75125 -14.052042) (xy 41.75125 -14.20114) (xy 41.94175 -14.20114) (xy 41.94175 -14.058646)
				(xy 41.948354 -14.052042)
				(arc
					(start 42.050208 -13.950188)
					(mid 42.470179 -13.629023)
					(end 42.149014 -14.048994)
				)
				(xy 42.139362 -14.058646) (xy 42.08145 -14.116558) (xy 42.08145 -14.20114)
				(arc
					(start 42.281348 -14.20114)
					(mid 42.665142 -13.817727)
					(end 42.281602 -13.43406)
				)
			)
		)
	)
	(zone
		(net "P3V3")
		(layer "In2.Cu")
		(hatch none 0.5)
		(connect_pads
			(clearance 0.5)
		)
		(min_thickness 0.25)
		(fill yes
			(thermal_gap 0.5)
			(thermal_bridge_width 0.5)
			(island_removal_mode 0)
		)
		(polygon
			(pts
				(xy 18.161 -48.895) (xy 16.891 -48.895) (xy 16.129 -48.895) (xy 15.748 -48.895) (xy 13.589 -51.054)
				(xy 13.589 -59.69) (xy 12.573 -60.706) (xy 12.573 -61.087) (xy 12.573 -68.072) (xy 12.573 -68.199)
				(xy 12.573 -68.707) (xy 12.7 -68.834) (xy 12.827 -68.961) (xy 14.351 -68.961) (xy 14.732 -68.961)
				(xy 16.129 -67.564) (xy 16.256 -67.437) (xy 16.256 -61.849) (xy 17.018 -61.087) (xy 17.526 -60.579)
				(xy 17.526 -51.308) (xy 18.415 -50.419) (xy 18.415 -49.149)
			)
		)
	)
	(zone
		(net "GND")
		(layer "In2.Cu")
		(hatch none 0.5)
		(connect_pads
			(clearance 0.5)
		)
		(min_thickness 0.25)
		(fill yes
			(thermal_gap 0.5)
			(thermal_bridge_width 0.5)
			(island_removal_mode 0)
		)
		(polygon
			(pts
				(xy 39.6875 -50.2285) (xy 41.656 -52.197) (xy 42.037 -52.578) (xy 42.926 -53.467) (xy 45.974 -53.467)
				(xy 46.101 -53.34) (xy 46.228 -53.213) (xy 46.228 -52.07) (xy 45.847 -51.689) (xy 44.323 -51.689)
				(xy 43.942 -51.689) (xy 40.64 -48.387) (xy 40.64 -48.006) (xy 40.64 -47.625) (xy 40.64 -45.72) (xy 39.37 -44.45)
				(xy 38.227 -43.307) (xy 38.227 -42.037) (xy 37.973 -41.783) (xy 35.306 -41.783) (xy 35.179 -41.656)
				(xy 34.925 -41.402) (xy 34.671 -41.148) (xy 34.036 -40.513) (xy 34.036 -40.386) (xy 34.036 -40.259)
				(xy 34.036 -40.132) (xy 34.036 -40.005) (xy 33.782 -39.751) (xy 32.766 -39.751) (xy 32.512 -40.005)
				(xy 32.512 -40.132) (xy 32.512 -40.894) (xy 33.3375 -41.7195) (xy 34.29 -42.672) (xy 34.417 -42.799)
				(xy 34.417 -46.736) (xy 35.306 -47.625) (xy 35.814 -48.133) (xy 36.322 -48.133) (xy 37.592 -48.133)
				(xy 37.846 -48.387)
			)
		)
	)
	(zone
		(layer "In2.Cu")
		(hatch none 0.5)
		(connect_pads
			(clearance 0)
		)
		(min_thickness 0.25)
		(keepout
			(tracks not_allowed)
			(vias allowed)
			(pads allowed)
			(copperpour not_allowed)
			(footprints allowed)
		)
		(placement
			(enabled no)
			(sheetname "")
		)
		(fill
			(thermal_gap 0.5)
			(thermal_bridge_width 0.5)
			(island_removal_mode 0)
		)
		(polygon
			(pts
				(arc
					(start 39.443914 -11.9634)
					(mid 39.06012 -12.346813)
					(end 39.44366 -12.73048)
				)
				(arc
					(start 40.40124 -12.73048)
					(mid 40.78478 -12.34694)
					(end 40.40124 -11.9634)
				)
				(xy 40.1574 -11.9634) (xy 40.1574 -12.004294) (xy 40.215312 -12.062206)
				(arc
					(start 40.268652 -12.115546)
					(mid 40.589817 -12.535517)
					(end 40.169846 -12.214352)
				)
				(xy 40.0177 -12.062206) (xy 40.0177 -11.9634) (xy 39.8272 -11.9634) (xy 39.8272 -12.062206)
				(arc
					(start 39.675054 -12.214352)
					(mid 39.255083 -12.535517)
					(end 39.576248 -12.115546)
				)
				(xy 39.6875 -12.004294) (xy 39.6875 -11.9634)
			)
		)
	)
	(zone
		(layer "In2.Cu")
		(hatch none 0.5)
		(connect_pads
			(clearance 0)
		)
		(min_thickness 0.25)
		(keepout
			(tracks not_allowed)
			(vias allowed)
			(pads allowed)
			(copperpour not_allowed)
			(footprints allowed)
		)
		(placement
			(enabled no)
			(sheetname "")
		)
		(fill
			(thermal_gap 0.5)
			(thermal_bridge_width 0.5)
			(island_removal_mode 0)
		)
		(polygon
			(pts
				(arc
					(start 90.156792 -53.552598)
					(mid 89.845768 -53.175928)
					(end 89.46896 -53.486812)
				)
				(xy 89.453974 -53.6448) (xy 89.597738 -53.6448)
				(arc
					(start 89.612724 -53.630068)
					(mid 89.974537 -53.357917)
					(end 89.702386 -53.71973)
				)
				(xy 89.687654 -53.734716) (xy 89.65057 -53.7718) (xy 89.597738 -53.7718) (xy 89.441782 -53.7718)
				(xy 89.434416 -53.848) (xy 89.568782 -53.848) (xy 89.621614 -53.848)
				(arc
					(start 89.6493 -53.87594)
					(mid 89.925144 -54.233975)
					(end 89.554812 -53.975)
				)
				(xy 89.422478 -53.975)
				(arc
					(start 89.415874 -54.043326)
					(mid 89.727024 -54.420008)
					(end 90.103706 -54.108858)
				)
			)
		)
	)
	(zone
		(layer "In2.Cu")
		(hatch none 0.5)
		(connect_pads
			(clearance 0)
		)
		(min_thickness 0.25)
		(keepout
			(tracks not_allowed)
			(vias allowed)
			(pads allowed)
			(copperpour not_allowed)
			(footprints allowed)
		)
		(placement
			(enabled no)
			(sheetname "")
		)
		(fill
			(thermal_gap 0.5)
			(thermal_bridge_width 0.5)
			(island_removal_mode 0)
		)
		(polygon
			(pts
				(arc
					(start 37.41801 -13.43406)
					(mid 37.03447 -13.8176)
					(end 37.41801 -14.20114)
				)
				(xy 37.61105 -14.20114) (xy 37.61105 -14.109446)
				(arc
					(start 37.550598 -14.048994)
					(mid 37.229433 -13.629023)
					(end 37.649404 -13.950188)
				)
				(xy 37.75075 -14.051534) (xy 37.75075 -14.20114) (xy 37.94125 -14.20114) (xy 37.94125 -14.059154)
				(xy 37.94887 -14.051534)
				(arc
					(start 38.050216 -13.950188)
					(mid 38.470187 -13.629023)
					(end 38.149022 -14.048994)
				)
				(xy 38.138862 -14.059154) (xy 38.08095 -14.117066) (xy 38.08095 -14.20114)
				(arc
					(start 38.281356 -14.20114)
					(mid 38.66515 -13.817727)
					(end 38.28161 -13.43406)
				)
			)
		)
	)
	(zone
		(net "GND")
		(layer "In2.Cu")
		(hatch none 0.5)
		(connect_pads
			(clearance 0.5)
		)
		(min_thickness 0.25)
		(fill yes
			(thermal_gap 0.5)
			(thermal_bridge_width 0.5)
			(island_removal_mode 0)
		)
		(polygon
			(pts
				(xy 74.93 -38.354) (xy 75.819 -39.243) (xy 77.597 -41.021) (xy 77.597 -41.783) (xy 79.248 -43.434)
				(xy 82.169 -43.434) (xy 82.677 -43.942) (xy 84.582 -43.942) (xy 85.217 -44.577) (xy 85.979 -44.577)
				(xy 87.884 -44.577) (xy 89.535 -44.577) (xy 89.916 -44.196) (xy 90.424 -44.196) (xy 90.551 -44.323)
				(xy 90.551 -45.466) (xy 89.916 -46.101) (xy 89.535 -46.101) (xy 89.408 -46.228) (xy 89.408 -47.371)
				(xy 88.9 -47.879) (xy 86.741 -47.879) (xy 86.487 -47.625) (xy 84.963 -47.625) (xy 84.709 -47.879)
				(xy 84.582 -47.879) (xy 84.328 -47.879) (xy 84.201 -48.006) (xy 83.947 -48.26) (xy 83.82 -48.387)
				(xy 82.931 -48.387) (xy 82.296 -49.022) (xy 80.899 -49.022) (xy 80.391 -48.514) (xy 79.375 -48.514)
				(xy 78.994 -48.133) (xy 78.994 -47.625) (xy 79.248 -47.371) (xy 79.248 -45.974) (xy 79.121 -45.847)
				(xy 78.74 -45.466) (xy 77.216 -45.466) (xy 77.089 -45.466) (xy 76.454 -45.466) (xy 73.406 -42.418)
				(xy 73.279 -42.418) (xy 70.993 -42.418) (xy 70.358 -41.783) (xy 70.231 -41.656) (xy 70.231 -40.259)
				(xy 70.485 -40.005) (xy 70.485 -38.481) (xy 70.612 -38.354)
			)
		)
	)
	(zone
		(layer "In2.Cu")
		(hatch none 0.5)
		(connect_pads
			(clearance 0)
		)
		(min_thickness 0.25)
		(keepout
			(tracks not_allowed)
			(vias allowed)
			(pads allowed)
			(copperpour not_allowed)
			(footprints allowed)
		)
		(placement
			(enabled no)
			(sheetname "")
		)
		(fill
			(thermal_gap 0.5)
			(thermal_bridge_width 0.5)
			(island_removal_mode 0)
		)
		(polygon
			(pts
				(arc
					(start 25.4127 -13.43406)
					(mid 25.02916 -13.8176)
					(end 25.4127 -14.20114)
				)
				(xy 25.63495 -14.20114) (xy 25.63495 -14.138656)
				(arc
					(start 25.545288 -14.048994)
					(mid 25.224123 -13.629023)
					(end 25.644094 -13.950188)
				)
				(xy 25.77465 -14.080744) (xy 25.77465 -14.20114) (xy 25.96515 -14.20114) (xy 25.96515 -14.029944)
				(arc
					(start 26.044906 -13.950188)
					(mid 26.464877 -13.629023)
					(end 26.143712 -14.048994)
				)
				(xy 26.10485 -14.087856) (xy 26.10485 -14.20114)
				(arc
					(start 26.276046 -14.20114)
					(mid 26.65984 -13.817727)
					(end 26.2763 -13.43406)
				)
			)
		)
	)
	(zone
		(layer "In2.Cu")
		(hatch none 0.5)
		(connect_pads
			(clearance 0)
		)
		(min_thickness 0.25)
		(keepout
			(tracks not_allowed)
			(vias allowed)
			(pads allowed)
			(copperpour not_allowed)
			(footprints allowed)
		)
		(placement
			(enabled no)
			(sheetname "")
		)
		(fill
			(thermal_gap 0.5)
			(thermal_bridge_width 0.5)
			(island_removal_mode 0)
		)
		(polygon
			(pts
				(arc
					(start 72.847454 -14.32306)
					(mid 72.46366 -14.706473)
					(end 72.8472 -15.09014)
				)
				(xy 73.03135 -15.09014) (xy 73.03135 -14.989556)
				(arc
					(start 72.979788 -14.937994)
					(mid 72.658623 -14.518023)
					(end 73.078594 -14.839188)
				)
				(xy 73.17105 -14.931644) (xy 73.17105 -15.09014) (xy 73.36155 -15.09014) (xy 73.36155 -14.957044)
				(xy 73.38695 -14.931644)
				(arc
					(start 73.479406 -14.839188)
					(mid 73.899377 -14.518023)
					(end 73.578212 -14.937994)
				)
				(xy 73.559162 -14.957044) (xy 73.50125 -15.014956) (xy 73.50125 -15.09014)
				(arc
					(start 73.7108 -15.09014)
					(mid 74.09434 -14.7066)
					(end 73.7108 -14.32306)
				)
			)
		)
	)
	(zone
		(net "GND")
		(layer "In2.Cu")
		(hatch none 0.5)
		(connect_pads
			(clearance 0.5)
		)
		(min_thickness 0.25)
		(fill yes
			(thermal_gap 0.5)
			(thermal_bridge_width 0.5)
			(island_removal_mode 0)
		)
		(polygon
			(pts
				(xy 1.016 -15.494) (xy 17.145 -15.494) (xy 21.59 -19.939) (xy 24.003 -19.939) (xy 24.257 -19.939)
				(xy 28.575 -24.257) (xy 28.575 -24.511) (xy 28.575 -32.004) (xy 30.099 -33.528) (xy 30.099 -34.798)
				(xy 30.353 -35.052) (xy 30.734 -35.052) (xy 30.861 -35.179) (xy 30.861 -35.433) (xy 30.734 -35.56)
				(xy 30.353 -35.56) (xy 29.21 -35.56) (xy 28.321 -35.56) (xy 28.194 -35.56) (xy 27.813 -35.941) (xy 27.813 -36.068)
				(xy 27.813 -36.957) (xy 27.813 -38.1) (xy 27.813 -48.006) (xy 27.559 -48.26) (xy 27.178 -48.26)
				(xy 26.416 -47.498) (xy 25.273 -47.498) (xy 25.146 -47.625) (xy 25.146 -48.26) (xy 25.654 -48.768)
				(xy 25.654 -50.927) (xy 25.654 -52.324) (xy 27.813 -54.483) (xy 27.813 -57.404) (xy 28.448 -58.039)
				(xy 30.734 -58.039) (xy 30.988 -57.785) (xy 31.496 -57.785) (xy 31.75 -58.039) (xy 35.56 -61.849)
				(xy 42.672 -61.849) (xy 42.926 -61.595) (xy 42.926 -60.96) (xy 42.926 -60.833) (xy 42.545 -60.452)
				(xy 38.481 -60.452) (xy 38.1 -60.071) (xy 38.1 -56.261) (xy 38.354 -56.007) (xy 52.451 -56.007)
				(xy 52.832 -56.388) (xy 55.499 -56.388) (xy 56.134 -57.023) (xy 56.134 -61.595) (xy 56.134 -62.23)
				(xy 58.928 -65.024) (xy 60.325 -65.024) (xy 61.722 -65.024) (xy 61.976 -65.278) (xy 61.976 -72.771)
				(xy 61.722 -73.025) (xy 61.595 -73.025) (xy 61.468 -73.025) (xy 59.182 -73.025) (xy 58.547 -73.025)
				(xy 45.847 -73.025) (xy 44.958 -73.025) (xy 44.704 -72.771) (xy 44.704 -71.12) (xy 47.371 -68.453)
				(xy 52.959 -68.453) (xy 55.118 -66.294) (xy 55.753 -66.294) (xy 56.896 -65.151) (xy 56.896 -64.516)
				(xy 55.88 -63.5) (xy 53.848 -63.5) (xy 53.467 -63.5) (xy 53.086 -63.881) (xy 53.086 -64.262) (xy 53.086 -65.532)
				(xy 51.943 -66.675) (xy 46.736 -66.675) (xy 45.085 -68.326) (xy 44.196 -68.326) (xy 36.83 -68.326)
				(xy 36.195 -68.326) (xy 35.814 -68.707) (xy 34.925 -69.596) (xy 34.417 -69.596) (xy 34.036 -69.215)
				(xy 34.036 -68.199) (xy 33.782 -67.945) (xy 32.512 -67.945) (xy 32.004 -68.453) (xy 29.083 -68.453)
				(xy 28.448 -67.818) (xy 28.448 -64.135) (xy 26.416 -62.103) (xy 24.511 -62.103) (xy 24.003 -62.611)
				(xy 24.003 -68.834) (xy 23.749 -69.088) (xy 22.86 -69.088) (xy 21.971 -68.199) (xy 21.971 -66.294)
				(xy 21.463 -65.786) (xy 21.082 -65.405) (xy 18.669 -65.405) (xy 18.288 -65.786) (xy 18.288 -66.04)
				(xy 18.288 -66.929) (xy 18.034 -67.183) (xy 17.145 -67.183) (xy 16.891 -67.183) (xy 16.637 -66.929)
				(xy 16.637 -66.675) (xy 16.637 -62.103) (xy 17.4625 -61.2775) (xy 17.907 -60.833) (xy 17.907 -51.435)
				(xy 18.796 -50.546) (xy 18.796 -48.768) (xy 18.542 -48.514) (xy 18.161 -48.514) (xy 17.399 -48.514)
				(xy 15.875 -48.514) (xy 15.621 -48.514) (xy 14.224 -49.911) (xy 13.462 -49.911) (xy 12.7 -49.911)
				(xy 12.192 -50.419) (xy 12.192 -59.182) (xy 11.303 -60.071) (xy 11.303 -63.373) (xy 10.795 -63.881)
				(xy 10.795 -66.04) (xy 10.541 -66.294) (xy 10.287 -66.294) (xy 10.033 -66.04) (xy 10.033 -57.277)
				(xy 10.033 -56.388) (xy 10.033 -55.372) (xy 9.906 -55.245) (xy 9.779 -55.118) (xy 9.652 -55.118)
				(xy 8.636 -55.118) (xy 8.001 -54.483) (xy 7.62 -54.102) (xy 7.112 -53.594) (xy 6.985 -53.467) (xy 6.985 -50.038)
				(xy 6.985 -49.911) (xy 7.62 -49.276) (xy 9.652 -49.276) (xy 10.414 -48.514) (xy 10.414 -46.863)
				(xy 8.763 -45.212) (xy 8.763 -43.815) (xy 8.255 -43.307) (xy 8.255 -41.656) (xy 8.255 -40.767) (xy 8.255 -32.385)
				(xy 4.699 -28.829) (xy 1.143 -28.829) (xy 0.889 -28.575) (xy 0.889 -15.621)
			)
		)
	)
	(zone
		(layer "In2.Cu")
		(hatch none 0.5)
		(connect_pads
			(clearance 0)
		)
		(min_thickness 0.25)
		(keepout
			(tracks not_allowed)
			(vias allowed)
			(pads allowed)
			(copperpour not_allowed)
			(footprints allowed)
		)
		(placement
			(enabled no)
			(sheetname "")
		)
		(fill
			(thermal_gap 0.5)
			(thermal_bridge_width 0.5)
			(island_removal_mode 0)
		)
		(polygon
			(pts
				(arc
					(start 84.586572 -54.022498)
					(mid 84.247863 -53.670456)
					(end 83.895692 -54.009036)
				)
				(xy 83.893152 -54.14264) (xy 84.024216 -54.14264)
				(arc
					(start 84.04098 -54.12613)
					(mid 84.402793 -53.853979)
					(end 84.130642 -54.215792)
				)
				(xy 84.114132 -54.232556) (xy 84.077048 -54.26964) (xy 84.024216 -54.26964) (xy 83.890612 -54.26964)
				(xy 83.889342 -54.34584) (xy 84.038948 -54.34584) (xy 84.09178 -54.34584)
				(arc
					(start 84.119974 -54.374288)
					(mid 84.395622 -54.732528)
					(end 84.02574 -54.47284)
				)
				(xy 83.886802 -54.47284)
				(arc
					(start 83.885024 -54.567836)
					(mid 84.22386 -54.91988)
					(end 84.575904 -54.581044)
				)
				(xy 84.580476 -54.34584)
			)
		)
	)
	(zone
		(layer "In2.Cu")
		(hatch none 0.5)
		(connect_pads
			(clearance 0)
		)
		(min_thickness 0.25)
		(keepout
			(tracks not_allowed)
			(vias allowed)
			(pads allowed)
			(copperpour not_allowed)
			(footprints allowed)
		)
		(placement
			(enabled no)
			(sheetname "")
		)
		(fill
			(thermal_gap 0.5)
			(thermal_bridge_width 0.5)
			(island_removal_mode 0)
		)
		(polygon
			(pts
				(arc
					(start 86.030054 -54.801008)
					(mid 85.689948 -54.450234)
					(end 85.339174 -54.79034)
				)
				(xy 85.33765 -54.8894)
				(arc
					(start 85.47608 -54.8894)
					(mid 85.85277 -54.640772)
					(end 85.574124 -54.995826)
				)
				(xy 85.553804 -55.0164) (xy 85.500972 -55.0164) (xy 85.335618 -55.0164) (xy 85.334602 -55.0926)
				(xy 85.443568 -55.0926) (xy 85.4964 -55.0926) (xy 85.533484 -55.129684)
				(arc
					(start 85.565488 -55.161942)
					(mid 85.837639 -55.523755)
					(end 85.475826 -55.251604)
				)
				(xy 85.443568 -55.2196) (xy 85.33257 -55.2196)
				(arc
					(start 85.330538 -55.356506)
					(mid 85.670517 -55.707536)
					(end 86.021418 -55.367428)
				)
				(xy 86.024974 -55.129684) (xy 86.025482 -55.0926)
			)
		)
	)
	(zone
		(layer "In2.Cu")
		(hatch none 0.5)
		(connect_pads
			(clearance 0)
		)
		(min_thickness 0.25)
		(keepout
			(tracks not_allowed)
			(vias allowed)
			(pads allowed)
			(copperpour not_allowed)
			(footprints allowed)
		)
		(placement
			(enabled no)
			(sheetname "")
		)
		(fill
			(thermal_gap 0.5)
			(thermal_bridge_width 0.5)
			(island_removal_mode 0)
		)
		(polygon
			(pts
				(arc
					(start 77.419454 -14.19606)
					(mid 77.03566 -14.579473)
					(end 77.4192 -14.96314)
				)
				(xy 77.62875 -14.96314) (xy 77.62875 -14.887956)
				(arc
					(start 77.551788 -14.810994)
					(mid 77.230623 -14.391023)
					(end 77.650594 -14.712188)
				)
				(xy 77.76845 -14.830044) (xy 77.76845 -14.96314) (xy 77.95895 -14.96314) (xy 77.95895 -14.804644)
				(arc
					(start 78.051406 -14.712188)
					(mid 78.471377 -14.391023)
					(end 78.150212 -14.810994)
				)
				(xy 78.09865 -14.862556) (xy 78.09865 -14.96314)
				(arc
					(start 78.2828 -14.96314)
					(mid 78.66634 -14.5796)
					(end 78.2828 -14.19606)
				)
			)
		)
	)
	(zone
		(layer "In2.Cu")
		(hatch none 0.5)
		(connect_pads
			(clearance 0)
		)
		(min_thickness 0.25)
		(keepout
			(tracks not_allowed)
			(vias allowed)
			(pads allowed)
			(copperpour not_allowed)
			(footprints allowed)
		)
		(placement
			(enabled no)
			(sheetname "")
		)
		(fill
			(thermal_gap 0.5)
			(thermal_bridge_width 0.5)
			(island_removal_mode 0)
		)
		(polygon
			(pts
				(arc
					(start 47.46371 -13.4112)
					(mid 47.08271 -13.7922)
					(end 47.46371 -14.1732)
				)
				(arc
					(start 48.183546 -14.1732)
					(mid 48.5648 -13.792327)
					(end 48.1838 -13.4112)
				)
				(xy 48.10125 -13.4112)
				(arc
					(start 48.10125 -13.538708)
					(mid 48.345167 -14.004411)
					(end 47.96155 -13.64488)
				)
				(xy 47.96155 -13.4112) (xy 47.77105 -13.4112) (xy 47.77105 -13.583666)
				(arc
					(start 47.695104 -13.659612)
					(mid 47.275133 -13.980777)
					(end 47.596298 -13.560806)
				)
				(xy 47.63135 -13.525754) (xy 47.63135 -13.4112)
			)
		)
	)
	(zone
		(layer "In2.Cu")
		(hatch none 0.5)
		(connect_pads
			(clearance 0)
		)
		(min_thickness 0.25)
		(keepout
			(tracks not_allowed)
			(vias allowed)
			(pads allowed)
			(copperpour not_allowed)
			(footprints allowed)
		)
		(placement
			(enabled no)
			(sheetname "")
		)
		(fill
			(thermal_gap 0.5)
			(thermal_bridge_width 0.5)
			(island_removal_mode 0)
		)
		(polygon
			(pts
				(arc
					(start 80.9117 -54.1274)
					(mid 80.5688 -53.7845)
					(end 80.2259 -54.1274)
				)
				(xy 80.2259 -54.1401)
				(arc
					(start 80.340454 -54.1401)
					(mid 80.780101 -54.039906)
					(end 80.398366 -54.2798)
				)
				(xy 80.2259 -54.2798) (xy 80.2259 -54.4703) (xy 80.451706 -54.4703)
				(arc
					(start 80.464152 -54.483)
					(mid 80.74063 -54.837048)
					(end 80.353154 -54.61)
				)
				(xy 80.2259 -54.61)
				(arc
					(start 80.2259 -54.685946)
					(mid 80.568673 -55.0291)
					(end 80.9117 -54.6862)
				)
			)
		)
	)
	(zone
		(layer "In2.Cu")
		(hatch none 0.5)
		(connect_pads
			(clearance 0)
		)
		(min_thickness 0.25)
		(keepout
			(tracks not_allowed)
			(vias allowed)
			(pads allowed)
			(copperpour not_allowed)
			(footprints allowed)
		)
		(placement
			(enabled no)
			(sheetname "")
		)
		(fill
			(thermal_gap 0.5)
			(thermal_bridge_width 0.5)
			(island_removal_mode 0)
		)
		(polygon
			(pts
				(arc
					(start 61.40831 -9.867138)
					(mid 61.02477 -10.250678)
					(end 61.40831 -10.634218)
				)
				(xy 61.6331 -10.634218) (xy 61.6331 -10.574274)
				(arc
					(start 61.540898 -10.482072)
					(mid 61.219733 -10.062101)
					(end 61.639704 -10.383266)
				)
				(xy 61.7728 -10.516362) (xy 61.7728 -10.634218) (xy 61.9633 -10.634218) (xy 61.9633 -10.516362)
				(arc
					(start 62.096396 -10.383266)
					(mid 62.516367 -10.062101)
					(end 62.195202 -10.482072)
				)
				(xy 62.160912 -10.516362) (xy 62.103 -10.574274) (xy 62.103 -10.634218)
				(arc
					(start 62.327536 -10.634218)
					(mid 62.71133 -10.250805)
					(end 62.32779 -9.867138)
				)
			)
		)
	)
	(zone
		(layer "In2.Cu")
		(hatch none 0.5)
		(connect_pads
			(clearance 0)
		)
		(min_thickness 0.25)
		(keepout
			(tracks not_allowed)
			(vias allowed)
			(pads allowed)
			(copperpour not_allowed)
			(footprints allowed)
		)
		(placement
			(enabled no)
			(sheetname "")
		)
		(fill
			(thermal_gap 0.5)
			(thermal_bridge_width 0.5)
			(island_removal_mode 0)
		)
		(polygon
			(pts
				(xy 20.70735 -15.7353)
				(arc
					(start 20.821396 -15.621254)
					(mid 21.241367 -15.300089)
					(end 20.920202 -15.72006)
				)
				(xy 20.77085 -15.869412) (xy 20.77085 -15.872206)
				(arc
					(start 21.052536 -15.872206)
					(mid 21.43633 -15.488793)
					(end 21.05279 -15.105126)
				)
				(arc
					(start 20.09521 -15.105126)
					(mid 19.71167 -15.488666)
					(end 20.09521 -15.872206)
				)
				(xy 20.30095 -15.872206) (xy 20.30095 -15.793212)
				(arc
					(start 20.227798 -15.72006)
					(mid 19.906633 -15.300089)
					(end 20.326604 -15.621254)
				)
				(xy 20.44065 -15.7353) (xy 20.44065 -15.872206) (xy 20.63115 -15.872206) (xy 20.63115 -15.8115)
			)
		)
	)
	(zone
		(layer "In2.Cu")
		(hatch none 0.5)
		(connect_pads
			(clearance 0)
		)
		(min_thickness 0.25)
		(keepout
			(tracks not_allowed)
			(vias allowed)
			(pads allowed)
			(copperpour not_allowed)
			(footprints allowed)
		)
		(placement
			(enabled no)
			(sheetname "")
		)
		(fill
			(thermal_gap 0.5)
			(thermal_bridge_width 0.5)
			(island_removal_mode 0)
		)
		(polygon
			(pts
				(xy 29.94025 -14.817344)
				(arc
					(start 30.045406 -14.712188)
					(mid 30.465377 -14.391023)
					(end 30.144212 -14.810994)
				)
				(xy 30.137862 -14.817344) (xy 30.07995 -14.875256) (xy 30.07995 -14.96314)
				(arc
					(start 30.276546 -14.96314)
					(mid 30.66034 -14.579727)
					(end 30.2768 -14.19606)
				)
				(arc
					(start 29.4132 -14.19606)
					(mid 29.02966 -14.5796)
					(end 29.4132 -14.96314)
				)
				(xy 29.61005 -14.96314) (xy 29.61005 -14.875256)
				(arc
					(start 29.545788 -14.810994)
					(mid 29.224623 -14.391023)
					(end 29.644594 -14.712188)
				)
				(xy 29.74975 -14.817344) (xy 29.74975 -14.96314) (xy 29.94025 -14.96314)
			)
		)
	)
	(zone
		(net "P12V")
		(layer "In2.Cu")
		(hatch none 0.5)
		(connect_pads
			(clearance 0.5)
		)
		(min_thickness 0.25)
		(fill yes
			(thermal_gap 0.5)
			(thermal_bridge_width 0.5)
			(island_removal_mode 0)
		)
		(polygon
			(pts
				(xy 1.27 -29.4386) (xy 0.762254 -29.946346) (xy 0.762254 -53.314854) (xy 0.762254 -55.245254) (xy 3.429 -57.912)
				(xy 4.445 -57.912) (xy 4.953 -58.42) (xy 4.953 -59.563) (xy 4.953 -69.0626) (xy 8.89 -72.9996) (xy 28.321 -72.9996)
				(xy 28.4734 -72.9996) (xy 28.575 -72.898) (xy 28.575 -72.7456) (xy 28.575 -72.39) (xy 28.575 -72.263)
				(xy 28.448 -72.136) (xy 28.321 -72.136) (xy 27.178 -72.136) (xy 25.5016 -70.4596) (xy 24.8666 -70.4596)
				(xy 22.352 -70.4596) (xy 17.653 -70.4596) (xy 17.5006 -70.612) (xy 17.3736 -70.739) (xy 10.922 -70.739)
				(xy 10.795 -70.612) (xy 8.89 -68.707) (xy 8.89 -68.1736) (xy 8.89 -58.039) (xy 8.89 -55.88) (xy 6.604 -53.594)
				(xy 6.604 -51.816) (xy 6.604 -47.371) (xy 6.096 -46.863) (xy 5.969 -46.736) (xy 5.969 -43.307) (xy 6.096 -43.18)
				(xy 6.604 -42.672) (xy 6.604 -42.418) (xy 6.604 -31.5976) (xy 4.445 -29.4386)
			)
		)
	)
	(zone
		(layer "In2.Cu")
		(hatch none 0.5)
		(connect_pads
			(clearance 0)
		)
		(min_thickness 0.25)
		(keepout
			(tracks not_allowed)
			(vias allowed)
			(pads allowed)
			(copperpour not_allowed)
			(footprints allowed)
		)
		(placement
			(enabled no)
			(sheetname "")
		)
		(fill
			(thermal_gap 0.5)
			(thermal_bridge_width 0.5)
			(island_removal_mode 0)
		)
		(polygon
			(pts
				(arc
					(start 88.633808 -53.399182)
					(mid 88.277446 -53.065172)
					(end 87.943436 -53.421534)
				)
				(xy 87.940896 -53.421534) (xy 87.94242 -53.467)
				(arc
					(start 88.067134 -53.467)
					(mid 88.478383 -53.282859)
					(end 88.152478 -53.594)
				)
				(xy 88.142064 -53.594) (xy 87.946484 -53.594) (xy 87.949024 -53.6702) (xy 88.045036 -53.6702) (xy 88.097868 -53.6702)
				(xy 88.134952 -53.707284)
				(arc
					(start 88.196166 -53.768752)
					(mid 88.468317 -54.130565)
					(end 88.106504 -53.858414)
				)
				(xy 88.045036 -53.7972) (xy 87.953088 -53.7972) (xy 87.95893 -53.98008)
				(arc
					(start 87.96147 -53.98008)
					(mid 88.317832 -54.31409)
					(end 88.651842 -53.957728)
				)
				(xy 88.654382 -53.957728) (xy 88.646254 -53.707284) (xy 88.644984 -53.6702) (xy 88.636348 -53.399436)
				(xy 88.636094 -53.399182)
			)
		)
	)
	(zone
		(net "GND")
		(layer "In2.Cu")
		(hatch none 0.5)
		(connect_pads
			(clearance 0.5)
		)
		(min_thickness 0.25)
		(fill yes
			(thermal_gap 0.5)
			(thermal_bridge_width 0.5)
			(island_removal_mode 0)
		)
		(polygon
			(pts
				(xy 0.762254 -58.292746) (xy 0.762254 -72.771254) (xy 1.016 -73.025) (xy 6.985 -73.025) (xy 7.239 -72.771)
				(xy 7.239 -71.882) (xy 4.572 -69.215) (xy 4.572 -69.088) (xy 4.572 -59.563) (xy 4.572 -58.42) (xy 4.318 -58.166)
				(xy 3.175 -58.166) (xy 3.048 -58.039) (xy 2.667 -57.658) (xy 1.27 -56.261) (xy 0.889 -56.261) (xy 0.762 -56.388)
				(xy 0.762 -57.912) (xy 0.762 -58.292492)
			)
		)
	)
	(zone
		(layers "In2.Cu" "In4.Cu" "In7.Cu" "In9.Cu")
		(hatch none 0.5)
		(connect_pads
			(clearance 0)
		)
		(min_thickness 0.25)
		(keepout
			(tracks not_allowed)
			(vias allowed)
			(pads allowed)
			(copperpour not_allowed)
			(footprints allowed)
		)
		(placement
			(enabled no)
			(sheetname "")
		)
		(fill yes
			(thermal_gap 0.5)
			(thermal_bridge_width 0.5)
			(island_removal_mode 0)
		)
		(polygon
			(pts
				(arc
					(start 2.31394 -63.221108)
					(mid 1.9304 -62.837568)
					(end 1.54686 -63.221108)
				)
				(arc
					(start 1.54686 -64.178434)
					(mid 1.929003 -64.562226)
					(end 2.31394 -64.181228)
				)
				(arc
					(start 2.1971 -64.181228)
					(mid 1.9304 -64.4454)
					(end 1.6637 -64.181228)
				)
				(arc
					(start 1.6637 -64.178688)
					(mid 1.9304 -63.911988)
					(end 2.1971 -64.178688)
				)
				(xy 2.31394 -64.178688) (xy 2.31394 -63.223648)
				(arc
					(start 2.1971 -63.223648)
					(mid 1.9304 -63.48782)
					(end 1.6637 -63.223648)
				)
				(arc
					(start 1.6637 -63.221108)
					(mid 1.9304 -62.954408)
					(end 2.1971 -63.221108)
				)
			)
		)
	)
	(zone
		(layers "In2.Cu" "In4.Cu" "In7.Cu" "In9.Cu")
		(hatch none 0.5)
		(connect_pads
			(clearance 0)
		)
		(min_thickness 0.25)
		(keepout
			(tracks not_allowed)
			(vias allowed)
			(pads allowed)
			(copperpour not_allowed)
			(footprints allowed)
		)
		(placement
			(enabled no)
			(sheetname "")
		)
		(fill yes
			(thermal_gap 0.5)
			(thermal_bridge_width 0.5)
			(island_removal_mode 0)
		)
		(polygon
			(pts
				(arc
					(start 69.52234 -27.521408)
					(mid 69.139689 -27.137869)
					(end 68.75526 -27.51963)
				)
				(arc
					(start 68.75145 -28.403296)
					(mid 69.132831 -28.788612)
					(end 69.51853 -28.407614)
				)
				(arc
					(start 69.40169 -28.407614)
					(mid 69.13499 -28.671786)
					(end 68.86829 -28.407614)
				)
				(arc
					(start 68.86829 -28.405074)
					(mid 69.13499 -28.138374)
					(end 69.40169 -28.405074)
				)
				(xy 69.51853 -28.405074) (xy 69.51853 -28.403296) (xy 69.52234 -27.523948)
				(arc
					(start 69.4055 -27.523948)
					(mid 69.1388 -27.78812)
					(end 68.8721 -27.523948)
				)
				(arc
					(start 68.8721 -27.521408)
					(mid 69.1388 -27.254708)
					(end 69.4055 -27.521408)
				)
			)
		)
	)
	(zone
		(layers "In2.Cu" "In4.Cu" "In7.Cu" "In9.Cu")
		(hatch none 0.5)
		(connect_pads
			(clearance 0)
		)
		(min_thickness 0.25)
		(keepout
			(tracks not_allowed)
			(vias allowed)
			(pads allowed)
			(copperpour not_allowed)
			(footprints allowed)
		)
		(placement
			(enabled no)
			(sheetname "")
		)
		(fill yes
			(thermal_gap 0.5)
			(thermal_bridge_width 0.5)
			(island_removal_mode 0)
		)
		(polygon
			(pts
				(arc
					(start 2.31394 -66.221102)
					(mid 1.9304 -65.837562)
					(end 1.54686 -66.221102)
				)
				(arc
					(start 1.54686 -67.178682)
					(mid 1.92913 -67.56222)
					(end 2.31394 -67.181222)
				)
				(arc
					(start 2.1971 -67.181222)
					(mid 1.9304 -67.445394)
					(end 1.6637 -67.181222)
				)
				(arc
					(start 1.6637 -67.178682)
					(mid 1.9304 -66.911982)
					(end 2.1971 -67.178682)
				)
				(xy 2.31394 -67.178682) (xy 2.31394 -66.223642)
				(arc
					(start 2.1971 -66.223642)
					(mid 1.9304 -66.487814)
					(end 1.6637 -66.223642)
				)
				(arc
					(start 1.6637 -66.221102)
					(mid 1.9304 -65.954402)
					(end 2.1971 -66.221102)
				)
			)
		)
	)
	(zone
		(layers "In2.Cu" "In4.Cu" "In7.Cu" "In9.Cu")
		(hatch none 0.5)
		(connect_pads
			(clearance 0)
		)
		(min_thickness 0.25)
		(keepout
			(tracks not_allowed)
			(vias allowed)
			(pads allowed)
			(copperpour not_allowed)
			(footprints allowed)
		)
		(placement
			(enabled no)
			(sheetname "")
		)
		(fill yes
			(thermal_gap 0.5)
			(thermal_bridge_width 0.5)
			(island_removal_mode 0)
		)
		(polygon
			(pts
				(arc
					(start 49.389284 -9.87679)
					(mid 49.00549 -10.260203)
					(end 49.38903 -10.64387)
				)
				(arc
					(start 50.310542 -10.64387)
					(mid 50.580846 -10.53243)
					(end 50.694082 -10.26287)
				)
				(arc
					(start 50.577242 -10.26287)
					(mid 50.310542 -10.527042)
					(end 50.043842 -10.26287)
				)
				(arc
					(start 49.65573 -10.26287)
					(mid 49.38903 -10.527042)
					(end 49.12233 -10.26287)
				)
				(arc
					(start 49.12233 -10.26033)
					(mid 49.38903 -9.99363)
					(end 49.65573 -10.26033)
				)
				(arc
					(start 50.043842 -10.26033)
					(mid 50.310542 -9.99363)
					(end 50.577242 -10.26033)
				)
				(arc
					(start 50.694082 -10.26033)
					(mid 50.581746 -9.989126)
					(end 50.310542 -9.87679)
				)
			)
		)
	)
	(zone
		(layers "In2.Cu" "In4.Cu" "In7.Cu" "In9.Cu")
		(hatch none 0.5)
		(connect_pads
			(clearance 0)
		)
		(min_thickness 0.25)
		(keepout
			(tracks not_allowed)
			(vias allowed)
			(pads allowed)
			(copperpour not_allowed)
			(footprints allowed)
		)
		(placement
			(enabled no)
			(sheetname "")
		)
		(fill yes
			(thermal_gap 0.5)
			(thermal_bridge_width 0.5)
			(island_removal_mode 0)
		)
		(polygon
			(pts
				(arc
					(start 3.7084 -58.706766)
					(mid 3.32486 -58.323226)
					(end 2.94132 -58.706766)
				)
				(arc
					(start 2.94132 -59.664092)
					(mid 3.323463 -60.047884)
					(end 3.7084 -59.666886)
				)
				(arc
					(start 3.59156 -59.666886)
					(mid 3.32486 -59.931058)
					(end 3.05816 -59.666886)
				)
				(arc
					(start 3.05816 -59.664346)
					(mid 3.32486 -59.397646)
					(end 3.59156 -59.664346)
				)
				(xy 3.7084 -59.664346) (xy 3.7084 -58.709306)
				(arc
					(start 3.59156 -58.709306)
					(mid 3.32486 -58.973478)
					(end 3.05816 -58.709306)
				)
				(arc
					(start 3.05816 -58.706766)
					(mid 3.32486 -58.440066)
					(end 3.59156 -58.706766)
				)
			)
		)
	)
	(zone
		(layers "In2.Cu" "In4.Cu" "In7.Cu" "In9.Cu")
		(hatch none 0.5)
		(connect_pads
			(clearance 0)
		)
		(min_thickness 0.25)
		(keepout
			(tracks not_allowed)
			(vias allowed)
			(pads allowed)
			(copperpour not_allowed)
			(footprints allowed)
		)
		(placement
			(enabled no)
			(sheetname "")
		)
		(fill yes
			(thermal_gap 0.5)
			(thermal_bridge_width 0.5)
			(island_removal_mode 0)
		)
		(polygon
			(pts
				(arc
					(start 8.509 -50.6222)
					(mid 8.128 -50.2412)
					(end 7.747 -50.6222)
				)
				(arc
					(start 7.747 -51.6128)
					(mid 8.12673 -51.993798)
					(end 8.509 -51.61534)
				)
				(arc
					(start 8.3947 -51.61534)
					(mid 8.128 -51.879512)
					(end 7.8613 -51.61534)
				)
				(arc
					(start 7.8613 -51.6128)
					(mid 8.128 -51.3461)
					(end 8.3947 -51.6128)
				)
				(xy 8.509 -51.6128) (xy 8.509 -50.62474)
				(arc
					(start 8.3947 -50.62474)
					(mid 8.128 -50.888912)
					(end 7.8613 -50.62474)
				)
				(arc
					(start 7.8613 -50.6222)
					(mid 8.128 -50.3555)
					(end 8.3947 -50.6222)
				)
			)
		)
	)
	(zone
		(layers "In2.Cu" "In4.Cu" "In7.Cu" "In9.Cu")
		(hatch none 0.5)
		(connect_pads
			(clearance 0)
		)
		(min_thickness 0.25)
		(keepout
			(tracks not_allowed)
			(vias allowed)
			(pads allowed)
			(copperpour not_allowed)
			(footprints allowed)
		)
		(placement
			(enabled no)
			(sheetname "")
		)
		(fill yes
			(thermal_gap 0.5)
			(thermal_bridge_width 0.5)
			(island_removal_mode 0)
		)
		(polygon
			(pts
				(arc
					(start 2.31394 -60.221114)
					(mid 1.9304 -59.837574)
					(end 1.54686 -60.221114)
				)
				(arc
					(start 1.54686 -61.178694)
					(mid 1.92913 -61.562232)
					(end 2.31394 -61.181234)
				)
				(arc
					(start 2.1971 -61.181234)
					(mid 1.9304 -61.445406)
					(end 1.6637 -61.181234)
				)
				(arc
					(start 1.6637 -61.178694)
					(mid 1.9304 -60.911994)
					(end 2.1971 -61.178694)
				)
				(xy 2.31394 -61.178694) (xy 2.31394 -60.223654)
				(arc
					(start 2.1971 -60.223654)
					(mid 1.9304 -60.487826)
					(end 1.6637 -60.223654)
				)
				(arc
					(start 1.6637 -60.221114)
					(mid 1.9304 -59.954414)
					(end 2.1971 -60.221114)
				)
			)
		)
	)
	(zone
		(layers "In2.Cu" "In4.Cu" "In7.Cu" "In9.Cu")
		(hatch none 0.5)
		(connect_pads
			(clearance 0)
		)
		(min_thickness 0.25)
		(keepout
			(tracks not_allowed)
			(vias allowed)
			(pads allowed)
			(copperpour not_allowed)
			(footprints allowed)
		)
		(placement
			(enabled no)
			(sheetname "")
		)
		(fill yes
			(thermal_gap 0.5)
			(thermal_bridge_width 0.5)
			(island_removal_mode 0)
		)
		(polygon
			(pts
				(arc
					(start 3.8354 -61.70676)
					(mid 3.45186 -61.32322)
					(end 3.06832 -61.70676)
				)
				(arc
					(start 3.06832 -62.66434)
					(mid 3.45059 -63.047878)
					(end 3.8354 -62.66688)
				)
				(arc
					(start 3.71856 -62.66688)
					(mid 3.45186 -62.931052)
					(end 3.18516 -62.66688)
				)
				(arc
					(start 3.18516 -62.66434)
					(mid 3.45186 -62.39764)
					(end 3.71856 -62.66434)
				)
				(xy 3.8354 -62.66434) (xy 3.8354 -61.7093)
				(arc
					(start 3.71856 -61.7093)
					(mid 3.45186 -61.973472)
					(end 3.18516 -61.7093)
				)
				(arc
					(start 3.18516 -61.70676)
					(mid 3.45186 -61.44006)
					(end 3.71856 -61.70676)
				)
			)
		)
	)
	(zone
		(layers "In2.Cu" "In4.Cu" "In7.Cu" "In9.Cu")
		(hatch none 0.5)
		(connect_pads
			(clearance 0)
		)
		(min_thickness 0.25)
		(keepout
			(tracks not_allowed)
			(vias allowed)
			(pads allowed)
			(copperpour not_allowed)
			(footprints allowed)
		)
		(placement
			(enabled no)
			(sheetname "")
		)
		(fill yes
			(thermal_gap 0.5)
			(thermal_bridge_width 0.5)
			(island_removal_mode 0)
		)
		(polygon
			(pts
				(arc
					(start 38.65372 -29.337)
					(mid 38.27018 -28.95346)
					(end 37.88664 -29.337)
				)
				(arc
					(start 37.88664 -30.2006)
					(mid 38.26891 -30.584138)
					(end 38.65372 -30.20314)
				)
				(arc
					(start 38.53688 -30.20314)
					(mid 38.27018 -30.467312)
					(end 38.00348 -30.20314)
				)
				(arc
					(start 38.00348 -30.2006)
					(mid 38.27018 -29.9339)
					(end 38.53688 -30.2006)
				)
				(xy 38.65372 -30.2006) (xy 38.65372 -29.33954)
				(arc
					(start 38.53688 -29.33954)
					(mid 38.27018 -29.603712)
					(end 38.00348 -29.33954)
				)
				(arc
					(start 38.00348 -29.337)
					(mid 38.27018 -29.0703)
					(end 38.53688 -29.337)
				)
			)
		)
	)
	(zone
		(layers "In2.Cu" "In4.Cu" "In7.Cu" "In9.Cu")
		(hatch none 0.5)
		(connect_pads
			(clearance 0)
		)
		(min_thickness 0.25)
		(keepout
			(tracks not_allowed)
			(vias allowed)
			(pads allowed)
			(copperpour not_allowed)
			(footprints allowed)
		)
		(placement
			(enabled no)
			(sheetname "")
		)
		(fill yes
			(thermal_gap 0.5)
			(thermal_bridge_width 0.5)
			(island_removal_mode 0)
		)
		(polygon
			(pts
				(arc
					(start 9.2202 -52.9082)
					(mid 8.8392 -52.5272)
					(end 8.4582 -52.9082)
				)
				(arc
					(start 8.4582 -53.8988)
					(mid 8.83793 -54.279798)
					(end 9.2202 -53.90134)
				)
				(arc
					(start 9.1059 -53.90134)
					(mid 8.8392 -54.165512)
					(end 8.5725 -53.90134)
				)
				(arc
					(start 8.5725 -53.8988)
					(mid 8.8392 -53.6321)
					(end 9.1059 -53.8988)
				)
				(xy 9.2202 -53.8988) (xy 9.2202 -52.91074)
				(arc
					(start 9.1059 -52.91074)
					(mid 8.8392 -53.174912)
					(end 8.5725 -52.91074)
				)
				(arc
					(start 8.5725 -52.9082)
					(mid 8.8392 -52.6415)
					(end 9.1059 -52.9082)
				)
			)
		)
	)
	(zone
		(layers "In2.Cu" "In4.Cu" "In7.Cu" "In9.Cu")
		(hatch none 0.5)
		(connect_pads
			(clearance 0)
		)
		(min_thickness 0.25)
		(keepout
			(tracks not_allowed)
			(vias allowed)
			(pads allowed)
			(copperpour not_allowed)
			(footprints allowed)
		)
		(placement
			(enabled no)
			(sheetname "")
		)
		(fill yes
			(thermal_gap 0.5)
			(thermal_bridge_width 0.5)
			(island_removal_mode 0)
		)
		(polygon
			(pts
				(arc
					(start 3.8354 -64.706754)
					(mid 3.45186 -64.323214)
					(end 3.06832 -64.706754)
				)
				(arc
					(start 3.06832 -65.664334)
					(mid 3.45059 -66.047872)
					(end 3.8354 -65.666874)
				)
				(arc
					(start 3.71856 -65.666874)
					(mid 3.45186 -65.931046)
					(end 3.18516 -65.666874)
				)
				(arc
					(start 3.18516 -65.664334)
					(mid 3.45186 -65.397634)
					(end 3.71856 -65.664334)
				)
				(xy 3.8354 -65.664334) (xy 3.8354 -64.709294)
				(arc
					(start 3.71856 -64.709294)
					(mid 3.45186 -64.973466)
					(end 3.18516 -64.709294)
				)
				(arc
					(start 3.18516 -64.706754)
					(mid 3.45186 -64.440054)
					(end 3.71856 -64.706754)
				)
			)
		)
	)
	(zone
		(net "PV_VDDR")
		(layers "In2.Cu" "In7.Cu" "In9.Cu")
		(hatch none 0.5)
		(connect_pads
			(clearance 0.5)
		)
		(min_thickness 0.25)
		(fill yes
			(thermal_gap 0.5)
			(thermal_bridge_width 0.5)
			(island_removal_mode 0)
		)
		(polygon
			(pts
				(xy 200.279 -56.007) (xy 200.787 -56.007) (xy 200.914 -55.88) (xy 200.914 -52.832) (xy 201.295 -52.451)
				(xy 201.676 -52.451) (xy 201.93 -52.197) (xy 201.93 -51.816) (xy 201.803 -51.689) (xy 201.803 -49.276)
				(xy 203.2 -47.879) (xy 203.2 -47.498) (xy 202.946 -47.244) (xy 202.692 -47.244) (xy 200.279 -47.244)
				(xy 199.771 -47.244) (xy 199.136 -47.879) (xy 199.136 -48.387) (xy 199.136 -51.181) (xy 199.136 -51.689)
				(xy 200.025 -52.578) (xy 200.025 -55.753) (xy 200.152 -55.88)
			)
		)
	)
	(zone
		(net "PVCCP")
		(layer "In3.Cu")
		(hatch none 0.5)
		(connect_pads
			(clearance 0.5)
		)
		(min_thickness 0.25)
		(fill yes
			(thermal_gap 0.5)
			(thermal_bridge_width 0.5)
			(island_removal_mode 0)
		)
		(polygon
			(pts
				(xy 95.074994 -36.8935) (xy 94.1705 -37.797994) (xy 94.1705 -39.067994) (xy 92.915994 -40.3225)
				(xy 90.756994 -40.3225) (xy 89.9795 -41.099994) (xy 89.9795 -45.006006) (xy 90.4875 -45.514006)
				(xy 90.4875 -47.546006) (xy 91.2495 -48.308006) (xy 91.2495 -49.862994) (xy 91.1225 -49.989994)
				(xy 91.1225 -50.340006) (xy 91.2495 -50.467006) (xy 91.2495 -51.864006) (xy 92.2655 -52.880006)
				(xy 92.2655 -56.563006) (xy 92.7735 -57.071006) (xy 92.7735 -61.389006) (xy 93.677994 -62.2935)
				(xy 95.044006 -62.2935) (xy 96.2025 -61.135006) (xy 96.2025 -56.817006) (xy 96.7105 -56.309006)
				(xy 96.7105 -54.307994) (xy 96.4565 -54.053994) (xy 96.4565 -49.989994) (xy 96.3295 -49.862994)
				(xy 95.8215 -49.354994) (xy 95.8215 -45.006006) (xy 96.441006 -44.3865) (xy 97.233994 -44.3865)
				(xy 97.360994 -44.5135) (xy 102.537006 -44.5135) (xy 102.8065 -44.244006) (xy 102.8065 -41.988994)
				(xy 102.5525 -41.734994) (xy 102.5525 -41.069006) (xy 102.918006 -40.7035) (xy 105.331006 -40.7035)
				(xy 105.6005 -40.434006) (xy 105.6005 -40.083994) (xy 105.331006 -39.8145) (xy 104.696006 -39.8145)
				(xy 104.4575 -39.575994) (xy 104.4575 -38.686994) (xy 104.315006 -38.5445) (xy 103.680006 -38.5445)
				(xy 102.029006 -36.8935)
			)
		)
	)
	(zone
		(net "GND")
		(layer "In3.Cu")
		(hatch none 0.5)
		(connect_pads
			(clearance 0.5)
		)
		(min_thickness 0.25)
		(fill yes
			(thermal_gap 0.5)
			(thermal_bridge_width 0.5)
			(island_removal_mode 0)
		)
		(polygon
			(pts
				(arc
					(start 106.000042 -0.763016)
					(mid 105.83247 -0.832426)
					(end 105.76306 -0.999998)
				)
				(arc
					(start 105.76306 -10.700004)
					(mid 105.246685 -11.946643)
					(end 104.000046 -12.463018)
				)
				(arc
					(start 100.000054 -12.463018)
					(mid 98.753415 -11.946643)
					(end 98.23704 -10.700004)
				)
				(xy 98.23704 -5.244592) (xy 97.448624 -5.244592) (xy 88.562942 -5.244592)
				(arc
					(start 88.562942 -10.150094)
					(mid 86.849966 -11.86307)
					(end 85.13699 -10.150094)
				)
				(xy 85.13699 -5.244592) (xy 15.463012 -5.244592)
				(arc
					(start 15.463012 -13.699998)
					(mid 14.946637 -14.946637)
					(end 13.699998 -15.463012)
				)
				(arc
					(start 0.999998 -15.463012)
					(mid 0.832426 -15.532422)
					(end 0.763016 -15.699994)
				)
				(arc
					(start 0.763016 -72.799956)
					(mid 0.832426 -72.967528)
					(end 0.999998 -73.036938)
				)
				(arc
					(start 209.00009 -73.036938)
					(mid 209.167662 -72.967528)
					(end 209.237072 -72.799956)
				)
				(arc
					(start 209.237072 -0.999998)
					(mid 209.167662 -0.832426)
					(end 209.00009 -0.763016)
				)
			)
		)
		(polygon
			(pts
				(arc
					(start 2.31394 -66.220848)
					(mid 1.930273 -65.837562)
					(end 1.54686 -66.221102)
				)
				(arc
					(start 1.54686 -67.178682)
					(mid 1.9304 -67.562222)
					(end 2.31394 -67.178682)
				)
			)
		)
		(polygon
			(pts
				(arc
					(start 3.8354 -64.7065)
					(mid 3.451733 -64.323214)
					(end 3.06832 -64.706754)
				)
				(arc
					(start 3.06832 -65.664334)
					(mid 3.45186 -66.047874)
					(end 3.8354 -65.664334)
				)
			)
		)
		(polygon
			(pts
				(arc
					(start 10.01014 -64.515746)
					(mid 9.626473 -64.13246)
					(end 9.24306 -64.516)
				)
				(arc
					(start 9.24306 -65.405)
					(mid 9.6266 -65.78854)
					(end 10.01014 -65.405)
				)
			)
		)
		(polygon
			(pts
				(arc
					(start 2.31394 -63.221108)
					(mid 1.9304 -62.837568)
					(end 1.54686 -63.221108)
				)
				(arc
					(start 1.54686 -64.178942)
					(mid 1.930527 -64.562228)
					(end 2.31394 -64.178688)
				)
			)
		)
		(polygon
			(pts
				(arc
					(start 10.009886 -62.727078)
					(mid 9.615678 -62.354714)
					(end 9.243314 -62.748922)
				)
				(xy 9.240774 -62.748922) (xy 9.266174 -63.637668) (xy 9.266428 -63.637922)
				(arc
					(start 9.268714 -63.637922)
					(mid 9.662922 -64.010286)
					(end 10.035286 -63.616078)
				)
				(xy 10.037826 -63.616078) (xy 10.012426 -62.727078)
			)
		)
		(polygon
			(pts
				(arc
					(start 101.734366 -61.66993)
					(mid 101.189299 -61.660676)
					(end 101.185472 -62.20587)
				)
				(arc
					(start 101.795072 -62.817756)
					(mid 102.337616 -62.818772)
					(end 102.338632 -62.276228)
				)
			)
		)
		(polygon
			(pts
				(arc
					(start 3.8354 -61.706506)
					(mid 3.451733 -61.32322)
					(end 3.06832 -61.70676)
				)
				(arc
					(start 3.06832 -62.66434)
					(mid 3.45186 -63.04788)
					(end 3.8354 -62.66434)
				)
			)
		)
		(polygon
			(pts
				(arc
					(start 10.01014 -60.959746)
					(mid 9.626473 -60.57646)
					(end 9.24306 -60.96)
				)
				(arc
					(start 9.24306 -61.849)
					(mid 9.6266 -62.23254)
					(end 10.01014 -61.849)
				)
			)
		)
		(polygon
			(pts
				(arc
					(start 99.781106 -60.369704)
					(mid 99.238816 -60.378086)
					(end 99.247198 -60.920376)
				)
				(xy 99.24542 -60.922154) (xy 99.86518 -61.523372) (xy 99.865434 -61.523372)
				(arc
					(start 99.866958 -61.521848)
					(mid 100.409565 -61.513655)
					(end 100.40112 -60.971176)
				)
				(xy 100.402898 -60.969398) (xy 99.782884 -60.367926)
			)
		)
		(polygon
			(pts
				(arc
					(start 81.0514 -60.7187)
					(mid 81.3943 -60.3758)
					(end 81.0514 -60.0329)
				)
				(arc
					(start 80.263746 -60.0329)
					(mid 79.9211 -60.375927)
					(end 80.264 -60.7187)
				)
			)
		)
		(polygon
			(pts
				(arc
					(start 2.31394 -60.22086)
					(mid 1.930273 -59.837574)
					(end 1.54686 -60.221114)
				)
				(arc
					(start 1.54686 -61.178694)
					(mid 1.9304 -61.562234)
					(end 2.31394 -61.178694)
				)
			)
		)
		(polygon
			(pts
				(arc
					(start 84.348828 -59.595258)
					(mid 84.354625 -59.108766)
					(end 83.868006 -59.106054)
				)
				(arc
					(start 83.309968 -59.661806)
					(mid 83.308952 -60.146946)
					(end 83.794092 -60.147962)
				)
			)
		)
		(polygon
			(pts
				(arc
					(start 10.009886 -59.171078)
					(mid 9.615678 -58.798714)
					(end 9.243314 -59.192922)
				)
				(xy 9.240774 -59.192922) (xy 9.266174 -60.081668) (xy 9.266428 -60.081922)
				(arc
					(start 9.268714 -60.081922)
					(mid 9.662922 -60.454286)
					(end 10.035286 -60.060078)
				)
				(xy 10.037826 -60.060078) (xy 10.012426 -59.171078)
			)
		)
		(polygon
			(pts
				(arc
					(start 3.7084 -58.706766)
					(mid 3.32486 -58.323226)
					(end 2.94132 -58.706766)
				)
				(arc
					(start 2.94132 -59.6646)
					(mid 3.324987 -60.047886)
					(end 3.7084 -59.664346)
				)
			)
		)
		(polygon
			(pts
				(arc
					(start 10.01014 -57.403746)
					(mid 9.626473 -57.02046)
					(end 9.24306 -57.404)
				)
				(arc
					(start 9.24306 -58.293)
					(mid 9.6266 -58.67654)
					(end 10.01014 -58.293)
				)
			)
		)
		(polygon
			(pts
				(arc
					(start 10.01014 -55.625746)
					(mid 9.626473 -55.24246)
					(end 9.24306 -55.626)
				)
				(arc
					(start 9.24306 -56.515)
					(mid 9.6266 -56.89854)
					(end 10.01014 -56.515)
				)
			)
		)
		(polygon
			(pts
				(arc
					(start 83.701636 -55.68061)
					(mid 83.668625 -55.193446)
					(end 83.18119 -55.226204)
				)
				(arc
					(start 82.803746 -55.65902)
					(mid 82.83702 -56.146446)
					(end 83.324446 -56.113172)
				)
			)
		)
		(polygon
			(pts
				(arc
					(start 91.580462 -55.242714)
					(mid 91.688158 -54.76621)
					(end 91.211654 -54.658514)
				)
				(xy 91.210384 -54.656482) (xy 90.73769 -54.954678) (xy 90.73769 -54.954932)
				(arc
					(start 90.73896 -54.956964)
					(mid 90.631264 -55.433468)
					(end 91.107768 -55.541164)
				)
				(xy 91.109038 -55.543196) (xy 91.581732 -55.244746)
			)
		)
		(polygon
			(pts
				(arc
					(start 86.030054 -54.801008)
					(mid 85.689948 -54.450234)
					(end 85.339174 -54.79034)
				)
				(arc
					(start 85.330538 -55.356506)
					(mid 85.670517 -55.707536)
					(end 86.021418 -55.367428)
				)
			)
		)
		(polygon
			(pts
				(arc
					(start 87.528908 -54.284118)
					(mid 87.190326 -53.93182)
					(end 86.838028 -54.270402)
				)
				(arc
					(start 86.826852 -54.834028)
					(mid 87.165307 -55.186583)
					(end 87.517732 -54.847998)
				)
			)
		)
		(polygon
			(pts
				(arc
					(start 80.9117 -54.1274)
					(mid 80.5688 -53.7845)
					(end 80.2259 -54.1274)
				)
				(arc
					(start 80.2259 -54.686454)
					(mid 80.568927 -55.0291)
					(end 80.9117 -54.6862)
				)
			)
		)
		(polygon
			(pts
				(arc
					(start 84.586572 -54.022498)
					(mid 84.247863 -53.670456)
					(end 83.895692 -54.009036)
				)
				(arc
					(start 83.885024 -54.567836)
					(mid 84.22386 -54.91988)
					(end 84.575904 -54.581044)
				)
			)
		)
		(polygon
			(pts
				(arc
					(start 10.2616 -53.66766)
					(mid 10.2616 -54.38394)
					(end 10.2616 -53.66766)
				)
			)
		)
		(polygon
			(pts
				(arc
					(start 90.156792 -53.552598)
					(mid 89.845768 -53.175928)
					(end 89.46896 -53.486812)
				)
				(arc
					(start 89.415874 -54.043326)
					(mid 89.727024 -54.420008)
					(end 90.103706 -54.108858)
				)
			)
		)
		(polygon
			(pts
				(arc
					(start 88.633808 -53.399182)
					(mid 88.277446 -53.065172)
					(end 87.943436 -53.421534)
				)
				(xy 87.940896 -53.421534) (xy 87.95893 -53.98008)
				(arc
					(start 87.96147 -53.98008)
					(mid 88.317832 -54.31409)
					(end 88.651842 -53.957728)
				)
				(xy 88.654382 -53.957728) (xy 88.636348 -53.399436) (xy 88.636094 -53.399182)
			)
		)
		(polygon
			(pts
				(arc
					(start 91.403424 -53.414168)
					(mid 91.076653 -53.050941)
					(end 90.71356 -53.377846)
				)
				(xy 90.71102 -53.377592) (xy 90.681556 -53.93817)
				(arc
					(start 90.684096 -53.938424)
					(mid 91.010994 -54.30139)
					(end 91.37396 -53.974492)
				)
				(xy 91.3765 -53.974746) (xy 91.405964 -53.414422) (xy 91.40571 -53.414168)
			)
		)
		(polygon
			(pts
				(arc
					(start 86.443058 -53.20792)
					(mid 86.103968 -52.85613)
					(end 85.752178 -53.19522)
				)
				(arc
					(start 85.741764 -53.758592)
					(mid 86.080727 -54.110638)
					(end 86.432644 -53.771546)
				)
			)
		)
		(polygon
			(pts
				(arc
					(start 82.0293 -53.0098)
					(mid 81.6864 -52.6669)
					(end 81.3435 -53.0098)
				)
				(arc
					(start 81.3435 -53.594254)
					(mid 81.686527 -53.9369)
					(end 82.0293 -53.594)
				)
			)
		)
		(polygon
			(pts
				(arc
					(start 9.2202 -52.907946)
					(mid 8.839073 -52.5272)
					(end 8.4582 -52.9082)
				)
				(arc
					(start 8.4582 -53.8988)
					(mid 8.8392 -54.2798)
					(end 9.2202 -53.8988)
				)
			)
		)
		(polygon
			(pts
				(arc
					(start 10.2616 -52.42306)
					(mid 10.2616 -53.13934)
					(end 10.2616 -52.42306)
				)
			)
		)
		(polygon
			(pts
				(arc
					(start 9.5504 -51.38166)
					(mid 9.5504 -52.09794)
					(end 9.5504 -51.38166)
				)
			)
		)
		(polygon
			(pts
				(arc
					(start 8.509 -50.621946)
					(mid 8.127873 -50.2412)
					(end 7.747 -50.6222)
				)
				(arc
					(start 7.747 -51.6128)
					(mid 8.128 -51.9938)
					(end 8.509 -51.6128)
				)
			)
		)
		(polygon
			(pts
				(arc
					(start 9.5504 -50.13706)
					(mid 9.5504 -50.85334)
					(end 9.5504 -50.13706)
				)
			)
		)
		(polygon
			(pts
				(arc
					(start 13.55598 -47.66056)
					(mid 13.17244 -47.27702)
					(end 12.7889 -47.66056)
				)
				(arc
					(start 12.7889 -48.618394)
					(mid 13.172567 -49.00168)
					(end 13.55598 -48.61814)
				)
			)
		)
		(polygon
			(pts
				(arc
					(start 51.041554 -47.64278)
					(mid 50.663729 -47.253654)
					(end 50.274474 -47.63135)
				)
				(arc
					(start 50.262028 -48.49495)
					(mid 50.63998 -48.884078)
					(end 51.029108 -48.506126)
				)
			)
		)
		(polygon
			(pts
				(arc
					(start 15.082266 -47.21606)
					(mid 15.465806 -46.83252)
					(end 15.082266 -46.44898)
				)
				(arc
					(start 14.152626 -46.44898)
					(mid 13.76934 -46.832647)
					(end 14.15288 -47.21606)
				)
			)
		)
		(polygon
			(pts
				(arc
					(start 61.317378 -45.848016)
					(mid 60.910088 -45.489868)
					(end 60.551822 -45.897038)
				)
				(arc
					(start 60.607448 -46.75886)
					(mid 61.014864 -47.117)
					(end 61.373004 -46.709584)
				)
			)
		)
		(polygon
			(pts
				(arc
					(start 43.41114 -44.5389)
					(mid 43.79468 -44.15536)
					(end 43.41114 -43.77182)
				)
				(arc
					(start 42.453306 -43.77182)
					(mid 42.07002 -44.155487)
					(end 42.45356 -44.5389)
				)
			)
		)
		(polygon
			(pts
				(arc
					(start 45.007276 -43.53306)
					(mid 44.615103 -43.907837)
					(end 44.98975 -44.30014)
				)
				(arc
					(start 45.947838 -44.32173)
					(mid 46.340014 -43.946826)
					(end 45.96511 -43.55465)
				)
			)
		)
		(polygon
			(pts
				(arc
					(start 49.692052 -37.74567)
					(mid 49.15027 -37.771832)
					(end 49.176432 -38.313614)
				)
				(arc
					(start 49.81321 -38.892226)
					(mid 50.356403 -38.869633)
					(end 50.33137 -38.326568)
				)
			)
		)
		(polygon
			(pts
				(xy 102.186994 -36.5125) (xy 94.917006 -36.5125) (xy 93.7895 -37.640006) (xy 93.7895 -38.910006)
				(xy 92.758006 -39.9415) (xy 90.599006 -39.9415) (xy 89.5985 -40.942006) (xy 89.5985 -45.163994)
				(xy 90.1065 -45.671994) (xy 90.1065 -47.703994) (xy 90.8685 -48.465994) (xy 90.8685 -49.705006)
				(xy 90.7415 -49.832006) (xy 90.7415 -50.497994) (xy 90.8685 -50.624994) (xy 90.8685 -52.021994)
				(xy 91.8845 -53.037994) (xy 91.8845 -56.720994) (xy 92.3925 -57.228994) (xy 92.3925 -61.546994)
				(xy 93.520006 -62.6745) (xy 95.201994 -62.6745) (xy 96.5835 -61.292994) (xy 96.5835 -56.974994)
				(xy 97.0915 -56.466994) (xy 97.0915 -54.150006) (xy 96.8375 -53.896006) (xy 96.8375 -49.832006)
				(xy 96.2025 -49.197006) (xy 96.2025 -45.163994) (xy 96.598994 -44.7675) (xy 97.076006 -44.7675)
				(xy 97.203006 -44.8945) (xy 102.694994 -44.8945) (xy 103.1875 -44.401994) (xy 103.1875 -41.831006)
				(xy 102.9335 -41.577006) (xy 102.9335 -41.226994) (xy 103.075994 -41.0845) (xy 105.488994 -41.0845)
				(xy 105.9815 -40.591994) (xy 105.9815 -39.926006) (xy 105.488994 -39.4335) (xy 104.853994 -39.4335)
				(xy 104.8385 -39.418006) (xy 104.8385 -38.529006) (xy 104.472994 -38.1635) (xy 103.837994 -38.1635)
			)
		)
		(polygon
			(pts
				(arc
					(start 60.04179 -35.379406)
					(mid 59.658123 -34.99612)
					(end 59.27471 -35.37966)
				)
				(arc
					(start 59.27471 -36.33724)
					(mid 59.65825 -36.72078)
					(end 60.04179 -36.33724)
				)
			)
		)
		(polygon
			(pts
				(arc
					(start 53.479954 -35.696652)
					(mid 53.862478 -35.311969)
					(end 53.477668 -34.929572)
				)
				(arc
					(start 52.52339 -34.93262)
					(mid 52.14112 -35.31743)
					(end 52.52593 -35.6997)
				)
			)
		)
		(polygon
			(pts
				(arc
					(start 52.16652 -34.47034)
					(mid 52.55006 -34.0868)
					(end 52.16652 -33.70326)
				)
				(arc
					(start 51.282092 -33.70326)
					(mid 50.898806 -34.086927)
					(end 51.282346 -34.47034)
				)
			)
		)
		(polygon
			(pts
				(arc
					(start 78.12024 -30.823154)
					(mid 77.762614 -31.150687)
					(end 78.090014 -31.508446)
				)
				(arc
					(start 78.648814 -31.53283)
					(mid 79.006446 -31.20517)
					(end 78.678786 -30.847538)
				)
			)
		)
		(polygon
			(pts
				(arc
					(start 78.538832 -30.2387)
					(mid 78.878175 -29.892117)
					(end 78.531466 -29.5529)
				)
				(arc
					(start 77.972666 -29.55925)
					(mid 77.633576 -29.90596)
					(end 77.980286 -30.24505)
				)
			)
		)
		(polygon
			(pts
				(arc
					(start 38.65372 -29.336746)
					(mid 38.270053 -28.95346)
					(end 37.88664 -29.337)
				)
				(arc
					(start 37.88664 -30.2006)
					(mid 38.27018 -30.58414)
					(end 38.65372 -30.2006)
				)
			)
		)
		(polygon
			(pts
				(arc
					(start 53.535326 -28.897834)
					(mid 53.151786 -28.514294)
					(end 52.768246 -28.897834)
				)
				(arc
					(start 52.768246 -29.827474)
					(mid 53.151913 -30.21076)
					(end 53.535326 -29.82722)
				)
			)
		)
		(polygon
			(pts
				(arc
					(start 69.52234 -27.52344)
					(mid 69.140705 -27.138123)
					(end 68.75526 -27.51963)
				)
				(arc
					(start 68.75145 -28.403296)
					(mid 69.133212 -28.788614)
					(end 69.51853 -28.406852)
				)
			)
		)
		(polygon
			(pts
				(arc
					(start 50.25263 -20.79498)
					(mid 50.63617 -20.41144)
					(end 50.25263 -20.0279)
				)
				(arc
					(start 49.294796 -20.0279)
					(mid 48.91151 -20.411567)
					(end 49.29505 -20.79498)
				)
			)
		)
		(polygon
			(pts
				(arc
					(start 21.053044 -15.872206)
					(mid 21.43633 -15.488539)
					(end 21.05279 -15.105126)
				)
				(arc
					(start 20.09521 -15.105126)
					(mid 19.71167 -15.488666)
					(end 20.09521 -15.872206)
				)
			)
		)
		(polygon
			(pts
				(arc
					(start 64.389 -15.0876)
					(mid 64.77 -14.7066)
					(end 64.389 -14.3256)
				)
				(arc
					(start 63.626746 -14.3256)
					(mid 63.246 -14.706727)
					(end 63.627 -15.0876)
				)
			)
		)
		(polygon
			(pts
				(arc
					(start 73.7108 -15.09014)
					(mid 74.09434 -14.7066)
					(end 73.7108 -14.32306)
				)
				(arc
					(start 72.846946 -14.32306)
					(mid 72.46366 -14.706727)
					(end 72.8472 -15.09014)
				)
			)
		)
		(polygon
			(pts
				(arc
					(start 66.548254 -15.0622)
					(mid 66.929 -14.681073)
					(end 66.548 -14.3002)
				)
				(arc
					(start 65.786 -14.3002)
					(mid 65.405 -14.6812)
					(end 65.786 -15.0622)
				)
			)
		)
		(polygon
			(pts
				(arc
					(start 68.834 -14.98854)
					(mid 69.21754 -14.605)
					(end 68.834 -14.22146)
				)
				(arc
					(start 68.071746 -14.22146)
					(mid 67.68846 -14.605127)
					(end 68.072 -14.98854)
				)
			)
		)
		(polygon
			(pts
				(arc
					(start 81.077054 -14.96314)
					(mid 81.46034 -14.579473)
					(end 81.0768 -14.19606)
				)
				(arc
					(start 80.2132 -14.19606)
					(mid 79.82966 -14.5796)
					(end 80.2132 -14.96314)
				)
			)
		)
		(polygon
			(pts
				(arc
					(start 78.2828 -14.96314)
					(mid 78.66634 -14.5796)
					(end 78.2828 -14.19606)
				)
				(arc
					(start 77.418946 -14.19606)
					(mid 77.03566 -14.579727)
					(end 77.4192 -14.96314)
				)
			)
		)
		(polygon
			(pts
				(arc
					(start 34.290254 -14.96314)
					(mid 34.67354 -14.579473)
					(end 34.29 -14.19606)
				)
				(arc
					(start 33.4264 -14.19606)
					(mid 33.04286 -14.5796)
					(end 33.4264 -14.96314)
				)
			)
		)
		(polygon
			(pts
				(arc
					(start 30.277054 -14.96314)
					(mid 30.66034 -14.579473)
					(end 30.2768 -14.19606)
				)
				(arc
					(start 29.4132 -14.19606)
					(mid 29.02966 -14.5796)
					(end 29.4132 -14.96314)
				)
			)
		)
		(polygon
			(pts
				(arc
					(start 83.1596 -14.32814)
					(mid 83.54314 -13.9446)
					(end 83.1596 -13.56106)
				)
				(arc
					(start 82.295746 -13.56106)
					(mid 81.91246 -13.944727)
					(end 82.296 -14.32814)
				)
			)
		)
		(polygon
			(pts
				(arc
					(start 53.010054 -14.32814)
					(mid 53.39334 -13.944473)
					(end 53.0098 -13.56106)
				)
				(arc
					(start 52.1462 -13.56106)
					(mid 51.76266 -13.9446)
					(end 52.1462 -14.32814)
				)
			)
		)
		(polygon
			(pts
				(arc
					(start 50.2158 -14.1986)
					(mid 50.5968 -13.8176)
					(end 50.2158 -13.4366)
				)
				(arc
					(start 49.453546 -13.4366)
					(mid 49.0728 -13.817727)
					(end 49.4538 -14.1986)
				)
			)
		)
		(polygon
			(pts
				(arc
					(start 46.177454 -14.1986)
					(mid 46.5582 -13.817473)
					(end 46.1772 -13.4366)
				)
				(arc
					(start 45.466 -13.4366)
					(mid 45.085 -13.8176)
					(end 45.466 -14.1986)
				)
			)
		)
		(polygon
			(pts
				(arc
					(start 42.281856 -14.20114)
					(mid 42.665142 -13.817473)
					(end 42.281602 -13.43406)
				)
				(arc
					(start 41.418002 -13.43406)
					(mid 41.034462 -13.8176)
					(end 41.418002 -14.20114)
				)
			)
		)
		(polygon
			(pts
				(arc
					(start 38.281864 -14.20114)
					(mid 38.66515 -13.817473)
					(end 38.28161 -13.43406)
				)
				(arc
					(start 37.41801 -13.43406)
					(mid 37.03447 -13.8176)
					(end 37.41801 -14.20114)
				)
			)
		)
		(polygon
			(pts
				(arc
					(start 26.276554 -14.20114)
					(mid 26.65984 -13.817473)
					(end 26.2763 -13.43406)
				)
				(arc
					(start 25.4127 -13.43406)
					(mid 25.02916 -13.8176)
					(end 25.4127 -14.20114)
				)
			)
		)
		(polygon
			(pts
				(arc
					(start 22.5298 -14.20114)
					(mid 22.91334 -13.8176)
					(end 22.5298 -13.43406)
				)
				(arc
					(start 21.665946 -13.43406)
					(mid 21.28266 -13.817727)
					(end 21.6662 -14.20114)
				)
			)
		)
		(polygon
			(pts
				(arc
					(start 48.184054 -14.1732)
					(mid 48.5648 -13.792073)
					(end 48.1838 -13.4112)
				)
				(arc
					(start 47.46371 -13.4112)
					(mid 47.08271 -13.7922)
					(end 47.46371 -14.1732)
				)
			)
		)
		(polygon
			(pts
				(arc
					(start 44.211494 -12.98194)
					(mid 44.59478 -12.598273)
					(end 44.21124 -12.21486)
				)
				(arc
					(start 43.25366 -12.21486)
					(mid 42.87012 -12.5984)
					(end 43.25366 -12.98194)
				)
			)
		)
		(polygon
			(pts
				(arc
					(start 40.40124 -12.73048)
					(mid 40.78478 -12.34694)
					(end 40.40124 -11.9634)
				)
				(arc
					(start 39.443406 -11.9634)
					(mid 39.06012 -12.347067)
					(end 39.44366 -12.73048)
				)
			)
		)
		(polygon
			(pts
				(arc
					(start 59.997594 -11.320018)
					(mid 60.381134 -10.936478)
					(end 59.997594 -10.552938)
				)
				(arc
					(start 59.07786 -10.552938)
					(mid 58.694574 -10.936605)
					(end 59.078114 -11.320018)
				)
			)
		)
		(polygon
			(pts
				(arc
					(start 84.310474 -10.79627)
					(mid 84.694014 -10.41273)
					(end 84.310474 -10.02919)
				)
				(arc
					(start 83.388708 -10.02919)
					(mid 83.005422 -10.412857)
					(end 83.388962 -10.79627)
				)
			)
		)
		(polygon
			(pts
				(arc
					(start 80.328516 -10.7188)
					(mid 80.712056 -10.33526)
					(end 80.328516 -9.95172)
				)
				(arc
					(start 79.370682 -9.95172)
					(mid 78.987396 -10.335387)
					(end 79.370936 -10.7188)
				)
			)
		)
		(polygon
			(pts
				(arc
					(start 76.328524 -10.668)
					(mid 76.712064 -10.28446)
					(end 76.328524 -9.90092)
				)
				(arc
					(start 75.37069 -9.90092)
					(mid 74.987404 -10.284587)
					(end 75.370944 -10.668)
				)
			)
		)
		(polygon
			(pts
				(arc
					(start 72.328532 -10.668)
					(mid 72.712072 -10.28446)
					(end 72.328532 -9.90092)
				)
				(arc
					(start 71.370698 -9.90092)
					(mid 70.987412 -10.284587)
					(end 71.370952 -10.668)
				)
			)
		)
		(polygon
			(pts
				(arc
					(start 68.303394 -10.668)
					(mid 68.68668 -10.284333)
					(end 68.30314 -9.90092)
				)
				(arc
					(start 67.34556 -9.90092)
					(mid 66.96202 -10.28446)
					(end 67.34556 -10.668)
				)
			)
		)
		(polygon
			(pts
				(arc
					(start 50.310542 -10.64387)
					(mid 50.694082 -10.26033)
					(end 50.310542 -9.87679)
				)
				(arc
					(start 49.388776 -9.87679)
					(mid 49.00549 -10.260457)
					(end 49.38903 -10.64387)
				)
			)
		)
		(polygon
			(pts
				(arc
					(start 62.328044 -10.634218)
					(mid 62.71133 -10.250551)
					(end 62.32779 -9.867138)
				)
				(arc
					(start 61.40831 -9.867138)
					(mid 61.02477 -10.250678)
					(end 61.40831 -10.634218)
				)
			)
		)
		(polygon
			(pts
				(arc
					(start 48.327818 -10.634218)
					(mid 48.711358 -10.250678)
					(end 48.327818 -9.867138)
				)
				(arc
					(start 47.408084 -9.867138)
					(mid 47.024798 -10.250805)
					(end 47.408338 -10.634218)
				)
			)
		)
		(polygon
			(pts
				(arc
					(start 44.327826 -10.634218)
					(mid 44.711366 -10.250678)
					(end 44.327826 -9.867138)
				)
				(arc
					(start 43.408092 -9.867138)
					(mid 43.024806 -10.250805)
					(end 43.408346 -10.634218)
				)
			)
		)
		(polygon
			(pts
				(arc
					(start 40.327834 -10.634218)
					(mid 40.711374 -10.250678)
					(end 40.327834 -9.867138)
				)
				(arc
					(start 39.4081 -9.867138)
					(mid 39.024814 -10.250805)
					(end 39.408354 -10.634218)
				)
			)
		)
		(polygon
			(pts
				(arc
					(start 36.328096 -10.634218)
					(mid 36.711382 -10.250551)
					(end 36.327842 -9.867138)
				)
				(arc
					(start 35.408362 -9.867138)
					(mid 35.024822 -10.250678)
					(end 35.408362 -10.634218)
				)
			)
		)
		(polygon
			(pts
				(arc
					(start 32.328104 -10.634218)
					(mid 32.71139 -10.250551)
					(end 32.32785 -9.867138)
				)
				(arc
					(start 31.40837 -9.867138)
					(mid 31.02483 -10.250678)
					(end 31.40837 -10.634218)
				)
			)
		)
		(polygon
			(pts
				(arc
					(start 28.328112 -10.634218)
					(mid 28.711398 -10.250551)
					(end 28.327858 -9.867138)
				)
				(arc
					(start 27.408378 -9.867138)
					(mid 27.024838 -10.250678)
					(end 27.408378 -10.634218)
				)
			)
		)
		(polygon
			(pts
				(arc
					(start 24.327866 -10.634218)
					(mid 24.711406 -10.250678)
					(end 24.327866 -9.867138)
				)
				(arc
					(start 23.408132 -9.867138)
					(mid 23.024846 -10.250805)
					(end 23.408386 -10.634218)
				)
			)
		)
		(polygon
			(pts
				(arc
					(start 20.327874 -10.634218)
					(mid 20.711414 -10.250678)
					(end 20.327874 -9.867138)
				)
				(arc
					(start 19.40814 -9.867138)
					(mid 19.024854 -10.250805)
					(end 19.408394 -10.634218)
				)
			)
		)
	)
	(zone
		(net "GND")
		(layer "In4.Cu")
		(hatch none 0.5)
		(connect_pads
			(clearance 0.5)
		)
		(min_thickness 0.25)
		(fill yes
			(thermal_gap 0.5)
			(thermal_bridge_width 0.5)
			(island_removal_mode 0)
		)
		(polygon
			(pts
				(xy 118.300246 -0.762254) (xy 118.0465 -1.016) (xy 118.0465 -1.8415) (xy 119.38 -3.175) (xy 126.873 -3.175)
				(xy 127.508 -2.54) (xy 156.21 -2.54) (xy 173.736 -2.54) (xy 174.371 -3.175) (xy 174.371 -3.937)
				(xy 175.15586 -4.938776) (xy 175.641 -5.715) (xy 176.911 -6.985) (xy 176.911 -12.192) (xy 165.354 -23.749)
				(xy 165.354 -25.654) (xy 159.766 -31.242) (xy 156.083 -31.242) (xy 154.686 -32.639) (xy 149.606 -32.639)
				(xy 148.463 -31.496) (xy 120.015 -31.496) (xy 117.221 -34.29) (xy 115.189 -34.29) (xy 114.554 -33.655)
				(xy 111.125 -33.655) (xy 110.744 -33.274) (xy 110.236 -33.274) (xy 109.474 -34.036) (xy 109.474 -35.433)
				(xy 109.855 -35.814) (xy 109.855 -37.084) (xy 110.109 -37.338) (xy 111.252 -37.338) (xy 111.633 -36.957)
				(xy 112.903 -36.957) (xy 113.284 -37.338) (xy 113.284 -40.005) (xy 113.538 -40.259) (xy 156.2354 -40.259)
				(xy 160.1089 -36.3855) (xy 164.0205 -36.3855) (xy 170.942 -29.464) (xy 195.834 -29.464) (xy 199.898 -25.4)
				(xy 199.898 -20.32) (xy 200.533 -19.685) (xy 208.026 -19.685) (xy 209.169 -18.542) (xy 209.169 -1.016)
				(xy 208.915254 -0.762254)
			)
		)
		(polygon
			(pts
				(xy 195.453 -3.048) (xy 191.516 -3.048) (xy 190.5 -4.064) (xy 190.5 -14.605) (xy 191.643 -15.748)
				(xy 195.199 -15.748) (xy 196.469 -14.478) (xy 196.469 -4.064)
			)
		)
	)
	(zone
		(net "PV_VDDR")
		(layer "In4.Cu")
		(hatch none 0.5)
		(connect_pads
			(clearance 0.5)
		)
		(min_thickness 0.25)
		(fill yes
			(thermal_gap 0.5)
			(thermal_bridge_width 0.5)
			(island_removal_mode 0)
		)
		(polygon
			(pts
				(xy 149.352 -60.071) (xy 161.417 -60.071) (xy 162.306 -60.071) (xy 167.767 -65.532) (xy 168.529 -66.294)
				(xy 168.529 -67.7164) (xy 166.9034 -69.342) (xy 166.4208 -69.8246) (xy 160.5026 -69.8246) (xy 160.401 -69.723)
				(xy 151.13 -69.723) (xy 150.876 -69.469) (xy 150.876 -68.834) (xy 150.495 -68.453) (xy 149.479 -68.453)
				(xy 149.0345 -68.0085) (xy 149.0345 -60.3885)
			)
		)
	)
	(zone
		(net "PV_VDDR")
		(layer "In4.Cu")
		(hatch none 0.5)
		(connect_pads
			(clearance 0.5)
		)
		(min_thickness 0.25)
		(fill yes
			(thermal_gap 0.5)
			(thermal_bridge_width 0.5)
			(island_removal_mode 0)
		)
		(polygon
			(pts
				(xy 158.369 -12.954) (xy 166.751 -12.954) (xy 167.64 -12.065) (xy 167.64 -3.937) (xy 167.64 -3.302)
				(xy 167.259 -2.921) (xy 165.354 -2.921) (xy 165.227 -3.048) (xy 165.227 -3.81) (xy 164.846 -4.191)
				(xy 163.703 -4.191) (xy 163.449 -3.937) (xy 163.322 -3.81) (xy 163.322 -3.048) (xy 163.195 -2.921)
				(xy 156.337 -2.921) (xy 155.829 -3.429) (xy 155.829 -3.556) (xy 155.829 -4.064) (xy 155.829 -10.414)
			)
		)
	)
	(zone
		(net "PV_VDDR")
		(layer "In4.Cu")
		(hatch none 0.5)
		(connect_pads
			(clearance 0.5)
		)
		(min_thickness 0.25)
		(fill yes
			(thermal_gap 0.5)
			(thermal_bridge_width 0.5)
			(island_removal_mode 0)
		)
		(polygon
			(pts
				(xy 200.279 -56.007) (xy 203.708 -56.007) (xy 204.343 -55.372) (xy 204.343 -47.879) (xy 203.454 -46.99)
				(xy 200.406 -46.99) (xy 200.279 -47.117) (xy 200.152 -47.244) (xy 198.247 -47.244) (xy 197.739 -47.752)
				(xy 197.739 -55.118) (xy 198.247 -55.626) (xy 199.898 -55.626)
			)
		)
	)
	(zone
		(net "P3V3")
		(layer "In4.Cu")
		(hatch none 0.5)
		(connect_pads
			(clearance 0.5)
		)
		(min_thickness 0.25)
		(fill yes
			(thermal_gap 0.5)
			(thermal_bridge_width 0.5)
			(island_removal_mode 0)
		)
		(polygon
			(pts
				(xy 52.832 -40.259) (xy 56.388 -36.703) (xy 56.388 -34.544) (xy 57.531 -33.401) (xy 57.912 -33.401)
				(xy 58.166 -33.655) (xy 58.166 -34.163) (xy 57.404 -34.925) (xy 57.404 -36.703) (xy 57.404 -36.957)
				(xy 57.023 -37.338) (xy 57.023 -38.481) (xy 53.594 -41.91) (xy 51.7144 -41.91) (xy 51.435 -42.1894)
				(xy 50.7492 -42.8752) (xy 50.165 -42.8752) (xy 49.8094 -42.5196) (xy 49.8094 -40.8686) (xy 49.8094 -40.6146)
				(xy 50.165 -40.259)
			)
		)
	)
	(zone
		(net "P1V0")
		(layer "In4.Cu")
		(hatch none 0.5)
		(connect_pads
			(clearance 0.5)
		)
		(min_thickness 0.25)
		(fill yes
			(thermal_gap 0.5)
			(thermal_bridge_width 0.5)
			(island_removal_mode 0)
		)
		(polygon
			(pts
				(xy 28.956 -16.891) (xy 27.6225 -18.2245) (xy 27.559 -18.288) (xy 27.559 -25.019) (xy 27.559 -25.146)
				(xy 26.035 -26.67) (xy 26.035 -29.591) (xy 26.416 -29.972) (xy 27.305 -29.972) (xy 27.432 -29.972)
				(xy 29.083 -29.972) (xy 29.718 -29.972) (xy 31.75 -29.972) (xy 32.004 -29.718) (xy 32.385 -29.337)
				(xy 32.385 -22.225) (xy 32.385 -21.717) (xy 33.655 -20.447) (xy 33.782 -20.32) (xy 40.513 -20.32)
				(xy 41.021 -19.812) (xy 44.7294 -19.812) (xy 45.466 -19.0754) (xy 51.054 -19.0754) (xy 53.4416 -21.463)
				(xy 55.626 -21.463) (xy 60.706 -21.463) (xy 61.595 -21.463) (xy 62.992 -21.463) (xy 63.5635 -20.8915)
				(xy 75.3745 -20.8915) (xy 75.565 -20.701) (xy 82.677 -20.701) (xy 85.344 -20.701) (xy 86.106 -21.463)
				(xy 89.154 -21.463) (xy 92.583 -18.034) (xy 92.583 -17.399) (xy 92.075 -16.891) (xy 52.197 -16.891)
				(xy 51.562 -16.256) (xy 47.244 -16.256) (xy 46.863 -16.637) (xy 46.609 -16.891)
			)
		)
	)
	(zone
		(net "PVCCP")
		(layer "In4.Cu")
		(hatch none 0.5)
		(connect_pads
			(clearance 0.5)
		)
		(min_thickness 0.25)
		(fill yes
			(thermal_gap 0.5)
			(thermal_bridge_width 0.5)
			(island_removal_mode 0)
		)
		(polygon
			(pts
				(xy 103.251 -43.18) (xy 103.251 -41.656) (xy 103.251 -41.021) (xy 103.378 -40.894) (xy 104.013 -40.894)
				(xy 105.156 -40.894) (xy 105.283 -40.894) (xy 105.918 -40.259) (xy 106.553 -39.624) (xy 108.839 -39.624)
				(xy 109.093 -39.37) (xy 111.76 -39.37) (xy 112.903 -38.227) (xy 112.903 -37.973) (xy 112.903 -37.592)
				(xy 112.649 -37.338) (xy 111.506 -37.338) (xy 111.252 -37.592) (xy 108.712 -37.592) (xy 108.585 -37.719)
				(xy 102.997 -37.719) (xy 102.743 -37.465) (xy 102.743 -37.211) (xy 102.489 -36.957) (xy 101.473 -35.941)
				(xy 99.822 -35.941) (xy 99.441 -35.56) (xy 94.996 -35.56) (xy 93.853 -36.703) (xy 93.853 -38.862)
				(xy 93.726 -38.989) (xy 93.599 -39.116) (xy 92.964 -39.116) (xy 92.456 -39.624) (xy 91.948 -40.132)
				(xy 91.694 -40.386) (xy 89.154 -40.386) (xy 88.519 -41.021) (xy 87.376 -41.021) (xy 86.995 -41.402)
				(xy 86.233 -42.164) (xy 82.423 -42.164) (xy 79.756 -44.831) (xy 79.756 -46.355) (xy 79.502 -46.609)
				(xy 79.502 -47.879) (xy 79.248 -48.133) (xy 77.343 -48.133) (xy 76.581 -48.895) (xy 76.2 -48.895)
				(xy 76.1365 -48.8315) (xy 70.739 -54.229) (xy 66.167 -54.229) (xy 65.786 -54.61) (xy 60.579 -54.61)
				(xy 60.0075 -55.1815) (xy 56.642 -58.547) (xy 56.642 -62.23) (xy 57.404 -62.992) (xy 58.293 -62.992)
				(xy 68.326 -62.992) (xy 68.961 -62.992) (xy 69.85 -63.881) (xy 91.821 -63.881) (xy 92.71 -63.881)
				(xy 94.234 -62.357) (xy 94.234 -61.468) (xy 94.234 -60.96) (xy 94.234 -56.515) (xy 93.853 -56.134)
				(xy 93.853 -54.483) (xy 94.234 -54.102) (xy 96.266 -52.07) (xy 96.266 -45.593) (xy 96.2787 -45.5803)
				(xy 96.2787 -44.9453) (xy 96.647 -44.577) (xy 101.854 -44.577)
			)
		)
	)
	(zone
		(layer "In4.Cu")
		(hatch none 0.5)
		(connect_pads
			(clearance 0)
		)
		(min_thickness 0.25)
		(keepout
			(tracks not_allowed)
			(vias allowed)
			(pads allowed)
			(copperpour not_allowed)
			(footprints allowed)
		)
		(placement
			(enabled no)
			(sheetname "")
		)
		(fill
			(thermal_gap 0.5)
			(thermal_bridge_width 0.5)
			(island_removal_mode 0)
		)
		(polygon
			(pts
				(xy 78.570836 -31.524448) (xy 78.570836 -31.529528)
				(arc
					(start 78.648814 -31.53283)
					(mid 79.006446 -31.20517)
					(end 78.678786 -30.847538)
				)
				(arc
					(start 78.12024 -30.823154)
					(mid 77.762614 -31.150687)
					(end 78.090014 -31.508446)
				)
				(xy 78.169008 -31.512002) (xy 78.240636 -31.44012) (xy 78.240636 -31.391352)
				(arc
					(start 78.21549 -31.365952)
					(mid 77.943339 -31.004139)
					(end 78.305152 -31.27629)
				)
				(xy 78.330552 -31.301436) (xy 78.367636 -31.33852) (xy 78.367636 -31.391352) (xy 78.367636 -31.44012)
				(xy 78.367636 -31.492952) (xy 78.340966 -31.519368) (xy 78.443836 -31.52394) (xy 78.443836 -31.373064)
				(xy 78.443836 -31.320232)
				(arc
					(start 78.463648 -31.300674)
					(mid 78.818405 -31.021761)
					(end 78.570836 -31.398972)
				)
			)
		)
	)
	(zone
		(net "P3V3_STBY")
		(layer "In4.Cu")
		(hatch none 0.5)
		(connect_pads
			(clearance 0.5)
		)
		(min_thickness 0.25)
		(fill yes
			(thermal_gap 0.5)
			(thermal_bridge_width 0.5)
			(island_removal_mode 0)
		)
		(polygon
			(pts
				(xy 33.528 -24.892) (xy 33.528 -24.257) (xy 33.782 -24.003) (xy 34.8996 -24.003) (xy 35.9283 -22.9743)
				(xy 38.735 -22.9743) (xy 38.7477 -22.987) (xy 41.1353 -22.987) (xy 42.418 -21.7043) (xy 48.2854 -21.7043)
				(xy 48.514 -21.9329) (xy 48.514 -22.479) (xy 48.387 -22.606) (xy 47.498 -22.606) (xy 43.688 -22.606)
				(xy 41.656 -24.638) (xy 38.862 -24.638) (xy 38.481 -24.638) (xy 37.973 -25.146) (xy 33.782 -25.146)
			)
		)
	)
	(zone
		(net "GND")
		(layer "In4.Cu")
		(hatch none 0.5)
		(connect_pads
			(clearance 0.5)
		)
		(min_thickness 0.25)
		(fill yes
			(thermal_gap 0.5)
			(thermal_bridge_width 0.5)
			(island_removal_mode 0)
		)
		(polygon
			(pts
				(xy 186.944 -48.387) (xy 186.944 -48.514) (xy 186.817 -48.641) (xy 185.039 -48.641) (xy 183.769 -47.371)
				(xy 182.0164 -47.371) (xy 180.0225 -49.3649) (xy 180.0225 -53.4035) (xy 185.293 -58.674) (xy 185.293 -68.453)
				(xy 184.658 -69.088) (xy 184.658 -69.469) (xy 184.785 -69.596) (xy 185.039 -69.596) (xy 185.166 -69.469)
				(xy 185.166 -69.088) (xy 185.293 -68.961) (xy 185.801 -68.961) (xy 186.436 -69.596) (xy 186.563 -69.596)
				(xy 191.389 -64.77) (xy 191.389 -60.452) (xy 192.278 -59.563) (xy 193.294 -59.563) (xy 193.802 -59.055)
				(xy 195.199 -60.452) (xy 195.199 -72.644) (xy 195.58 -73.025) (xy 199.644 -73.025) (xy 203.835 -73.025)
				(xy 208.915 -73.025) (xy 209.169 -72.771) (xy 209.169 -68.961) (xy 209.042 -68.834) (xy 208.788 -68.834)
				(xy 206.375 -71.247) (xy 204.978 -71.247) (xy 204.6605 -70.9295) (xy 204.6605 -66.7385) (xy 205.867 -65.532)
				(xy 206.121 -65.278) (xy 206.121 -50.038) (xy 206.121 -48.387) (xy 205.994 -48.26) (xy 205.486 -48.26)
				(xy 204.851 -48.895) (xy 204.851 -65.151) (xy 203.708 -66.294) (xy 203.708 -67.31) (xy 202.184 -68.834)
				(xy 199.644 -68.834) (xy 199.517 -68.834) (xy 196.977 -66.294) (xy 196.977 -66.167) (xy 196.977 -62.103)
				(xy 196.977 -45.72) (xy 196.977 -40.132) (xy 196.215 -39.37) (xy 183.896 -39.37) (xy 183.515 -39.751)
				(xy 183.515 -44.958)
			)
		)
	)
	(zone
		(net "P3V3_STBY")
		(layer "In4.Cu")
		(hatch none 0.5)
		(connect_pads
			(clearance 0.5)
		)
		(min_thickness 0.25)
		(fill yes
			(thermal_gap 0.5)
			(thermal_bridge_width 0.5)
			(island_removal_mode 0)
		)
		(polygon
			(pts
				(xy 28.702 -40.64) (xy 28.702 -40.132) (xy 30.48 -38.354) (xy 38.735 -38.354) (xy 39.624 -39.243)
				(xy 40.64 -39.243) (xy 41.148 -39.243) (xy 42.164 -40.259) (xy 42.164 -44.45) (xy 42.418 -44.704)
				(xy 44.196 -44.704) (xy 44.577 -45.085) (xy 45.466 -45.085) (xy 46.482 -44.069) (xy 46.482 -42.799)
				(xy 46.482 -42.418) (xy 48.26 -40.64) (xy 49.149 -40.64) (xy 49.403 -40.894) (xy 49.403 -42.164)
				(xy 49.403 -43.434) (xy 46.101 -46.736) (xy 42.291 -46.736) (xy 41.91 -46.355) (xy 40.894 -45.339)
				(xy 40.894 -41.275) (xy 40.386 -40.767) (xy 39.37 -40.767) (xy 38.862 -40.259) (xy 38.481 -39.878)
				(xy 31.877 -39.878) (xy 30.861 -40.894) (xy 28.956 -40.894)
			)
		)
	)
	(zone
		(net "GND")
		(layer "In4.Cu")
		(hatch none 0.5)
		(connect_pads
			(clearance 0.5)
		)
		(min_thickness 0.25)
		(fill yes
			(thermal_gap 0.5)
			(thermal_bridge_width 0.5)
			(island_removal_mode 0)
		)
		(polygon
			(pts
				(xy 72.39 -41.529) (xy 74.295 -39.624) (xy 75.438 -39.624) (xy 76.073 -38.989) (xy 76.073 -36.068)
				(xy 75.565 -35.56) (xy 71.247 -35.56) (xy 70.993 -35.814) (xy 70.993 -36.322) (xy 69.977 -37.338)
				(xy 69.977 -41.275) (xy 69.977 -41.402) (xy 70.358 -41.783) (xy 72.136 -41.783)
			)
		)
	)
	(zone
		(layer "In4.Cu")
		(hatch none 0.5)
		(connect_pads
			(clearance 0)
		)
		(min_thickness 0.25)
		(keepout
			(tracks not_allowed)
			(vias allowed)
			(pads allowed)
			(copperpour not_allowed)
			(footprints allowed)
		)
		(placement
			(enabled no)
			(sheetname "")
		)
		(fill
			(thermal_gap 0.5)
			(thermal_bridge_width 0.5)
			(island_removal_mode 0)
		)
		(polygon
			(pts
				(arc
					(start 42.453814 -43.77182)
					(mid 42.07002 -44.155233)
					(end 42.45356 -44.5389)
				)
				(arc
					(start 43.41114 -44.5389)
					(mid 43.79468 -44.15536)
					(end 43.41114 -43.77182)
				)
				(xy 43.17365 -43.77182) (xy 43.17365 -43.819064)
				(arc
					(start 43.278552 -43.923966)
					(mid 43.599717 -44.343937)
					(end 43.179746 -44.022772)
				)
				(xy 43.03395 -43.876976) (xy 43.03395 -43.77182) (xy 42.84345 -43.77182) (xy 42.84345 -43.864276)
				(arc
					(start 42.684954 -44.022772)
					(mid 42.264983 -44.343937)
					(end 42.586148 -43.923966)
				)
				(xy 42.70375 -43.806364) (xy 42.70375 -43.77182)
			)
		)
	)
	(zone
		(layer "In4.Cu")
		(hatch none 0.5)
		(connect_pads
			(clearance 0)
		)
		(min_thickness 0.25)
		(keepout
			(tracks not_allowed)
			(vias allowed)
			(pads allowed)
			(copperpour not_allowed)
			(footprints allowed)
		)
		(placement
			(enabled no)
			(sheetname "")
		)
		(fill
			(thermal_gap 0.5)
			(thermal_bridge_width 0.5)
			(island_removal_mode 0)
		)
		(polygon
			(pts
				(xy 50.21707 -38.222682) (xy 50.14341 -38.296596)
				(arc
					(start 50.14341 -38.353238)
					(mid 50.07356 -38.877155)
					(end 50.00371 -38.353238)
				)
				(xy 50.00371 -38.238684) (xy 50.113692 -38.128702) (xy 49.972468 -38.000432) (xy 49.873408 -38.099492)
				(arc
					(start 49.691544 -38.099492)
					(mid 49.167627 -38.029642)
					(end 49.691544 -37.959792)
				)
				(xy 49.815496 -37.959792) (xy 49.868836 -37.906452)
				(arc
					(start 49.692052 -37.74567)
					(mid 49.15027 -37.771832)
					(end 49.176432 -38.313614)
				)
				(arc
					(start 49.81321 -38.892226)
					(mid 50.356403 -38.869633)
					(end 50.33137 -38.326568)
				)
			)
		)
	)
	(zone
		(layer "In4.Cu")
		(hatch none 0.5)
		(connect_pads
			(clearance 0)
		)
		(min_thickness 0.25)
		(keepout
			(tracks not_allowed)
			(vias allowed)
			(pads allowed)
			(copperpour not_allowed)
			(footprints allowed)
		)
		(placement
			(enabled no)
			(sheetname "")
		)
		(fill
			(thermal_gap 0.5)
			(thermal_bridge_width 0.5)
			(island_removal_mode 0)
		)
		(polygon
			(pts
				(xy 45.598334 -43.546268) (xy 45.407834 -43.542204) (xy 45.407834 -43.605958)
				(arc
					(start 45.22978 -43.784012)
					(mid 44.809809 -44.105177)
					(end 45.130974 -43.685206)
				)
				(xy 45.268134 -43.548046) (xy 45.268134 -43.538902)
				(arc
					(start 45.007276 -43.53306)
					(mid 44.615103 -43.907837)
					(end 44.98975 -44.30014)
				)
				(arc
					(start 45.947838 -44.32173)
					(mid 46.340014 -43.946826)
					(end 45.96511 -43.55465)
				)
				(xy 45.738034 -43.54957) (xy 45.738034 -43.620944)
				(arc
					(start 45.823886 -43.706796)
					(mid 46.145051 -44.126767)
					(end 45.72508 -43.805602)
				)
				(xy 45.598334 -43.678856)
			)
		)
	)
	(zone
		(net "GND")
		(layer "In4.Cu")
		(hatch none 0.5)
		(connect_pads
			(clearance 0.5)
		)
		(min_thickness 0.25)
		(fill yes
			(thermal_gap 0.5)
			(thermal_bridge_width 0.5)
			(island_removal_mode 0)
		)
		(polygon
			(pts
				(xy 28.575 -45.847) (xy 32.766 -41.656) (xy 37.084 -41.656) (xy 37.719 -42.291) (xy 39.37 -42.291)
				(xy 40.259 -43.18) (xy 40.259 -46.863) (xy 39.878 -47.244) (xy 34.163 -47.244) (xy 33.655 -46.736)
				(xy 28.702 -46.736) (xy 28.448 -46.482) (xy 28.448 -45.974)
			)
		)
	)
	(zone
		(net "GND")
		(layer "In4.Cu")
		(hatch none 0.5)
		(connect_pads
			(clearance 0.5)
		)
		(min_thickness 0.25)
		(fill yes
			(thermal_gap 0.5)
			(thermal_bridge_width 0.5)
			(island_removal_mode 0)
		)
		(polygon
			(pts
				(xy 0.762254 -48.895) (xy 0.762254 -72.771254) (xy 1.016 -73.025) (xy 9.525 -73.025) (xy 9.779 -72.771)
				(xy 9.779 -68.199) (xy 10.668 -67.31) (xy 10.668 -57.531) (xy 10.795 -57.404) (xy 11.049 -57.15)
				(xy 12.573 -55.626) (xy 15.113 -55.626) (xy 16.129 -56.642) (xy 16.129 -59.182) (xy 16.129 -61.976)
				(xy 16.129 -67.437) (xy 16.51 -67.818) (xy 18.669 -67.818) (xy 20.701 -69.85) (xy 43.561 -69.85)
				(xy 46.101 -67.31) (xy 63.627 -67.31) (xy 64.643 -66.294) (xy 64.643 -63.754) (xy 64.262 -63.373)
				(xy 57.023 -63.373) (xy 56.134 -62.484) (xy 56.134 -59.69) (xy 52.451 -56.007) (xy 34.798 -56.007)
				(xy 33.147 -54.356) (xy 25.527 -54.356) (xy 24.511 -55.372) (xy 20.32 -55.372) (xy 19.177 -54.229)
				(xy 10.668 -54.229) (xy 10.541 -54.356) (xy 10.033 -54.356) (xy 9.779 -54.102) (xy 9.779 -53.721)
				(xy 9.779 -52.705) (xy 9.017 -51.943) (xy 9.017 -51.816) (xy 9.017 -50.292) (xy 9.017 -50.165) (xy 8.128 -49.276)
				(xy 5.207 -49.276) (xy 4.953 -49.022) (xy 4.953 -43.942) (xy 5.461 -43.434) (xy 7.874 -43.434) (xy 8.509 -43.434)
				(xy 8.636 -43.561) (xy 8.636 -48.768) (xy 9.779 -49.911) (xy 10.033 -50.165) (xy 14.605 -50.165)
				(xy 22.987 -41.783) (xy 22.987 -39.624) (xy 27.94 -34.671) (xy 28.194 -34.417) (xy 29.21 -34.417)
				(xy 29.464 -34.163) (xy 29.464 -33.401) (xy 27.3685 -31.3055) (xy 26.3525 -31.3055) (xy 25.3365 -31.3055)
				(xy 24.765 -30.734) (xy 24.765 -30.48) (xy 24.892 -30.353) (xy 25.019 -30.353) (xy 25.527 -29.845)
				(xy 25.527 -26.289) (xy 27.178 -24.638) (xy 27.178 -21.717) (xy 26.416 -20.955) (xy 21.717 -20.955)
				(xy 18.415 -24.257) (xy 11.557 -24.257) (xy 11.176 -24.638) (xy 11.176 -27.051) (xy 10.795 -27.432)
				(xy 7.747 -27.432) (xy 7.112 -28.067) (xy 7.112 -32.512) (xy 5.842 -33.782) (xy 1.397 -33.782) (xy 0.762 -34.417)
				(xy 0.762 -48.768) (xy 0.762254 -48.768254)
			)
		)
	)
	(zone
		(layer "In4.Cu")
		(hatch none 0.5)
		(connect_pads
			(clearance 0)
		)
		(min_thickness 0.25)
		(keepout
			(tracks not_allowed)
			(vias allowed)
			(pads allowed)
			(copperpour not_allowed)
			(footprints allowed)
		)
		(placement
			(enabled no)
			(sheetname "")
		)
		(fill
			(thermal_gap 0.5)
			(thermal_bridge_width 0.5)
			(island_removal_mode 0)
		)
		(polygon
			(pts
				(arc
					(start 60.04179 -35.379914)
					(mid 59.658377 -34.99612)
					(end 59.27471 -35.37966)
				)
				(arc
					(start 59.27471 -36.33724)
					(mid 59.65825 -36.72078)
					(end 60.04179 -36.33724)
				)
				(xy 60.04179 -36.11245) (xy 59.981846 -36.11245)
				(arc
					(start 59.889644 -36.204652)
					(mid 59.469673 -36.525817)
					(end 59.790838 -36.105846)
				)
				(xy 59.923934 -35.97275) (xy 60.04179 -35.97275) (xy 60.04179 -35.78225) (xy 59.962034 -35.78225)
				(arc
					(start 59.790838 -35.611054)
					(mid 59.469673 -35.191083)
					(end 59.889644 -35.512248)
				)
				(xy 60.019946 -35.64255) (xy 60.04179 -35.64255)
			)
		)
	)
	(zone
		(net "P12V")
		(layer "In4.Cu")
		(hatch none 0.5)
		(connect_pads
			(clearance 0.5)
		)
		(min_thickness 0.25)
		(fill yes
			(thermal_gap 0.5)
			(thermal_bridge_width 0.5)
			(island_removal_mode 0)
		)
		(polygon
			(pts
				(xy 201.041 -20.32) (xy 203.073 -20.32) (xy 209.169 -26.416) (xy 209.169 -67.945) (xy 206.375 -70.739)
				(xy 205.359 -70.739) (xy 205.105 -70.485) (xy 205.105 -67.056) (xy 205.105 -66.802) (xy 206.375 -65.532)
				(xy 206.502 -65.405) (xy 206.502 -46.736) (xy 206.502 -28.321) (xy 206.375 -28.194) (xy 200.533 -22.352)
				(xy 200.533 -20.828)
			)
		)
	)
	(zone
		(net "P1V0_STBY")
		(layer "In4.Cu")
		(hatch none 0.5)
		(connect_pads
			(clearance 0.5)
		)
		(min_thickness 0.25)
		(fill yes
			(thermal_gap 0.5)
			(thermal_bridge_width 0.5)
			(island_removal_mode 0)
		)
		(polygon
			(pts
				(xy 93.726 -36.576) (xy 93.726 -33.909) (xy 93.218 -33.401) (xy 90.297 -33.401) (xy 89.281 -32.385)
				(xy 87.63 -32.385) (xy 87.376 -32.639) (xy 87.249 -32.639) (xy 86.868 -32.258) (xy 86.868 -32.004)
				(xy 86.614 -31.75) (xy 84.836 -31.75) (xy 84.328 -32.258) (xy 83.693 -32.258) (xy 82.931 -31.496)
				(xy 81.407 -31.496) (xy 80.391 -32.512) (xy 79.883 -33.02) (xy 79.883 -34.163) (xy 78.994 -35.052)
				(xy 77.978 -36.068) (xy 77.978 -37.846) (xy 76.6445 -39.1795) (xy 76.6445 -39.8145) (xy 73.406 -43.053)
				(xy 70.485 -43.053) (xy 67.945 -45.593) (xy 67.183 -46.355) (xy 66.802 -46.736) (xy 66.802 -48.895)
				(xy 65.532 -50.165) (xy 62.738 -50.165) (xy 62.23 -50.673) (xy 62.23 -52.07) (xy 62.484 -52.324)
				(xy 71.755 -52.324) (xy 75.565 -48.514) (xy 75.565 -45.974) (xy 76.327 -45.212) (xy 76.962 -45.212)
				(xy 82.677 -39.497) (xy 82.677 -39.243) (xy 83.82 -38.1) (xy 85.344 -38.1) (xy 85.979 -38.735) (xy 87.503 -38.735)
				(xy 87.884 -39.116) (xy 91.948 -39.116) (xy 93.218 -37.846) (xy 93.218 -37.084)
			)
		)
	)
	(zone
		(net "PV_VDDR")
		(layer "In4.Cu")
		(hatch none 0.5)
		(connect_pads
			(clearance 0.5)
		)
		(min_thickness 0.25)
		(fill yes
			(thermal_gap 0.5)
			(thermal_bridge_width 0.5)
			(island_removal_mode 0)
		)
		(polygon
			(pts
				(xy 199.771 -68.453) (xy 201.803 -68.453) (xy 203.2 -67.056) (xy 203.2 -66.167) (xy 204.47 -64.897)
				(xy 204.47 -56.769) (xy 204.089 -56.388) (xy 200.914 -56.388) (xy 200.152 -56.388) (xy 199.898 -56.388)
				(xy 199.771 -56.261) (xy 199.517 -56.007) (xy 198.12 -56.007) (xy 197.612 -56.515) (xy 197.612 -66.294)
			)
		)
	)
	(zone
		(net "PV_VDDR")
		(layer "In4.Cu")
		(hatch none 0.5)
		(connect_pads
			(clearance 0.5)
		)
		(min_thickness 0.25)
		(fill yes
			(thermal_gap 0.5)
			(thermal_bridge_width 0.5)
			(island_removal_mode 0)
		)
		(polygon
			(pts
				(xy 191.008 -4.064) (xy 191.008 -7.874) (xy 191.008 -8.382) (xy 191.008 -12.446) (xy 191.008 -14.605)
				(xy 191.77 -15.367) (xy 194.945 -15.367) (xy 195.961 -14.351) (xy 195.961 -4.064) (xy 195.453 -3.556)
				(xy 195.326 -3.429) (xy 191.643 -3.429)
			)
		)
	)
	(zone
		(net "P12V")
		(layer "In4.Cu")
		(hatch none 0.5)
		(connect_pads
			(clearance 0.5)
		)
		(min_thickness 0.25)
		(fill yes
			(thermal_gap 0.5)
			(thermal_bridge_width 0.5)
			(island_removal_mode 0)
		)
		(polygon
			(pts
				(xy 96.774 -9.271) (xy 96.393 -9.271) (xy 96.012 -9.652) (xy 95.885 -9.779) (xy 95.504 -10.16) (xy 94.107 -10.16)
				(xy 93.726 -10.541) (xy 93.726 -11.811) (xy 93.599 -11.938) (xy 93.218 -12.319) (xy 91.948 -12.319)
				(xy 91.567 -11.938) (xy 91.059 -11.938) (xy 86.1695 -11.938) (xy 85.979 -11.7475) (xy 85.09 -10.8585)
				(xy 85.05825 -10.82675) (xy 83.21675 -10.82675) (xy 82.55 -10.16) (xy 81.026 -10.16) (xy 80.391 -10.795)
				(xy 61.468 -10.795) (xy 59.309 -10.795) (xy 35.306 -10.795) (xy 34.798 -10.287) (xy 33.147 -10.287)
				(xy 32.639 -10.795) (xy 19.177 -10.795) (xy 18.669 -10.287) (xy 15.875 -10.287) (xy 15.494 -10.668)
				(xy 15.494 -11.303) (xy 15.494 -14.859) (xy 14.859 -15.494) (xy 14.478 -15.494) (xy 1.397 -15.494)
				(xy 0.762 -16.129) (xy 0.762 -32.131) (xy 0.762 -32.639) (xy 1.397 -33.274) (xy 4.699 -33.274) (xy 5.461 -33.274)
				(xy 5.969 -32.766) (xy 5.969 -30.226) (xy 6.223 -29.972) (xy 6.731 -29.464) (xy 6.731 -27.686) (xy 6.858 -27.559)
				(xy 10.414 -24.003) (xy 10.541 -23.876) (xy 16.002 -23.876) (xy 17.272 -22.606) (xy 19.177 -22.606)
				(xy 25.273 -16.51) (xy 26.162 -16.51) (xy 28.702 -16.51) (xy 46.355 -16.51) (xy 47.625 -15.24) (xy 51.435 -15.24)
				(xy 52.705 -16.51) (xy 94.361 -16.51) (xy 97.282 -13.589) (xy 97.409 -13.462) (xy 97.409 -9.779)
				(xy 96.901 -9.271)
			)
		)
	)
	(zone
		(layer "In4.Cu")
		(hatch none 0.5)
		(connect_pads
			(clearance 0)
		)
		(min_thickness 0.25)
		(keepout
			(tracks not_allowed)
			(vias allowed)
			(pads allowed)
			(copperpour not_allowed)
			(footprints allowed)
		)
		(placement
			(enabled no)
			(sheetname "")
		)
		(fill
			(thermal_gap 0.5)
			(thermal_bridge_width 0.5)
			(island_removal_mode 0)
		)
		(polygon
			(pts
				(arc
					(start 51.2826 -33.70326)
					(mid 50.898806 -34.086673)
					(end 51.282346 -34.47034)
				)
				(arc
					(start 52.16652 -34.47034)
					(mid 52.55006 -34.0868)
					(end 52.16652 -33.70326)
				)
				(xy 51.93665 -33.70326) (xy 51.93665 -33.758124)
				(arc
					(start 52.033932 -33.855406)
					(mid 52.355097 -34.275377)
					(end 51.935126 -33.954212)
				)
				(xy 51.79695 -33.816036) (xy 51.79695 -33.70326) (xy 51.60645 -33.70326) (xy 51.60645 -33.861502)
				(arc
					(start 51.51374 -33.954212)
					(mid 51.093769 -34.275377)
					(end 51.414934 -33.855406)
				)
				(xy 51.46675 -33.80359) (xy 51.46675 -33.70326)
			)
		)
	)
	(zone
		(net "GND")
		(layer "In5.Cu")
		(hatch none 0.5)
		(connect_pads
			(clearance 0.5)
		)
		(min_thickness 0.25)
		(fill yes
			(thermal_gap 0.5)
			(thermal_bridge_width 0.5)
			(island_removal_mode 0)
		)
		(polygon
			(pts
				(xy 6.4135 -32.590994) (xy 5.666994 -33.3375) (xy 0.763016 -33.3375)
				(arc
					(start 0.763016 -72.799956)
					(mid 0.832426 -72.967528)
					(end 0.999998 -73.036938)
				)
				(arc
					(start 209.00009 -73.036938)
					(mid 209.167662 -72.967528)
					(end 209.237072 -72.799956)
				)
				(arc
					(start 209.237072 -0.999998)
					(mid 209.167662 -0.832426)
					(end 209.00009 -0.763016)
				)
				(arc
					(start 106.000042 -0.763016)
					(mid 105.83247 -0.832426)
					(end 105.76306 -0.999998)
				)
				(arc
					(start 105.76306 -10.700004)
					(mid 105.246685 -11.946643)
					(end 104.000046 -12.463018)
				)
				(arc
					(start 100.000054 -12.463018)
					(mid 98.753415 -11.946643)
					(end 98.23704 -10.700004)
				)
				(xy 98.23704 -5.244592) (xy 97.448624 -5.244592) (xy 88.562942 -5.244592)
				(arc
					(start 88.562942 -10.150094)
					(mid 86.849966 -11.86307)
					(end 85.13699 -10.150094)
				)
				(xy 85.13699 -5.244592) (xy 15.463012 -5.244592) (xy 15.463012 -10.0965) (xy 16.842994 -10.0965)
				(xy 17.477994 -10.7315) (xy 57.325006 -10.7315) (xy 57.833006 -10.2235) (xy 60.403994 -10.2235)
				(xy 60.911994 -10.7315)
				(arc
					(start 83.175602 -10.7315)
					(mid 83.021902 -10.301358)
					(end 83.388708 -10.02919)
				)
				(arc
					(start 84.310474 -10.02919)
					(mid 84.694014 -10.41273)
					(end 84.310474 -10.79627)
				)
				(xy 84.090764 -10.79627) (xy 84.1375 -10.843006) (xy 84.279994 -10.9855) (xy 84.787994 -10.9855)
				(xy 84.8995 -11.097006) (xy 86.057994 -12.2555) (xy 93.012006 -12.2555) (xy 93.4085 -11.859006)
				(xy 93.4085 -10.589006) (xy 94.028006 -9.9695) (xy 95.298006 -9.9695) (xy 96.314006 -8.9535) (xy 97.106994 -8.9535)
				(xy 97.2185 -9.065006) (xy 97.7265 -9.573006) (xy 97.7265 -13.667994) (xy 89.7255 -21.668994) (xy 89.7255 -22.557994)
				(xy 89.232994 -23.0505) (xy 81.201006 -23.0505) (xy 80.947006 -22.7965) (xy 80.596994 -22.7965)
				(xy 79.707994 -23.6855) (xy 77.137006 -23.6855) (xy 76.121006 -22.6695) (xy 73.357994 -22.6695)
				(xy 72.468994 -23.5585) (xy 68.501006 -23.5585) (xy 67.739006 -22.7965) (xy 64.340994 -22.7965)
				(xy 63.451994 -23.6855) (xy 44.655994 -23.6855) (xy 44.147994 -24.1935) (xy 38.940994 -24.1935)
				(xy 34.749994 -28.3845) (xy 33.606994 -28.3845) (xy 31.574994 -30.4165) (xy 26.210006 -30.4165)
				(xy 25.5905 -29.796994) (xy 25.5905 -26.718006) (xy 27.6225 -24.686006) (xy 27.6225 -21.541994)
				(xy 26.9875 -20.906994) (xy 26.9875 -18.4785) (xy 21.541994 -18.4785) (xy 16.080994 -23.9395) (xy 8.938006 -23.9395)
				(xy 8.303006 -23.3045) (xy 7.063994 -23.3045) (xy 6.4135 -23.954994)
			)
		)
		(polygon
			(pts
				(arc
					(start 2.31394 -66.220848)
					(mid 1.930273 -65.837562)
					(end 1.54686 -66.221102)
				)
				(arc
					(start 1.54686 -67.178682)
					(mid 1.9304 -67.562222)
					(end 2.31394 -67.178682)
				)
			)
		)
		(polygon
			(pts
				(arc
					(start 3.8354 -64.7065)
					(mid 3.451733 -64.323214)
					(end 3.06832 -64.706754)
				)
				(arc
					(start 3.06832 -65.664334)
					(mid 3.45186 -66.047874)
					(end 3.8354 -65.664334)
				)
			)
		)
		(polygon
			(pts
				(arc
					(start 10.01014 -64.515746)
					(mid 9.626473 -64.13246)
					(end 9.24306 -64.516)
				)
				(arc
					(start 9.24306 -65.405)
					(mid 9.6266 -65.78854)
					(end 10.01014 -65.405)
				)
			)
		)
		(polygon
			(pts
				(arc
					(start 2.31394 -63.221108)
					(mid 1.9304 -62.837568)
					(end 1.54686 -63.221108)
				)
				(arc
					(start 1.54686 -64.178942)
					(mid 1.930527 -64.562228)
					(end 2.31394 -64.178688)
				)
			)
		)
		(polygon
			(pts
				(arc
					(start 10.009886 -62.727078)
					(mid 9.615678 -62.354714)
					(end 9.243314 -62.748922)
				)
				(xy 9.240774 -62.748922) (xy 9.266174 -63.637668) (xy 9.266428 -63.637922)
				(arc
					(start 9.268714 -63.637922)
					(mid 9.662922 -64.010286)
					(end 10.035286 -63.616078)
				)
				(xy 10.037826 -63.616078) (xy 10.012426 -62.727078)
			)
		)
		(polygon
			(pts
				(arc
					(start 101.734366 -61.66993)
					(mid 101.189299 -61.660676)
					(end 101.185472 -62.20587)
				)
				(arc
					(start 101.795072 -62.817756)
					(mid 102.337616 -62.818772)
					(end 102.338632 -62.276228)
				)
			)
		)
		(polygon
			(pts
				(arc
					(start 3.8354 -61.706506)
					(mid 3.451733 -61.32322)
					(end 3.06832 -61.70676)
				)
				(arc
					(start 3.06832 -62.66434)
					(mid 3.45186 -63.04788)
					(end 3.8354 -62.66434)
				)
			)
		)
		(polygon
			(pts
				(arc
					(start 10.01014 -60.959746)
					(mid 9.626473 -60.57646)
					(end 9.24306 -60.96)
				)
				(arc
					(start 9.24306 -61.849)
					(mid 9.6266 -62.23254)
					(end 10.01014 -61.849)
				)
			)
		)
		(polygon
			(pts
				(arc
					(start 99.781106 -60.369704)
					(mid 99.238816 -60.378086)
					(end 99.247198 -60.920376)
				)
				(xy 99.24542 -60.922154) (xy 99.86518 -61.523372) (xy 99.865434 -61.523372)
				(arc
					(start 99.866958 -61.521848)
					(mid 100.409565 -61.513655)
					(end 100.40112 -60.971176)
				)
				(xy 100.402898 -60.969398) (xy 99.782884 -60.367926)
			)
		)
		(polygon
			(pts
				(arc
					(start 2.31394 -60.22086)
					(mid 1.930273 -59.837574)
					(end 1.54686 -60.221114)
				)
				(arc
					(start 1.54686 -61.178694)
					(mid 1.9304 -61.562234)
					(end 2.31394 -61.178694)
				)
			)
		)
		(polygon
			(pts
				(arc
					(start 10.009886 -59.171078)
					(mid 9.615678 -58.798714)
					(end 9.243314 -59.192922)
				)
				(xy 9.240774 -59.192922) (xy 9.266174 -60.081668) (xy 9.266428 -60.081922)
				(arc
					(start 9.268714 -60.081922)
					(mid 9.662922 -60.454286)
					(end 10.035286 -60.060078)
				)
				(xy 10.037826 -60.060078) (xy 10.012426 -59.171078)
			)
		)
		(polygon
			(pts
				(arc
					(start 3.7084 -58.706766)
					(mid 3.32486 -58.323226)
					(end 2.94132 -58.706766)
				)
				(arc
					(start 2.94132 -59.6646)
					(mid 3.324987 -60.047886)
					(end 3.7084 -59.664346)
				)
			)
		)
		(polygon
			(pts
				(arc
					(start 10.01014 -57.403746)
					(mid 9.626473 -57.02046)
					(end 9.24306 -57.404)
				)
				(arc
					(start 9.24306 -58.293)
					(mid 9.6266 -58.67654)
					(end 10.01014 -58.293)
				)
			)
		)
		(polygon
			(pts
				(arc
					(start 10.01014 -55.625746)
					(mid 9.626473 -55.24246)
					(end 9.24306 -55.626)
				)
				(arc
					(start 9.24306 -56.515)
					(mid 9.6266 -56.89854)
					(end 10.01014 -56.515)
				)
			)
		)
		(polygon
			(pts
				(arc
					(start 10.2616 -53.66766)
					(mid 10.2616 -54.38394)
					(end 10.2616 -53.66766)
				)
			)
		)
		(polygon
			(pts
				(arc
					(start 9.2202 -52.907946)
					(mid 8.839073 -52.5272)
					(end 8.4582 -52.9082)
				)
				(arc
					(start 8.4582 -53.8988)
					(mid 8.8392 -54.2798)
					(end 9.2202 -53.8988)
				)
			)
		)
		(polygon
			(pts
				(arc
					(start 10.2616 -52.42306)
					(mid 10.2616 -53.13934)
					(end 10.2616 -52.42306)
				)
			)
		)
		(polygon
			(pts
				(arc
					(start 9.5504 -51.38166)
					(mid 9.5504 -52.09794)
					(end 9.5504 -51.38166)
				)
			)
		)
		(polygon
			(pts
				(arc
					(start 8.509 -50.621946)
					(mid 8.127873 -50.2412)
					(end 7.747 -50.6222)
				)
				(arc
					(start 7.747 -51.6128)
					(mid 8.128 -51.9938)
					(end 8.509 -51.6128)
				)
			)
		)
		(polygon
			(pts
				(arc
					(start 9.5504 -50.13706)
					(mid 9.5504 -50.85334)
					(end 9.5504 -50.13706)
				)
			)
		)
		(polygon
			(pts
				(arc
					(start 13.55598 -47.66056)
					(mid 13.17244 -47.27702)
					(end 12.7889 -47.66056)
				)
				(arc
					(start 12.7889 -48.618394)
					(mid 13.172567 -49.00168)
					(end 13.55598 -48.61814)
				)
			)
		)
		(polygon
			(pts
				(arc
					(start 51.041554 -47.64278)
					(mid 50.663729 -47.253654)
					(end 50.274474 -47.63135)
				)
				(arc
					(start 50.262028 -48.49495)
					(mid 50.63998 -48.884078)
					(end 51.029108 -48.506126)
				)
			)
		)
		(polygon
			(pts
				(arc
					(start 15.082266 -47.21606)
					(mid 15.465806 -46.83252)
					(end 15.082266 -46.44898)
				)
				(arc
					(start 14.152626 -46.44898)
					(mid 13.76934 -46.832647)
					(end 14.15288 -47.21606)
				)
			)
		)
		(polygon
			(pts
				(arc
					(start 61.317378 -45.848016)
					(mid 60.910088 -45.489868)
					(end 60.551822 -45.897038)
				)
				(arc
					(start 60.607448 -46.75886)
					(mid 61.014864 -47.117)
					(end 61.373004 -46.709584)
				)
			)
		)
		(polygon
			(pts
				(arc
					(start 43.41114 -44.5389)
					(mid 43.79468 -44.15536)
					(end 43.41114 -43.77182)
				)
				(arc
					(start 42.453306 -43.77182)
					(mid 42.07002 -44.155487)
					(end 42.45356 -44.5389)
				)
			)
		)
		(polygon
			(pts
				(xy 8.543798 -43.688) (xy 5.114798 -43.688) (xy 5.114798 -49.276) (xy 8.543798 -49.276)
			)
		)
		(polygon
			(pts
				(arc
					(start 45.007276 -43.53306)
					(mid 44.615103 -43.907837)
					(end 44.98975 -44.30014)
				)
				(arc
					(start 45.947838 -44.32173)
					(mid 46.340014 -43.946826)
					(end 45.96511 -43.55465)
				)
			)
		)
		(polygon
			(pts
				(xy 38.559994 -38.0365) (xy 30.782006 -38.0365) (xy 30.147006 -38.6715) (xy 26.464006 -38.6715)
				(xy 22.400006 -42.7355) (xy 20.622006 -42.7355) (xy 14.7955 -48.562006) (xy 14.7955 -49.862994)
				(xy 15.288006 -50.3555) (xy 19.255994 -50.3555) (xy 21.287994 -48.3235) (xy 23.827994 -48.3235)
				(xy 28.526994 -43.6245) (xy 32.336994 -43.6245) (xy 34.241994 -41.7195) (xy 37.005006 -41.7195)
				(xy 37.9095 -42.623994) (xy 37.9095 -44.909994) (xy 40.942006 -47.9425) (xy 47.830994 -47.9425)
				(xy 52.402994 -43.3705) (xy 53.926994 -43.3705) (xy 55.3085 -41.988994) (xy 55.3085 -39.672006)
				(xy 54.688994 -39.0525) (xy 53.769006 -39.0525) (xy 52.753006 -40.0685) (xy 48.562006 -40.0685)
				(xy 46.6725 -41.958006) (xy 46.6725 -43.863006) (xy 45.641006 -44.8945) (xy 43.893994 -44.8945)
				(xy 43.639994 -44.6405) (xy 42.242994 -44.6405) (xy 41.9735 -44.371006) (xy 41.9735 -40.180006)
				(xy 40.210994 -38.4175) (xy 38.940994 -38.4175)
			)
		)
		(polygon
			(pts
				(arc
					(start 49.692052 -37.74567)
					(mid 49.15027 -37.771832)
					(end 49.176432 -38.313614)
				)
				(arc
					(start 49.81321 -38.892226)
					(mid 50.356403 -38.869633)
					(end 50.33137 -38.326568)
				)
			)
		)
		(polygon
			(pts
				(arc
					(start 60.04179 -35.379406)
					(mid 59.658123 -34.99612)
					(end 59.27471 -35.37966)
				)
				(arc
					(start 59.27471 -36.33724)
					(mid 59.65825 -36.72078)
					(end 60.04179 -36.33724)
				)
			)
		)
		(polygon
			(pts
				(arc
					(start 53.479954 -35.696652)
					(mid 53.862478 -35.311969)
					(end 53.477668 -34.929572)
				)
				(arc
					(start 52.52339 -34.93262)
					(mid 52.14112 -35.31743)
					(end 52.52593 -35.6997)
				)
			)
		)
		(polygon
			(pts
				(arc
					(start 52.16652 -34.47034)
					(mid 52.55006 -34.0868)
					(end 52.16652 -33.70326)
				)
				(arc
					(start 51.282092 -33.70326)
					(mid 50.898806 -34.086927)
					(end 51.282346 -34.47034)
				)
			)
		)
		(polygon
			(pts
				(xy 94.820994 -32.8295) (xy 92.377006 -32.8295) (xy 91.996006 -33.2105) (xy 89.202006 -33.2105)
				(xy 87.678006 -34.7345) (xy 87.297006 -34.7345) (xy 86.789006 -35.2425) (xy 81.963006 -35.2425)
				(xy 81.2165 -35.989006) (xy 81.2165 -36.751006) (xy 80.0735 -37.894006) (xy 80.0735 -39.799006)
				(xy 77.899006 -41.9735) (xy 75.867006 -41.9735) (xy 75.851766 -41.988994) (xy 73.454006 -44.3865)
				(xy 70.025006 -44.3865) (xy 67.8815 -46.530006) (xy 67.8815 -48.943006) (xy 65.072006 -51.7525)
				(xy 64.056006 -51.7525) (xy 63.167006 -52.6415) (xy 62.024006 -52.6415) (xy 56.4515 -58.214006)
				(xy 56.4515 -62.308994) (xy 57.325006 -63.1825) (xy 93.677994 -63.1825) (xy 95.5675 -61.292994)
				(xy 95.5675 -58.087006) (xy 93.7895 -56.309006) (xy 93.7895 -53.799994) (xy 94.058994 -53.5305)
				(xy 94.820994 -53.5305) (xy 96.8375 -51.513994) (xy 96.8375 -49.832006) (xy 96.2025 -49.197006)
				(xy 96.2025 -45.163994) (xy 96.598994 -44.7675) (xy 97.360994 -44.7675) (xy 97.868994 -44.2595)
				(xy 98.219006 -44.2595) (xy 98.854006 -44.8945) (xy 102.567994 -44.8945) (xy 103.1875 -44.274994)
				(xy 103.1875 -42.593006) (xy 102.8065 -42.212006) (xy 102.8065 -41.226994) (xy 102.948994 -41.0845)
				(xy 105.361994 -41.0845) (xy 106.6165 -39.829994) (xy 106.6165 -38.148006) (xy 105.996994 -37.5285)
				(xy 103.075994 -37.5285) (xy 102.9335 -37.386006) (xy 102.9335 -37.132006) (xy 102.567994 -36.7665)
				(xy 102.186994 -36.7665) (xy 101.170994 -35.7505) (xy 99.773994 -35.7505) (xy 99.265994 -35.2425)
				(xy 96.725994 -35.2425) (xy 96.3295 -34.846006) (xy 96.3295 -34.338006)
			)
		)
		(polygon
			(pts
				(arc
					(start 78.12024 -30.823154)
					(mid 77.762614 -31.150687)
					(end 78.090014 -31.508446)
				)
				(arc
					(start 78.648814 -31.53283)
					(mid 79.006446 -31.20517)
					(end 78.678786 -30.847538)
				)
			)
		)
		(polygon
			(pts
				(arc
					(start 78.538832 -30.2387)
					(mid 78.878175 -29.892117)
					(end 78.531466 -29.5529)
				)
				(arc
					(start 77.972666 -29.55925)
					(mid 77.633576 -29.90596)
					(end 77.980286 -30.24505)
				)
			)
		)
		(polygon
			(pts
				(arc
					(start 38.65372 -29.336746)
					(mid 38.270053 -28.95346)
					(end 37.88664 -29.337)
				)
				(arc
					(start 37.88664 -30.2006)
					(mid 38.27018 -30.58414)
					(end 38.65372 -30.2006)
				)
			)
		)
		(polygon
			(pts
				(arc
					(start 53.535326 -28.897834)
					(mid 53.151786 -28.514294)
					(end 52.768246 -28.897834)
				)
				(arc
					(start 52.768246 -29.827474)
					(mid 53.151913 -30.21076)
					(end 53.535326 -29.82722)
				)
			)
		)
		(polygon
			(pts
				(arc
					(start 69.52234 -27.52344)
					(mid 69.140705 -27.138123)
					(end 68.75526 -27.51963)
				)
				(arc
					(start 68.75145 -28.403296)
					(mid 69.133212 -28.788614)
					(end 69.51853 -28.406852)
				)
			)
		)
		(polygon
			(pts
				(arc
					(start 80.328516 -10.7188)
					(mid 80.712056 -10.33526)
					(end 80.328516 -9.95172)
				)
				(arc
					(start 79.370682 -9.95172)
					(mid 78.987396 -10.335387)
					(end 79.370936 -10.7188)
				)
			)
		)
		(polygon
			(pts
				(arc
					(start 76.328524 -10.668)
					(mid 76.712064 -10.28446)
					(end 76.328524 -9.90092)
				)
				(arc
					(start 75.37069 -9.90092)
					(mid 74.987404 -10.284587)
					(end 75.370944 -10.668)
				)
			)
		)
		(polygon
			(pts
				(arc
					(start 72.328532 -10.668)
					(mid 72.712072 -10.28446)
					(end 72.328532 -9.90092)
				)
				(arc
					(start 71.370698 -9.90092)
					(mid 70.987412 -10.284587)
					(end 71.370952 -10.668)
				)
			)
		)
		(polygon
			(pts
				(arc
					(start 68.303394 -10.668)
					(mid 68.68668 -10.284333)
					(end 68.30314 -9.90092)
				)
				(arc
					(start 67.34556 -9.90092)
					(mid 66.96202 -10.28446)
					(end 67.34556 -10.668)
				)
			)
		)
		(polygon
			(pts
				(arc
					(start 50.310542 -10.64387)
					(mid 50.694082 -10.26033)
					(end 50.310542 -9.87679)
				)
				(arc
					(start 49.388776 -9.87679)
					(mid 49.00549 -10.260457)
					(end 49.38903 -10.64387)
				)
			)
		)
		(polygon
			(pts
				(arc
					(start 62.328044 -10.634218)
					(mid 62.71133 -10.250551)
					(end 62.32779 -9.867138)
				)
				(arc
					(start 61.40831 -9.867138)
					(mid 61.02477 -10.250678)
					(end 61.40831 -10.634218)
				)
			)
		)
		(polygon
			(pts
				(arc
					(start 48.327818 -10.634218)
					(mid 48.711358 -10.250678)
					(end 48.327818 -9.867138)
				)
				(arc
					(start 47.408084 -9.867138)
					(mid 47.024798 -10.250805)
					(end 47.408338 -10.634218)
				)
			)
		)
		(polygon
			(pts
				(arc
					(start 44.327826 -10.634218)
					(mid 44.711366 -10.250678)
					(end 44.327826 -9.867138)
				)
				(arc
					(start 43.408092 -9.867138)
					(mid 43.024806 -10.250805)
					(end 43.408346 -10.634218)
				)
			)
		)
		(polygon
			(pts
				(arc
					(start 40.327834 -10.634218)
					(mid 40.711374 -10.250678)
					(end 40.327834 -9.867138)
				)
				(arc
					(start 39.4081 -9.867138)
					(mid 39.024814 -10.250805)
					(end 39.408354 -10.634218)
				)
			)
		)
		(polygon
			(pts
				(arc
					(start 36.328096 -10.634218)
					(mid 36.711382 -10.250551)
					(end 36.327842 -9.867138)
				)
				(arc
					(start 35.408362 -9.867138)
					(mid 35.024822 -10.250678)
					(end 35.408362 -10.634218)
				)
			)
		)
		(polygon
			(pts
				(arc
					(start 32.328104 -10.634218)
					(mid 32.71139 -10.250551)
					(end 32.32785 -9.867138)
				)
				(arc
					(start 31.40837 -9.867138)
					(mid 31.02483 -10.250678)
					(end 31.40837 -10.634218)
				)
			)
		)
		(polygon
			(pts
				(arc
					(start 28.328112 -10.634218)
					(mid 28.711398 -10.250551)
					(end 28.327858 -9.867138)
				)
				(arc
					(start 27.408378 -9.867138)
					(mid 27.024838 -10.250678)
					(end 27.408378 -10.634218)
				)
			)
		)
		(polygon
			(pts
				(arc
					(start 24.327866 -10.634218)
					(mid 24.711406 -10.250678)
					(end 24.327866 -9.867138)
				)
				(arc
					(start 23.408132 -9.867138)
					(mid 23.024846 -10.250805)
					(end 23.408386 -10.634218)
				)
			)
		)
		(polygon
			(pts
				(arc
					(start 20.327874 -10.634218)
					(mid 20.711414 -10.250678)
					(end 20.327874 -9.867138)
				)
				(arc
					(start 19.40814 -9.867138)
					(mid 19.024854 -10.250805)
					(end 19.408394 -10.634218)
				)
			)
		)
	)
	(zone
		(net "P1V0")
		(layer "In5.Cu")
		(hatch none 0.5)
		(connect_pads
			(clearance 0.5)
		)
		(min_thickness 0.25)
		(fill yes
			(thermal_gap 0.5)
			(thermal_bridge_width 0.5)
			(island_removal_mode 0)
		)
		(polygon
			(pts
				(xy 88.724994 -16.5735) (xy 86.819994 -18.4785) (xy 84.406994 -18.4785) (xy 83.898994 -18.9865)
				(xy 80.566006 -18.9865) (xy 80.312006 -18.7325) (xy 72.438006 -18.7325) (xy 71.930006 -18.2245)
				(xy 61.800994 -18.2245) (xy 61.546994 -18.4785) (xy 27.3685 -18.4785) (xy 27.3685 -20.749006) (xy 28.0035 -21.384006)
				(xy 28.0035 -24.843994) (xy 25.9715 -26.875994) (xy 25.9715 -29.639006) (xy 26.367994 -30.0355)
				(xy 31.417006 -30.0355) (xy 33.449006 -28.0035) (xy 34.592006 -28.0035) (xy 38.783006 -23.8125)
				(xy 43.990006 -23.8125) (xy 44.498006 -23.3045) (xy 63.294006 -23.3045) (xy 64.183006 -22.4155)
				(xy 67.896994 -22.4155) (xy 68.658994 -23.1775) (xy 72.311006 -23.1775) (xy 73.200006 -22.2885)
				(xy 76.278994 -22.2885) (xy 77.294994 -23.3045) (xy 79.550006 -23.3045) (xy 80.439006 -22.4155)
				(xy 81.104994 -22.4155) (xy 81.358994 -22.6695) (xy 89.075006 -22.6695) (xy 89.3445 -22.400006)
				(xy 89.3445 -21.511006) (xy 89.4715 -21.384006) (xy 93.456506 -17.399) (xy 92.631006 -16.5735)
			)
		)
		(polygon
			(pts
				(arc
					(start 50.25263 -20.79498)
					(mid 50.63617 -20.41144)
					(end 50.25263 -20.0279)
				)
				(arc
					(start 49.294796 -20.0279)
					(mid 48.91151 -20.411567)
					(end 49.29505 -20.79498)
				)
			)
		)
	)
	(zone
		(net "PVCCP")
		(layer "In5.Cu")
		(hatch none 0.5)
		(connect_pads
			(clearance 0.5)
		)
		(min_thickness 0.25)
		(fill yes
			(thermal_gap 0.5)
			(thermal_bridge_width 0.5)
			(island_removal_mode 0)
		)
		(polygon
			(pts
				(xy 92.534994 -33.2105) (xy 92.153994 -33.5915) (xy 89.359994 -33.5915) (xy 87.835994 -35.1155)
				(xy 87.454994 -35.1155) (xy 86.946994 -35.6235) (xy 82.120994 -35.6235) (xy 81.5975 -36.146994)
				(xy 81.5975 -36.908994) (xy 80.4545 -38.051994) (xy 80.4545 -39.956994) (xy 78.056994 -42.3545)
				(xy 76.024994 -42.3545) (xy 73.611994 -44.7675) (xy 70.182994 -44.7675) (xy 68.2625 -46.687994)
				(xy 68.2625 -49.100994) (xy 65.229994 -52.1335) (xy 64.213994 -52.1335) (xy 63.324994 -53.0225)
				(xy 62.181994 -53.0225) (xy 56.8325 -58.371994) (xy 56.8325 -62.151006) (xy 57.482994 -62.8015)
				(xy 93.520006 -62.8015) (xy 95.1865 -61.135006) (xy 95.1865 -58.244994) (xy 93.4085 -56.466994)
				(xy 93.4085 -53.642006) (xy 93.901006 -53.1495) (xy 94.663006 -53.1495) (xy 96.4565 -51.356006)
				(xy 96.4565 -49.989994) (xy 95.8215 -49.354994) (xy 95.8215 -45.006006) (xy 96.441006 -44.3865)
				(xy 97.203006 -44.3865) (xy 97.711006 -43.8785) (xy 98.376994 -43.8785) (xy 99.011994 -44.5135)
				(xy 102.410006 -44.5135) (xy 102.8065 -44.117006) (xy 102.8065 -42.750994) (xy 102.4255 -42.369994)
				(xy 102.4255 -41.069006) (xy 102.791006 -40.7035) (xy 105.204006 -40.7035) (xy 105.950766 -39.956994)
				(xy 106.2355 -39.672006) (xy 106.2355 -38.305994) (xy 105.839006 -37.9095) (xy 102.918006 -37.9095)
				(xy 102.5525 -37.543994) (xy 102.5525 -37.289994) (xy 102.410006 -37.1475) (xy 102.029006 -37.1475)
				(xy 101.7905 -36.908994) (xy 101.013006 -36.1315) (xy 99.616006 -36.1315) (xy 99.108006 -35.6235)
				(xy 96.568006 -35.6235) (xy 95.9485 -35.003994) (xy 95.9485 -34.495994) (xy 94.663006 -33.2105)
			)
		)
		(polygon
			(pts
				(arc
					(start 81.0514 -60.7187)
					(mid 81.3943 -60.3758)
					(end 81.0514 -60.0329)
				)
				(arc
					(start 80.263746 -60.0329)
					(mid 79.9211 -60.375927)
					(end 80.264 -60.7187)
				)
			)
		)
		(polygon
			(pts
				(arc
					(start 84.348828 -59.595258)
					(mid 84.354625 -59.108766)
					(end 83.868006 -59.106054)
				)
				(arc
					(start 83.309968 -59.661806)
					(mid 83.308952 -60.146946)
					(end 83.794092 -60.147962)
				)
			)
		)
		(polygon
			(pts
				(arc
					(start 83.701636 -55.68061)
					(mid 83.668625 -55.193446)
					(end 83.18119 -55.226204)
				)
				(arc
					(start 82.803746 -55.65902)
					(mid 82.83702 -56.146446)
					(end 83.324446 -56.113172)
				)
			)
		)
		(polygon
			(pts
				(arc
					(start 91.580462 -55.242714)
					(mid 91.688158 -54.76621)
					(end 91.211654 -54.658514)
				)
				(xy 91.210384 -54.656482) (xy 90.73769 -54.954678) (xy 90.73769 -54.954932)
				(arc
					(start 90.73896 -54.956964)
					(mid 90.631264 -55.433468)
					(end 91.107768 -55.541164)
				)
				(xy 91.109038 -55.543196) (xy 91.581732 -55.244746)
			)
		)
		(polygon
			(pts
				(arc
					(start 86.030054 -54.801008)
					(mid 85.689948 -54.450234)
					(end 85.339174 -54.79034)
				)
				(arc
					(start 85.330538 -55.356506)
					(mid 85.670517 -55.707536)
					(end 86.021418 -55.367428)
				)
			)
		)
		(polygon
			(pts
				(arc
					(start 87.528908 -54.284118)
					(mid 87.190326 -53.93182)
					(end 86.838028 -54.270402)
				)
				(arc
					(start 86.826852 -54.834028)
					(mid 87.165307 -55.186583)
					(end 87.517732 -54.847998)
				)
			)
		)
		(polygon
			(pts
				(arc
					(start 80.9117 -54.1274)
					(mid 80.5688 -53.7845)
					(end 80.2259 -54.1274)
				)
				(arc
					(start 80.2259 -54.686454)
					(mid 80.568927 -55.0291)
					(end 80.9117 -54.6862)
				)
			)
		)
		(polygon
			(pts
				(arc
					(start 84.586572 -54.022498)
					(mid 84.247863 -53.670456)
					(end 83.895692 -54.009036)
				)
				(arc
					(start 83.885024 -54.567836)
					(mid 84.22386 -54.91988)
					(end 84.575904 -54.581044)
				)
			)
		)
		(polygon
			(pts
				(arc
					(start 90.156792 -53.552598)
					(mid 89.845768 -53.175928)
					(end 89.46896 -53.486812)
				)
				(arc
					(start 89.415874 -54.043326)
					(mid 89.727024 -54.420008)
					(end 90.103706 -54.108858)
				)
			)
		)
		(polygon
			(pts
				(arc
					(start 88.633808 -53.399182)
					(mid 88.277446 -53.065172)
					(end 87.943436 -53.421534)
				)
				(xy 87.940896 -53.421534) (xy 87.95893 -53.98008)
				(arc
					(start 87.96147 -53.98008)
					(mid 88.317832 -54.31409)
					(end 88.651842 -53.957728)
				)
				(xy 88.654382 -53.957728) (xy 88.636348 -53.399436) (xy 88.636094 -53.399182)
			)
		)
		(polygon
			(pts
				(arc
					(start 91.403424 -53.414168)
					(mid 91.076653 -53.050941)
					(end 90.71356 -53.377846)
				)
				(xy 90.71102 -53.377592) (xy 90.681556 -53.93817)
				(arc
					(start 90.684096 -53.938424)
					(mid 91.010994 -54.30139)
					(end 91.37396 -53.974492)
				)
				(xy 91.3765 -53.974746) (xy 91.405964 -53.414422) (xy 91.40571 -53.414168)
			)
		)
		(polygon
			(pts
				(arc
					(start 86.443058 -53.20792)
					(mid 86.103968 -52.85613)
					(end 85.752178 -53.19522)
				)
				(arc
					(start 85.741764 -53.758592)
					(mid 86.080727 -54.110638)
					(end 86.432644 -53.771546)
				)
			)
		)
		(polygon
			(pts
				(arc
					(start 82.0293 -53.0098)
					(mid 81.6864 -52.6669)
					(end 81.3435 -53.0098)
				)
				(arc
					(start 81.3435 -53.594254)
					(mid 81.686527 -53.9369)
					(end 82.0293 -53.594)
				)
			)
		)
	)
	(zone
		(net "P3V3")
		(layer "In5.Cu")
		(hatch none 0.5)
		(connect_pads
			(clearance 0.5)
		)
		(min_thickness 0.25)
		(fill yes
			(thermal_gap 0.5)
			(thermal_bridge_width 0.5)
			(island_removal_mode 0)
		)
		(polygon
			(pts
				(xy 30.939994 -38.4175) (xy 30.304994 -39.0525) (xy 26.621994 -39.0525) (xy 22.557994 -43.1165)
				(xy 20.779994 -43.1165) (xy 15.1765 -48.719994) (xy 15.1765 -49.705006) (xy 15.445994 -49.9745)
				(xy 19.098006 -49.9745) (xy 21.130006 -47.9425) (xy 23.670006 -47.9425) (xy 28.369006 -43.2435)
				(xy 32.179006 -43.2435) (xy 34.084006 -41.3385) (xy 37.162994 -41.3385) (xy 38.2905 -42.466006)
				(xy 38.2905 -44.752006) (xy 41.099994 -47.5615) (xy 47.673006 -47.5615) (xy 52.245006 -42.9895)
				(xy 53.769006 -42.9895) (xy 54.9275 -41.831006) (xy 54.9275 -39.829994) (xy 54.531006 -39.4335)
				(xy 53.926994 -39.4335) (xy 52.910994 -40.4495) (xy 48.719994 -40.4495) (xy 47.0535 -42.115994)
				(xy 47.0535 -44.020994) (xy 45.798994 -45.2755) (xy 43.736006 -45.2755) (xy 43.482006 -45.0215)
				(xy 42.085006 -45.0215) (xy 41.5925 -44.528994) (xy 41.5925 -40.337994) (xy 40.053006 -38.7985)
				(xy 38.783006 -38.7985) (xy 38.402006 -38.4175)
			)
		)
	)
	(zone
		(net "P12V")
		(layer "In5.Cu")
		(hatch none 0.5)
		(connect_pads
			(clearance 0.5)
		)
		(min_thickness 0.25)
		(fill yes
			(thermal_gap 0.5)
			(thermal_bridge_width 0.5)
			(island_removal_mode 0)
		)
		(polygon
			(pts
				(xy 6.0325 -23.797006) (xy 6.906006 -22.9235) (xy 8.460994 -22.9235) (xy 9.095994 -23.5585) (xy 15.923006 -23.5585)
				(xy 21.384006 -18.0975) (xy 61.389006 -18.0975) (xy 61.643006 -17.8435) (xy 72.087994 -17.8435)
				(xy 72.595994 -18.3515) (xy 80.469994 -18.3515) (xy 80.723994 -18.6055) (xy 83.741006 -18.6055)
				(xy 84.249006 -18.0975) (xy 86.662006 -18.0975) (xy 88.567006 -16.1925) (xy 92.788994 -16.1925)
				(xy 92.9005 -16.304006) (xy 93.726 -17.129506) (xy 97.3455 -13.510006) (xy 97.3455 -9.730994) (xy 96.949006 -9.3345)
				(xy 96.471994 -9.3345) (xy 95.5675 -10.238994) (xy 95.455994 -10.3505) (xy 94.185994 -10.3505) (xy 93.7895 -10.746994)
				(xy 93.7895 -12.016994) (xy 93.2815 -12.524994) (xy 93.169994 -12.6365) (xy 85.900006 -12.6365)
				(xy 84.630006 -11.3665) (xy 84.122006 -11.3665) (xy 83.868006 -11.1125) (xy 60.754006 -11.1125)
				(xy 60.246006 -10.6045)
				(arc
					(start 60.189618 -10.6045)
					(mid 60.368 -11.035888)
					(end 59.997594 -11.320018)
				)
				(arc
					(start 59.078114 -11.320018)
					(mid 58.707683 -11.035895)
					(end 58.88609 -10.6045)
				)
				(xy 57.990994 -10.6045) (xy 57.482994 -11.1125) (xy 17.320006 -11.1125) (xy 16.685006 -10.4775)
				(xy 15.463012 -10.4775)
				(arc
					(start 15.463012 -13.699998)
					(mid 14.946637 -14.946637)
					(end 13.699998 -15.463012)
				)
				(arc
					(start 0.999998 -15.463012)
					(mid 0.832426 -15.532422)
					(end 0.763016 -15.699994)
				)
				(xy 0.763016 -32.9565) (xy 5.509006 -32.9565) (xy 6.0325 -32.433006)
			)
		)
		(polygon
			(pts
				(arc
					(start 21.053044 -15.872206)
					(mid 21.43633 -15.488539)
					(end 21.05279 -15.105126)
				)
				(arc
					(start 20.09521 -15.105126)
					(mid 19.71167 -15.488666)
					(end 20.09521 -15.872206)
				)
			)
		)
		(polygon
			(pts
				(arc
					(start 64.389 -15.0876)
					(mid 64.77 -14.7066)
					(end 64.389 -14.3256)
				)
				(arc
					(start 63.626746 -14.3256)
					(mid 63.246 -14.706727)
					(end 63.627 -15.0876)
				)
			)
		)
		(polygon
			(pts
				(arc
					(start 73.7108 -15.09014)
					(mid 74.09434 -14.7066)
					(end 73.7108 -14.32306)
				)
				(arc
					(start 72.846946 -14.32306)
					(mid 72.46366 -14.706727)
					(end 72.8472 -15.09014)
				)
			)
		)
		(polygon
			(pts
				(arc
					(start 66.548254 -15.0622)
					(mid 66.929 -14.681073)
					(end 66.548 -14.3002)
				)
				(arc
					(start 65.786 -14.3002)
					(mid 65.405 -14.6812)
					(end 65.786 -15.0622)
				)
			)
		)
		(polygon
			(pts
				(arc
					(start 68.834 -14.98854)
					(mid 69.21754 -14.605)
					(end 68.834 -14.22146)
				)
				(arc
					(start 68.071746 -14.22146)
					(mid 67.68846 -14.605127)
					(end 68.072 -14.98854)
				)
			)
		)
		(polygon
			(pts
				(arc
					(start 81.077054 -14.96314)
					(mid 81.46034 -14.579473)
					(end 81.0768 -14.19606)
				)
				(arc
					(start 80.2132 -14.19606)
					(mid 79.82966 -14.5796)
					(end 80.2132 -14.96314)
				)
			)
		)
		(polygon
			(pts
				(arc
					(start 78.2828 -14.96314)
					(mid 78.66634 -14.5796)
					(end 78.2828 -14.19606)
				)
				(arc
					(start 77.418946 -14.19606)
					(mid 77.03566 -14.579727)
					(end 77.4192 -14.96314)
				)
			)
		)
		(polygon
			(pts
				(arc
					(start 34.290254 -14.96314)
					(mid 34.67354 -14.579473)
					(end 34.29 -14.19606)
				)
				(arc
					(start 33.4264 -14.19606)
					(mid 33.04286 -14.5796)
					(end 33.4264 -14.96314)
				)
			)
		)
		(polygon
			(pts
				(arc
					(start 30.277054 -14.96314)
					(mid 30.66034 -14.579473)
					(end 30.2768 -14.19606)
				)
				(arc
					(start 29.4132 -14.19606)
					(mid 29.02966 -14.5796)
					(end 29.4132 -14.96314)
				)
			)
		)
		(polygon
			(pts
				(arc
					(start 83.1596 -14.32814)
					(mid 83.54314 -13.9446)
					(end 83.1596 -13.56106)
				)
				(arc
					(start 82.295746 -13.56106)
					(mid 81.91246 -13.944727)
					(end 82.296 -14.32814)
				)
			)
		)
		(polygon
			(pts
				(arc
					(start 53.010054 -14.32814)
					(mid 53.39334 -13.944473)
					(end 53.0098 -13.56106)
				)
				(arc
					(start 52.1462 -13.56106)
					(mid 51.76266 -13.9446)
					(end 52.1462 -14.32814)
				)
			)
		)
		(polygon
			(pts
				(arc
					(start 50.2158 -14.1986)
					(mid 50.5968 -13.8176)
					(end 50.2158 -13.4366)
				)
				(arc
					(start 49.453546 -13.4366)
					(mid 49.0728 -13.817727)
					(end 49.4538 -14.1986)
				)
			)
		)
		(polygon
			(pts
				(arc
					(start 46.177454 -14.1986)
					(mid 46.5582 -13.817473)
					(end 46.1772 -13.4366)
				)
				(arc
					(start 45.466 -13.4366)
					(mid 45.085 -13.8176)
					(end 45.466 -14.1986)
				)
			)
		)
		(polygon
			(pts
				(arc
					(start 42.281856 -14.20114)
					(mid 42.665142 -13.817473)
					(end 42.281602 -13.43406)
				)
				(arc
					(start 41.418002 -13.43406)
					(mid 41.034462 -13.8176)
					(end 41.418002 -14.20114)
				)
			)
		)
		(polygon
			(pts
				(arc
					(start 38.281864 -14.20114)
					(mid 38.66515 -13.817473)
					(end 38.28161 -13.43406)
				)
				(arc
					(start 37.41801 -13.43406)
					(mid 37.03447 -13.8176)
					(end 37.41801 -14.20114)
				)
			)
		)
		(polygon
			(pts
				(arc
					(start 26.276554 -14.20114)
					(mid 26.65984 -13.817473)
					(end 26.2763 -13.43406)
				)
				(arc
					(start 25.4127 -13.43406)
					(mid 25.02916 -13.8176)
					(end 25.4127 -14.20114)
				)
			)
		)
		(polygon
			(pts
				(arc
					(start 22.5298 -14.20114)
					(mid 22.91334 -13.8176)
					(end 22.5298 -13.43406)
				)
				(arc
					(start 21.665946 -13.43406)
					(mid 21.28266 -13.817727)
					(end 21.6662 -14.20114)
				)
			)
		)
		(polygon
			(pts
				(arc
					(start 48.184054 -14.1732)
					(mid 48.5648 -13.792073)
					(end 48.1838 -13.4112)
				)
				(arc
					(start 47.46371 -13.4112)
					(mid 47.08271 -13.7922)
					(end 47.46371 -14.1732)
				)
			)
		)
		(polygon
			(pts
				(arc
					(start 44.211494 -12.98194)
					(mid 44.59478 -12.598273)
					(end 44.21124 -12.21486)
				)
				(arc
					(start 43.25366 -12.21486)
					(mid 42.87012 -12.5984)
					(end 43.25366 -12.98194)
				)
			)
		)
		(polygon
			(pts
				(arc
					(start 40.40124 -12.73048)
					(mid 40.78478 -12.34694)
					(end 40.40124 -11.9634)
				)
				(arc
					(start 39.443406 -11.9634)
					(mid 39.06012 -12.347067)
					(end 39.44366 -12.73048)
				)
			)
		)
	)
	(zone
		(net "P1V0")
		(layer "In6.Cu")
		(hatch none 0.5)
		(connect_pads
			(clearance 0.5)
		)
		(min_thickness 0.25)
		(fill yes
			(thermal_gap 0.5)
			(thermal_bridge_width 0.5)
			(island_removal_mode 0)
		)
		(polygon
			(pts
				(xy 85.930994 -15.5575) (xy 85.2805 -16.207994) (xy 85.2805 -21.130006) (xy 86.8045 -22.654006)
				(xy 86.8045 -24.970994) (xy 86.0425 -25.732994) (xy 86.0425 -26.210006) (xy 88.8365 -29.004006)
				(xy 88.8365 -30.401006) (xy 89.3445 -30.909006) (xy 89.3445 -32.717994) (xy 88.8365 -33.225994)
				(xy 88.8365 -34.338006) (xy 91.1225 -36.624006) (xy 91.1225 -38.529006) (xy 91.8845 -39.291006)
				(xy 91.8845 -45.006006) (xy 93.296994 -46.4185) (xy 96.949006 -46.4185) (xy 97.965006 -45.4025)
				(xy 98.018854 -45.4025) (xy 98.742754 -44.6786) (xy 101.7016 -44.6786) (xy 101.7016 -43.497246)
				(xy 101.536754 -43.3324) (xy 99.631754 -43.3324) (xy 99.2886 -42.989246) (xy 99.2886 -37.020754)
				(xy 99.631754 -36.6776) (xy 101.663754 -36.6776) (xy 101.717348 -36.624006) (xy 102.5906 -35.750754)
				(xy 102.5906 -33.8074) (xy 100.520754 -33.8074) (xy 99.4156 -32.702246) (xy 99.4156 -32.321246)
				(xy 99.250754 -32.1564) (xy 98.615246 -32.1564) (xy 98.361246 -32.4104) (xy 97.599754 -32.4104)
				(xy 97.2566 -32.067246) (xy 97.2566 -28.3845) (xy 91.869006 -28.3845) (xy 88.9635 -25.478994) (xy 88.9635 -21.384006)
				(xy 92.5195 -17.828006) (xy 92.5195 -16.461994) (xy 91.615006 -15.5575)
			)
		)
	)
	(zone
		(net "PV_VDDR")
		(layer "In6.Cu")
		(hatch none 0.5)
		(connect_pads
			(clearance 0.5)
		)
		(min_thickness 0.25)
		(fill yes
			(thermal_gap 0.5)
			(thermal_bridge_width 0.5)
			(island_removal_mode 0)
		)
		(polygon
			(pts
				(xy 152.097994 -2.7305) (xy 144.858994 -9.9695) (xy 135.460994 -9.9695) (xy 131.5085 -13.921994)
				(xy 131.396994 -14.0335) (xy 114.251994 -14.0335) (xy 108.409994 -19.8755) (xy 100.79355 -19.8755)
				(xy 98.9584 -21.833078) (xy 98.9584 -24.574246) (xy 97.5614 -25.971246) (xy 97.5614 -28.076906)
				(xy 97.5995 -28.115006) (xy 97.5995 -28.272994) (xy 97.5614 -28.311094) (xy 97.5614 -31.940754)
				(xy 97.726246 -32.1056) (xy 98.234754 -32.1056) (xy 98.488754 -31.8516) (xy 99.377246 -31.8516)
				(xy 99.7204 -32.194754) (xy 99.7204 -32.575754) (xy 100.647246 -33.5026) (xy 104.076246 -33.5026)
				(xy 104.1654 -33.591754) (xy 104.330246 -33.7566) (xy 110.934754 -33.7566) (xy 111.569754 -33.1216)
				(xy 112.077754 -33.1216) (xy 114.363754 -30.8356) (xy 117.738906 -30.8356) (xy 118.920006 -29.6545)
				(xy 161.338006 -29.6545) (xy 166.418514 -24.574246) (xy 168.704006 -22.2885) (xy 187.754006 -22.2885)
				(xy 195.7705 -14.272006) (xy 195.7705 -5.4102) (xy 193.212466 -2.7305)
			)
		)
	)
	(zone
		(net "PV_VDDR")
		(layer "In6.Cu")
		(hatch none 0.5)
		(connect_pads
			(clearance 0.5)
		)
		(min_thickness 0.25)
		(fill yes
			(thermal_gap 0.5)
			(thermal_bridge_width 0.5)
			(island_removal_mode 0)
		)
		(polygon
			(pts
				(xy 98.869246 -44.9834) (xy 98.2345 -45.618146) (xy 98.2345 -45.671994) (xy 98.1964 -45.710094)
				(xy 98.1964 -50.101754) (xy 98.5774 -50.482754) (xy 98.5774 -57.032906) (xy 102.694994 -61.1505)
				(xy 135.460994 -61.1505) (xy 137.3505 -63.040006) (xy 137.3505 -64.691006) (xy 142.572994 -69.9135)
				(xy 166.418006 -69.9135) (xy 168.4655 -67.866006) (xy 168.4655 -65.102994) (xy 166.402766 -63.040006)
				(xy 166.1795 -62.816994) (xy 166.1795 -60.276994) (xy 156.385514 -50.482754) (xy 151.432006 -45.5295)
				(xy 121.236994 -45.5295) (xy 120.855994 -45.9105) (xy 120.698006 -45.9105) (xy 120.659906 -45.8724)
				(xy 118.173754 -45.8724) (xy 117.919754 -45.6184) (xy 109.029754 -45.6184) (xy 108.521754 -45.1104)
				(xy 107.466638 -45.1104) (xy 107.430316 -45.122592) (xy 107.405932 -45.1104) (xy 107.378754 -45.1104)
				(xy 107.35183 -45.083222) (xy 107.151932 -44.9834)
			)
		)
	)
	(zone
		(net "GND")
		(layer "In6.Cu")
		(hatch none 0.5)
		(connect_pads
			(clearance 0.5)
		)
		(min_thickness 0.25)
		(fill yes
			(thermal_gap 0.5)
			(thermal_bridge_width 0.5)
			(island_removal_mode 0)
		)
		(polygon
			(pts
				(arc
					(start 106.000042 -0.763016)
					(mid 105.83247 -0.832426)
					(end 105.76306 -0.999998)
				)
				(arc
					(start 105.76306 -10.700004)
					(mid 105.246685 -11.946643)
					(end 104.000046 -12.463018)
				)
				(arc
					(start 100.000054 -12.463018)
					(mid 98.753415 -11.946643)
					(end 98.23704 -10.700004)
				)
				(xy 98.23704 -5.244592) (xy 97.448624 -5.244592) (xy 88.562942 -5.244592)
				(arc
					(start 88.562942 -10.150094)
					(mid 86.849966 -11.86307)
					(end 85.13699 -10.150094)
				)
				(xy 85.13699 -5.244592) (xy 15.463012 -5.244592)
				(arc
					(start 15.463012 -13.699998)
					(mid 14.946637 -14.946637)
					(end 13.699998 -15.463012)
				)
				(arc
					(start 0.999998 -15.463012)
					(mid 0.832426 -15.532422)
					(end 0.763016 -15.699994)
				)
				(arc
					(start 0.763016 -72.799956)
					(mid 0.832426 -72.967528)
					(end 0.999998 -73.036938)
				)
				(arc
					(start 209.00009 -73.036938)
					(mid 209.167662 -72.967528)
					(end 209.237072 -72.799956)
				)
				(arc
					(start 209.237072 -0.999998)
					(mid 209.167662 -0.832426)
					(end 209.00009 -0.763016)
				)
			)
		)
		(polygon
			(pts
				(arc
					(start 2.31394 -66.220848)
					(mid 1.930273 -65.837562)
					(end 1.54686 -66.221102)
				)
				(arc
					(start 1.54686 -67.178682)
					(mid 1.9304 -67.562222)
					(end 2.31394 -67.178682)
				)
			)
		)
		(polygon
			(pts
				(arc
					(start 3.8354 -64.7065)
					(mid 3.451733 -64.323214)
					(end 3.06832 -64.706754)
				)
				(arc
					(start 3.06832 -65.664334)
					(mid 3.45186 -66.047874)
					(end 3.8354 -65.664334)
				)
			)
		)
		(polygon
			(pts
				(arc
					(start 10.01014 -64.515746)
					(mid 9.626473 -64.13246)
					(end 9.24306 -64.516)
				)
				(arc
					(start 9.24306 -65.405)
					(mid 9.6266 -65.78854)
					(end 10.01014 -65.405)
				)
			)
		)
		(polygon
			(pts
				(arc
					(start 2.31394 -63.221108)
					(mid 1.9304 -62.837568)
					(end 1.54686 -63.221108)
				)
				(arc
					(start 1.54686 -64.178942)
					(mid 1.930527 -64.562228)
					(end 2.31394 -64.178688)
				)
			)
		)
		(polygon
			(pts
				(arc
					(start 10.009886 -62.727078)
					(mid 9.615678 -62.354714)
					(end 9.243314 -62.748922)
				)
				(xy 9.240774 -62.748922) (xy 9.266174 -63.637668) (xy 9.266428 -63.637922)
				(arc
					(start 9.268714 -63.637922)
					(mid 9.662922 -64.010286)
					(end 10.035286 -63.616078)
				)
				(xy 10.037826 -63.616078) (xy 10.012426 -62.727078)
			)
		)
		(polygon
			(pts
				(arc
					(start 101.734366 -61.66993)
					(mid 101.189299 -61.660676)
					(end 101.185472 -62.20587)
				)
				(arc
					(start 101.795072 -62.817756)
					(mid 102.337616 -62.818772)
					(end 102.338632 -62.276228)
				)
			)
		)
		(polygon
			(pts
				(arc
					(start 3.8354 -61.706506)
					(mid 3.451733 -61.32322)
					(end 3.06832 -61.70676)
				)
				(arc
					(start 3.06832 -62.66434)
					(mid 3.45186 -63.04788)
					(end 3.8354 -62.66434)
				)
			)
		)
		(polygon
			(pts
				(arc
					(start 10.01014 -60.959746)
					(mid 9.626473 -60.57646)
					(end 9.24306 -60.96)
				)
				(arc
					(start 9.24306 -61.849)
					(mid 9.6266 -62.23254)
					(end 10.01014 -61.849)
				)
			)
		)
		(polygon
			(pts
				(arc
					(start 99.781106 -60.369704)
					(mid 99.238816 -60.378086)
					(end 99.247198 -60.920376)
				)
				(xy 99.24542 -60.922154) (xy 99.86518 -61.523372) (xy 99.865434 -61.523372)
				(arc
					(start 99.866958 -61.521848)
					(mid 100.409565 -61.513655)
					(end 100.40112 -60.971176)
				)
				(xy 100.402898 -60.969398) (xy 99.782884 -60.367926)
			)
		)
		(polygon
			(pts
				(arc
					(start 81.0514 -60.7187)
					(mid 81.3943 -60.3758)
					(end 81.0514 -60.0329)
				)
				(arc
					(start 80.263746 -60.0329)
					(mid 79.9211 -60.375927)
					(end 80.264 -60.7187)
				)
			)
		)
		(polygon
			(pts
				(arc
					(start 2.31394 -60.22086)
					(mid 1.930273 -59.837574)
					(end 1.54686 -60.221114)
				)
				(arc
					(start 1.54686 -61.178694)
					(mid 1.9304 -61.562234)
					(end 2.31394 -61.178694)
				)
			)
		)
		(polygon
			(pts
				(arc
					(start 84.348828 -59.595258)
					(mid 84.354625 -59.108766)
					(end 83.868006 -59.106054)
				)
				(arc
					(start 83.309968 -59.661806)
					(mid 83.308952 -60.146946)
					(end 83.794092 -60.147962)
				)
			)
		)
		(polygon
			(pts
				(arc
					(start 10.009886 -59.171078)
					(mid 9.615678 -58.798714)
					(end 9.243314 -59.192922)
				)
				(xy 9.240774 -59.192922) (xy 9.266174 -60.081668) (xy 9.266428 -60.081922)
				(arc
					(start 9.268714 -60.081922)
					(mid 9.662922 -60.454286)
					(end 10.035286 -60.060078)
				)
				(xy 10.037826 -60.060078) (xy 10.012426 -59.171078)
			)
		)
		(polygon
			(pts
				(arc
					(start 3.7084 -58.706766)
					(mid 3.32486 -58.323226)
					(end 2.94132 -58.706766)
				)
				(arc
					(start 2.94132 -59.6646)
					(mid 3.324987 -60.047886)
					(end 3.7084 -59.664346)
				)
			)
		)
		(polygon
			(pts
				(arc
					(start 10.01014 -57.403746)
					(mid 9.626473 -57.02046)
					(end 9.24306 -57.404)
				)
				(arc
					(start 9.24306 -58.293)
					(mid 9.6266 -58.67654)
					(end 10.01014 -58.293)
				)
			)
		)
		(polygon
			(pts
				(arc
					(start 10.01014 -55.625746)
					(mid 9.626473 -55.24246)
					(end 9.24306 -55.626)
				)
				(arc
					(start 9.24306 -56.515)
					(mid 9.6266 -56.89854)
					(end 10.01014 -56.515)
				)
			)
		)
		(polygon
			(pts
				(arc
					(start 83.701636 -55.68061)
					(mid 83.668625 -55.193446)
					(end 83.18119 -55.226204)
				)
				(arc
					(start 82.803746 -55.65902)
					(mid 82.83702 -56.146446)
					(end 83.324446 -56.113172)
				)
			)
		)
		(polygon
			(pts
				(arc
					(start 91.580462 -55.242714)
					(mid 91.688158 -54.76621)
					(end 91.211654 -54.658514)
				)
				(xy 91.210384 -54.656482) (xy 90.73769 -54.954678) (xy 90.73769 -54.954932)
				(arc
					(start 90.73896 -54.956964)
					(mid 90.631264 -55.433468)
					(end 91.107768 -55.541164)
				)
				(xy 91.109038 -55.543196) (xy 91.581732 -55.244746)
			)
		)
		(polygon
			(pts
				(arc
					(start 86.030054 -54.801008)
					(mid 85.689948 -54.450234)
					(end 85.339174 -54.79034)
				)
				(arc
					(start 85.330538 -55.356506)
					(mid 85.670517 -55.707536)
					(end 86.021418 -55.367428)
				)
			)
		)
		(polygon
			(pts
				(arc
					(start 87.528908 -54.284118)
					(mid 87.190326 -53.93182)
					(end 86.838028 -54.270402)
				)
				(arc
					(start 86.826852 -54.834028)
					(mid 87.165307 -55.186583)
					(end 87.517732 -54.847998)
				)
			)
		)
		(polygon
			(pts
				(arc
					(start 80.9117 -54.1274)
					(mid 80.5688 -53.7845)
					(end 80.2259 -54.1274)
				)
				(arc
					(start 80.2259 -54.686454)
					(mid 80.568927 -55.0291)
					(end 80.9117 -54.6862)
				)
			)
		)
		(polygon
			(pts
				(arc
					(start 84.586572 -54.022498)
					(mid 84.247863 -53.670456)
					(end 83.895692 -54.009036)
				)
				(arc
					(start 83.885024 -54.567836)
					(mid 84.22386 -54.91988)
					(end 84.575904 -54.581044)
				)
			)
		)
		(polygon
			(pts
				(arc
					(start 10.2616 -53.66766)
					(mid 10.2616 -54.38394)
					(end 10.2616 -53.66766)
				)
			)
		)
		(polygon
			(pts
				(arc
					(start 90.156792 -53.552598)
					(mid 89.845768 -53.175928)
					(end 89.46896 -53.486812)
				)
				(arc
					(start 89.415874 -54.043326)
					(mid 89.727024 -54.420008)
					(end 90.103706 -54.108858)
				)
			)
		)
		(polygon
			(pts
				(arc
					(start 88.633808 -53.399182)
					(mid 88.277446 -53.065172)
					(end 87.943436 -53.421534)
				)
				(xy 87.940896 -53.421534) (xy 87.95893 -53.98008)
				(arc
					(start 87.96147 -53.98008)
					(mid 88.317832 -54.31409)
					(end 88.651842 -53.957728)
				)
				(xy 88.654382 -53.957728) (xy 88.636348 -53.399436) (xy 88.636094 -53.399182)
			)
		)
		(polygon
			(pts
				(arc
					(start 91.403424 -53.414168)
					(mid 91.076653 -53.050941)
					(end 90.71356 -53.377846)
				)
				(xy 90.71102 -53.377592) (xy 90.681556 -53.93817)
				(arc
					(start 90.684096 -53.938424)
					(mid 91.010994 -54.30139)
					(end 91.37396 -53.974492)
				)
				(xy 91.3765 -53.974746) (xy 91.405964 -53.414422) (xy 91.40571 -53.414168)
			)
		)
		(polygon
			(pts
				(arc
					(start 86.443058 -53.20792)
					(mid 86.103968 -52.85613)
					(end 85.752178 -53.19522)
				)
				(arc
					(start 85.741764 -53.758592)
					(mid 86.080727 -54.110638)
					(end 86.432644 -53.771546)
				)
			)
		)
		(polygon
			(pts
				(arc
					(start 82.0293 -53.0098)
					(mid 81.6864 -52.6669)
					(end 81.3435 -53.0098)
				)
				(arc
					(start 81.3435 -53.594254)
					(mid 81.686527 -53.9369)
					(end 82.0293 -53.594)
				)
			)
		)
		(polygon
			(pts
				(arc
					(start 9.2202 -52.907946)
					(mid 8.839073 -52.5272)
					(end 8.4582 -52.9082)
				)
				(arc
					(start 8.4582 -53.8988)
					(mid 8.8392 -54.2798)
					(end 9.2202 -53.8988)
				)
			)
		)
		(polygon
			(pts
				(arc
					(start 10.2616 -52.42306)
					(mid 10.2616 -53.13934)
					(end 10.2616 -52.42306)
				)
			)
		)
		(polygon
			(pts
				(arc
					(start 9.5504 -51.38166)
					(mid 9.5504 -52.09794)
					(end 9.5504 -51.38166)
				)
			)
		)
		(polygon
			(pts
				(arc
					(start 8.509 -50.621946)
					(mid 8.127873 -50.2412)
					(end 7.747 -50.6222)
				)
				(arc
					(start 7.747 -51.6128)
					(mid 8.128 -51.9938)
					(end 8.509 -51.6128)
				)
			)
		)
		(polygon
			(pts
				(arc
					(start 9.5504 -50.13706)
					(mid 9.5504 -50.85334)
					(end 9.5504 -50.13706)
				)
			)
		)
		(polygon
			(pts
				(arc
					(start 13.55598 -47.66056)
					(mid 13.17244 -47.27702)
					(end 12.7889 -47.66056)
				)
				(arc
					(start 12.7889 -48.618394)
					(mid 13.172567 -49.00168)
					(end 13.55598 -48.61814)
				)
			)
		)
		(polygon
			(pts
				(arc
					(start 51.041554 -47.64278)
					(mid 50.663729 -47.253654)
					(end 50.274474 -47.63135)
				)
				(arc
					(start 50.262028 -48.49495)
					(mid 50.63998 -48.884078)
					(end 51.029108 -48.506126)
				)
			)
		)
		(polygon
			(pts
				(arc
					(start 15.082266 -47.21606)
					(mid 15.465806 -46.83252)
					(end 15.082266 -46.44898)
				)
				(arc
					(start 14.152626 -46.44898)
					(mid 13.76934 -46.832647)
					(end 14.15288 -47.21606)
				)
			)
		)
		(polygon
			(pts
				(arc
					(start 61.317378 -45.848016)
					(mid 60.910088 -45.489868)
					(end 60.551822 -45.897038)
				)
				(arc
					(start 60.607448 -46.75886)
					(mid 61.014864 -47.117)
					(end 61.373004 -46.709584)
				)
			)
		)
		(polygon
			(pts
				(arc
					(start 43.41114 -44.5389)
					(mid 43.79468 -44.15536)
					(end 43.41114 -43.77182)
				)
				(arc
					(start 42.453306 -43.77182)
					(mid 42.07002 -44.155487)
					(end 42.45356 -44.5389)
				)
			)
		)
		(polygon
			(pts
				(xy 8.543798 -43.688) (xy 5.114798 -43.688) (xy 5.114798 -49.276) (xy 8.543798 -49.276)
			)
		)
		(polygon
			(pts
				(arc
					(start 45.007276 -43.53306)
					(mid 44.615103 -43.907837)
					(end 44.98975 -44.30014)
				)
				(arc
					(start 45.947838 -44.32173)
					(mid 46.340014 -43.946826)
					(end 45.96511 -43.55465)
				)
			)
		)
		(polygon
			(pts
				(arc
					(start 49.692052 -37.74567)
					(mid 49.15027 -37.771832)
					(end 49.176432 -38.313614)
				)
				(arc
					(start 49.81321 -38.892226)
					(mid 50.356403 -38.869633)
					(end 50.33137 -38.326568)
				)
			)
		)
		(polygon
			(pts
				(arc
					(start 60.04179 -35.379406)
					(mid 59.658123 -34.99612)
					(end 59.27471 -35.37966)
				)
				(arc
					(start 59.27471 -36.33724)
					(mid 59.65825 -36.72078)
					(end 60.04179 -36.33724)
				)
			)
		)
		(polygon
			(pts
				(arc
					(start 53.479954 -35.696652)
					(mid 53.862478 -35.311969)
					(end 53.477668 -34.929572)
				)
				(arc
					(start 52.52339 -34.93262)
					(mid 52.14112 -35.31743)
					(end 52.52593 -35.6997)
				)
			)
		)
		(polygon
			(pts
				(arc
					(start 52.16652 -34.47034)
					(mid 52.55006 -34.0868)
					(end 52.16652 -33.70326)
				)
				(arc
					(start 51.282092 -33.70326)
					(mid 50.898806 -34.086927)
					(end 51.282346 -34.47034)
				)
			)
		)
		(polygon
			(pts
				(arc
					(start 78.12024 -30.823154)
					(mid 77.762614 -31.150687)
					(end 78.090014 -31.508446)
				)
				(arc
					(start 78.648814 -31.53283)
					(mid 79.006446 -31.20517)
					(end 78.678786 -30.847538)
				)
			)
		)
		(polygon
			(pts
				(arc
					(start 78.538832 -30.2387)
					(mid 78.878175 -29.892117)
					(end 78.531466 -29.5529)
				)
				(arc
					(start 77.972666 -29.55925)
					(mid 77.633576 -29.90596)
					(end 77.980286 -30.24505)
				)
			)
		)
		(polygon
			(pts
				(arc
					(start 38.65372 -29.336746)
					(mid 38.270053 -28.95346)
					(end 37.88664 -29.337)
				)
				(arc
					(start 37.88664 -30.2006)
					(mid 38.27018 -30.58414)
					(end 38.65372 -30.2006)
				)
			)
		)
		(polygon
			(pts
				(arc
					(start 53.535326 -28.897834)
					(mid 53.151786 -28.514294)
					(end 52.768246 -28.897834)
				)
				(arc
					(start 52.768246 -29.827474)
					(mid 53.151913 -30.21076)
					(end 53.535326 -29.82722)
				)
			)
		)
		(polygon
			(pts
				(arc
					(start 69.52234 -27.52344)
					(mid 69.140705 -27.138123)
					(end 68.75526 -27.51963)
				)
				(arc
					(start 68.75145 -28.403296)
					(mid 69.133212 -28.788614)
					(end 69.51853 -28.406852)
				)
			)
		)
		(polygon
			(pts
				(arc
					(start 50.25263 -20.79498)
					(mid 50.63617 -20.41144)
					(end 50.25263 -20.0279)
				)
				(arc
					(start 49.294796 -20.0279)
					(mid 48.91151 -20.411567)
					(end 49.29505 -20.79498)
				)
			)
		)
		(polygon
			(pts
				(arc
					(start 21.053044 -15.872206)
					(mid 21.43633 -15.488539)
					(end 21.05279 -15.105126)
				)
				(arc
					(start 20.09521 -15.105126)
					(mid 19.71167 -15.488666)
					(end 20.09521 -15.872206)
				)
			)
		)
		(polygon
			(pts
				(arc
					(start 64.389 -15.0876)
					(mid 64.77 -14.7066)
					(end 64.389 -14.3256)
				)
				(arc
					(start 63.626746 -14.3256)
					(mid 63.246 -14.706727)
					(end 63.627 -15.0876)
				)
			)
		)
		(polygon
			(pts
				(arc
					(start 73.7108 -15.09014)
					(mid 74.09434 -14.7066)
					(end 73.7108 -14.32306)
				)
				(arc
					(start 72.846946 -14.32306)
					(mid 72.46366 -14.706727)
					(end 72.8472 -15.09014)
				)
			)
		)
		(polygon
			(pts
				(arc
					(start 66.548254 -15.0622)
					(mid 66.929 -14.681073)
					(end 66.548 -14.3002)
				)
				(arc
					(start 65.786 -14.3002)
					(mid 65.405 -14.6812)
					(end 65.786 -15.0622)
				)
			)
		)
		(polygon
			(pts
				(arc
					(start 68.834 -14.98854)
					(mid 69.21754 -14.605)
					(end 68.834 -14.22146)
				)
				(arc
					(start 68.071746 -14.22146)
					(mid 67.68846 -14.605127)
					(end 68.072 -14.98854)
				)
			)
		)
		(polygon
			(pts
				(arc
					(start 81.077054 -14.96314)
					(mid 81.46034 -14.579473)
					(end 81.0768 -14.19606)
				)
				(arc
					(start 80.2132 -14.19606)
					(mid 79.82966 -14.5796)
					(end 80.2132 -14.96314)
				)
			)
		)
		(polygon
			(pts
				(arc
					(start 78.2828 -14.96314)
					(mid 78.66634 -14.5796)
					(end 78.2828 -14.19606)
				)
				(arc
					(start 77.418946 -14.19606)
					(mid 77.03566 -14.579727)
					(end 77.4192 -14.96314)
				)
			)
		)
		(polygon
			(pts
				(arc
					(start 34.290254 -14.96314)
					(mid 34.67354 -14.579473)
					(end 34.29 -14.19606)
				)
				(arc
					(start 33.4264 -14.19606)
					(mid 33.04286 -14.5796)
					(end 33.4264 -14.96314)
				)
			)
		)
		(polygon
			(pts
				(arc
					(start 30.277054 -14.96314)
					(mid 30.66034 -14.579473)
					(end 30.2768 -14.19606)
				)
				(arc
					(start 29.4132 -14.19606)
					(mid 29.02966 -14.5796)
					(end 29.4132 -14.96314)
				)
			)
		)
		(polygon
			(pts
				(arc
					(start 83.1596 -14.32814)
					(mid 83.54314 -13.9446)
					(end 83.1596 -13.56106)
				)
				(arc
					(start 82.295746 -13.56106)
					(mid 81.91246 -13.944727)
					(end 82.296 -14.32814)
				)
			)
		)
		(polygon
			(pts
				(arc
					(start 53.010054 -14.32814)
					(mid 53.39334 -13.944473)
					(end 53.0098 -13.56106)
				)
				(arc
					(start 52.1462 -13.56106)
					(mid 51.76266 -13.9446)
					(end 52.1462 -14.32814)
				)
			)
		)
		(polygon
			(pts
				(arc
					(start 50.2158 -14.1986)
					(mid 50.5968 -13.8176)
					(end 50.2158 -13.4366)
				)
				(arc
					(start 49.453546 -13.4366)
					(mid 49.0728 -13.817727)
					(end 49.4538 -14.1986)
				)
			)
		)
		(polygon
			(pts
				(arc
					(start 46.177454 -14.1986)
					(mid 46.5582 -13.817473)
					(end 46.1772 -13.4366)
				)
				(arc
					(start 45.466 -13.4366)
					(mid 45.085 -13.8176)
					(end 45.466 -14.1986)
				)
			)
		)
		(polygon
			(pts
				(arc
					(start 42.281856 -14.20114)
					(mid 42.665142 -13.817473)
					(end 42.281602 -13.43406)
				)
				(arc
					(start 41.418002 -13.43406)
					(mid 41.034462 -13.8176)
					(end 41.418002 -14.20114)
				)
			)
		)
		(polygon
			(pts
				(arc
					(start 38.281864 -14.20114)
					(mid 38.66515 -13.817473)
					(end 38.28161 -13.43406)
				)
				(arc
					(start 37.41801 -13.43406)
					(mid 37.03447 -13.8176)
					(end 37.41801 -14.20114)
				)
			)
		)
		(polygon
			(pts
				(arc
					(start 26.276554 -14.20114)
					(mid 26.65984 -13.817473)
					(end 26.2763 -13.43406)
				)
				(arc
					(start 25.4127 -13.43406)
					(mid 25.02916 -13.8176)
					(end 25.4127 -14.20114)
				)
			)
		)
		(polygon
			(pts
				(arc
					(start 22.5298 -14.20114)
					(mid 22.91334 -13.8176)
					(end 22.5298 -13.43406)
				)
				(arc
					(start 21.665946 -13.43406)
					(mid 21.28266 -13.817727)
					(end 21.6662 -14.20114)
				)
			)
		)
		(polygon
			(pts
				(arc
					(start 48.184054 -14.1732)
					(mid 48.5648 -13.792073)
					(end 48.1838 -13.4112)
				)
				(arc
					(start 47.46371 -13.4112)
					(mid 47.08271 -13.7922)
					(end 47.46371 -14.1732)
				)
			)
		)
		(polygon
			(pts
				(arc
					(start 44.211494 -12.98194)
					(mid 44.59478 -12.598273)
					(end 44.21124 -12.21486)
				)
				(arc
					(start 43.25366 -12.21486)
					(mid 42.87012 -12.5984)
					(end 43.25366 -12.98194)
				)
			)
		)
		(polygon
			(pts
				(arc
					(start 40.40124 -12.73048)
					(mid 40.78478 -12.34694)
					(end 40.40124 -11.9634)
				)
				(arc
					(start 39.443406 -11.9634)
					(mid 39.06012 -12.347067)
					(end 39.44366 -12.73048)
				)
			)
		)
		(polygon
			(pts
				(arc
					(start 59.997594 -11.320018)
					(mid 60.381134 -10.936478)
					(end 59.997594 -10.552938)
				)
				(arc
					(start 59.07786 -10.552938)
					(mid 58.694574 -10.936605)
					(end 59.078114 -11.320018)
				)
			)
		)
		(polygon
			(pts
				(arc
					(start 84.310474 -10.79627)
					(mid 84.694014 -10.41273)
					(end 84.310474 -10.02919)
				)
				(arc
					(start 83.388708 -10.02919)
					(mid 83.005422 -10.412857)
					(end 83.388962 -10.79627)
				)
			)
		)
		(polygon
			(pts
				(arc
					(start 80.328516 -10.7188)
					(mid 80.712056 -10.33526)
					(end 80.328516 -9.95172)
				)
				(arc
					(start 79.370682 -9.95172)
					(mid 78.987396 -10.335387)
					(end 79.370936 -10.7188)
				)
			)
		)
		(polygon
			(pts
				(arc
					(start 76.328524 -10.668)
					(mid 76.712064 -10.28446)
					(end 76.328524 -9.90092)
				)
				(arc
					(start 75.37069 -9.90092)
					(mid 74.987404 -10.284587)
					(end 75.370944 -10.668)
				)
			)
		)
		(polygon
			(pts
				(arc
					(start 72.328532 -10.668)
					(mid 72.712072 -10.28446)
					(end 72.328532 -9.90092)
				)
				(arc
					(start 71.370698 -9.90092)
					(mid 70.987412 -10.284587)
					(end 71.370952 -10.668)
				)
			)
		)
		(polygon
			(pts
				(arc
					(start 68.303394 -10.668)
					(mid 68.68668 -10.284333)
					(end 68.30314 -9.90092)
				)
				(arc
					(start 67.34556 -9.90092)
					(mid 66.96202 -10.28446)
					(end 67.34556 -10.668)
				)
			)
		)
		(polygon
			(pts
				(arc
					(start 50.310542 -10.64387)
					(mid 50.694082 -10.26033)
					(end 50.310542 -9.87679)
				)
				(arc
					(start 49.388776 -9.87679)
					(mid 49.00549 -10.260457)
					(end 49.38903 -10.64387)
				)
			)
		)
		(polygon
			(pts
				(arc
					(start 62.328044 -10.634218)
					(mid 62.71133 -10.250551)
					(end 62.32779 -9.867138)
				)
				(arc
					(start 61.40831 -9.867138)
					(mid 61.02477 -10.250678)
					(end 61.40831 -10.634218)
				)
			)
		)
		(polygon
			(pts
				(arc
					(start 48.327818 -10.634218)
					(mid 48.711358 -10.250678)
					(end 48.327818 -9.867138)
				)
				(arc
					(start 47.408084 -9.867138)
					(mid 47.024798 -10.250805)
					(end 47.408338 -10.634218)
				)
			)
		)
		(polygon
			(pts
				(arc
					(start 44.327826 -10.634218)
					(mid 44.711366 -10.250678)
					(end 44.327826 -9.867138)
				)
				(arc
					(start 43.408092 -9.867138)
					(mid 43.024806 -10.250805)
					(end 43.408346 -10.634218)
				)
			)
		)
		(polygon
			(pts
				(arc
					(start 40.327834 -10.634218)
					(mid 40.711374 -10.250678)
					(end 40.327834 -9.867138)
				)
				(arc
					(start 39.4081 -9.867138)
					(mid 39.024814 -10.250805)
					(end 39.408354 -10.634218)
				)
			)
		)
		(polygon
			(pts
				(arc
					(start 36.328096 -10.634218)
					(mid 36.711382 -10.250551)
					(end 36.327842 -9.867138)
				)
				(arc
					(start 35.408362 -9.867138)
					(mid 35.024822 -10.250678)
					(end 35.408362 -10.634218)
				)
			)
		)
		(polygon
			(pts
				(arc
					(start 32.328104 -10.634218)
					(mid 32.71139 -10.250551)
					(end 32.32785 -9.867138)
				)
				(arc
					(start 31.40837 -9.867138)
					(mid 31.02483 -10.250678)
					(end 31.40837 -10.634218)
				)
			)
		)
		(polygon
			(pts
				(arc
					(start 28.328112 -10.634218)
					(mid 28.711398 -10.250551)
					(end 28.327858 -9.867138)
				)
				(arc
					(start 27.408378 -9.867138)
					(mid 27.024838 -10.250678)
					(end 27.408378 -10.634218)
				)
			)
		)
		(polygon
			(pts
				(arc
					(start 24.327866 -10.634218)
					(mid 24.711406 -10.250678)
					(end 24.327866 -9.867138)
				)
				(arc
					(start 23.408132 -9.867138)
					(mid 23.024846 -10.250805)
					(end 23.408386 -10.634218)
				)
			)
		)
		(polygon
			(pts
				(arc
					(start 20.327874 -10.634218)
					(mid 20.711414 -10.250678)
					(end 20.327874 -9.867138)
				)
				(arc
					(start 19.40814 -9.867138)
					(mid 19.024854 -10.250805)
					(end 19.408394 -10.634218)
				)
			)
		)
		(polygon
			(pts
				(xy 193.296286 -2.3495) (xy 193.219578 -2.347722) (xy 193.2178 -2.3495) (xy 151.940006 -2.3495)
				(xy 144.701006 -9.5885) (xy 135.303006 -9.5885) (xy 131.239006 -13.6525) (xy 114.094006 -13.6525)
				(xy 111.4425 -16.304006) (xy 109.760766 -17.985994) (xy 108.252006 -19.4945) (xy 100.786438 -19.4945)
				(xy 100.783644 -19.49196) (xy 100.707952 -19.4945) (xy 100.632006 -19.4945) (xy 100.629466 -19.49704)
				(xy 100.62591 -19.49704) (xy 100.574094 -19.552412) (xy 100.5205 -19.606006) (xy 100.5205 -19.609562)
				(xy 98.61296 -21.644356) (xy 98.61804 -21.80209) (xy 98.6536 -21.835364) (xy 98.6536 -24.447754)
				(xy 97.2566 -25.844754) (xy 97.2566 -28.0035) (xy 92.026994 -28.0035) (xy 89.3445 -25.321006) (xy 89.3445 -21.541994)
				(xy 92.9005 -17.985994) (xy 92.9005 -16.304006) (xy 91.8845 -15.288006) (xy 91.772994 -15.1765)
				(xy 85.773006 -15.1765) (xy 84.8995 -16.050006) (xy 84.8995 -21.287994) (xy 86.4235 -22.811994)
				(xy 86.4235 -24.813006) (xy 85.6615 -25.575006) (xy 85.6615 -26.367994) (xy 88.4555 -29.161994)
				(xy 88.4555 -30.558994) (xy 88.9635 -31.066994) (xy 88.9635 -32.560006) (xy 88.4555 -33.068006)
				(xy 88.4555 -34.495994) (xy 90.7415 -36.781994) (xy 90.7415 -38.686994) (xy 91.5035 -39.448994)
				(xy 91.5035 -45.163994) (xy 93.139006 -46.7995) (xy 97.106994 -46.7995) (xy 97.8916 -46.014894)
				(xy 97.8916 -50.228246) (xy 98.2726 -50.609246) (xy 98.2726 -57.032906) (xy 98.2345 -57.071006)
				(xy 98.2345 -57.228994) (xy 102.537006 -61.5315) (xy 135.303006 -61.5315) (xy 136.9695 -63.197994)
				(xy 136.9695 -64.848994) (xy 142.415006 -70.2945) (xy 166.575994 -70.2945) (xy 166.6875 -70.182994)
				(xy 168.8465 -68.023994) (xy 168.8465 -64.945006) (xy 166.5605 -62.659006) (xy 166.5605 -60.119006)
				(xy 151.589994 -45.1485) (xy 121.079006 -45.1485) (xy 120.659906 -45.5676) (xy 118.300246 -45.5676)
				(xy 118.1354 -45.402754) (xy 118.046246 -45.3136) (xy 109.156246 -45.3136) (xy 108.7374 -44.894754)
				(xy 108.648246 -44.8056) (xy 107.478068 -44.8056) (xy 107.27817 -44.705778) (xy 107.251246 -44.6786)
				(xy 107.224068 -44.6786) (xy 107.199684 -44.666408) (xy 107.163362 -44.6786) (xy 102.0064 -44.6786)
				(xy 102.0064 -43.370754) (xy 101.7524 -43.116754) (xy 101.663246 -43.0276) (xy 99.758246 -43.0276)
				(xy 99.5934 -42.862754) (xy 99.5934 -37.147246) (xy 99.758246 -36.9824) (xy 101.790246 -36.9824)
				(xy 101.8794 -36.893246) (xy 102.8954 -35.877246) (xy 102.8954 -33.8074) (xy 103.949754 -33.8074)
				(xy 104.203754 -34.0614) (xy 111.061246 -34.0614) (xy 111.1504 -33.972246) (xy 111.696246 -33.4264)
				(xy 112.204246 -33.4264) (xy 112.2934 -33.337246) (xy 114.490246 -31.1404) (xy 117.738906 -31.1404)
				(xy 117.777006 -31.1785) (xy 117.934994 -31.1785) (xy 119.077994 -30.0355) (xy 161.495994 -30.0355)
				(xy 168.861994 -22.6695) (xy 187.911994 -22.6695) (xy 196.1515 -14.429994) (xy 196.1515 -5.336286)
				(xy 196.153278 -5.259578) (xy 196.1515 -5.2578) (xy 196.1515 -5.255006) (xy 196.097144 -5.200904)
				(xy 193.4845 -2.4638) (xy 193.4845 -2.461006) (xy 193.430144 -2.406904) (xy 193.377312 -2.351278)
				(xy 193.374772 -2.351278) (xy 193.372994 -2.3495)
			)
		)
	)
	(zone
		(net "P3V3_STBY")
		(layer "In7.Cu")
		(hatch none 0.5)
		(connect_pads
			(clearance 0.5)
		)
		(min_thickness 0.25)
		(fill yes
			(thermal_gap 0.5)
			(thermal_bridge_width 0.5)
			(island_removal_mode 0)
		)
		(polygon
			(pts
				(xy 60.833 -24.384) (xy 60.833 -23.749) (xy 59.817 -22.733) (xy 59.563 -22.479) (xy 54.737 -22.479)
				(xy 54.483 -22.733) (xy 52.959 -22.733) (xy 52.07 -21.844) (xy 51.943 -21.717) (xy 49.657 -21.717)
				(xy 49.53 -21.59) (xy 47.879 -21.59) (xy 47.625 -21.844) (xy 47.625 -22.606) (xy 47.9933 -22.9743)
				(xy 48.006 -22.9743) (xy 48.7807 -23.749) (xy 49.9364 -23.749) (xy 50.3174 -24.13) (xy 50.4444 -24.257)
				(xy 51.943 -24.257) (xy 52.07 -24.384) (xy 58.166 -24.384) (xy 58.547 -24.765) (xy 60.452 -24.765)
			)
		)
	)
	(zone
		(layer "In7.Cu")
		(hatch none 0.5)
		(connect_pads
			(clearance 0)
		)
		(min_thickness 0.25)
		(keepout
			(tracks not_allowed)
			(vias allowed)
			(pads allowed)
			(copperpour not_allowed)
			(footprints allowed)
		)
		(placement
			(enabled no)
			(sheetname "")
		)
		(fill
			(thermal_gap 0.5)
			(thermal_bridge_width 0.5)
			(island_removal_mode 0)
		)
		(polygon
			(pts
				(arc
					(start 53.535326 -28.897834)
					(mid 53.151786 -28.514294)
					(end 52.768246 -28.897834)
				)
				(arc
					(start 52.768246 -29.826966)
					(mid 53.151659 -30.21076)
					(end 53.535326 -29.82722)
				)
				(xy 53.535326 -29.59735) (xy 53.480462 -29.59735)
				(arc
					(start 53.38318 -29.694632)
					(mid 52.963209 -30.015797)
					(end 53.284374 -29.595826)
				)
				(xy 53.42255 -29.45765) (xy 53.535326 -29.45765) (xy 53.535326 -29.26715) (xy 53.422296 -29.26715)
				(arc
					(start 53.284374 -29.129228)
					(mid 52.963209 -28.709257)
					(end 53.38318 -29.030422)
				)
				(xy 53.480208 -29.12745) (xy 53.535326 -29.12745)
			)
		)
	)
	(zone
		(layer "In7.Cu")
		(hatch none 0.5)
		(connect_pads
			(clearance 0)
		)
		(min_thickness 0.25)
		(keepout
			(tracks not_allowed)
			(vias allowed)
			(pads allowed)
			(copperpour not_allowed)
			(footprints allowed)
		)
		(placement
			(enabled no)
			(sheetname "")
		)
		(fill
			(thermal_gap 0.5)
			(thermal_bridge_width 0.5)
			(island_removal_mode 0)
		)
		(polygon
			(pts
				(arc
					(start 52.1462 -13.56106)
					(mid 51.76266 -13.9446)
					(end 52.1462 -14.32814)
				)
				(xy 52.35575 -14.32814) (xy 52.35575 -14.252956)
				(arc
					(start 52.278788 -14.175994)
					(mid 51.957623 -13.756023)
					(end 52.377594 -14.077188)
				)
				(xy 52.49545 -14.195044) (xy 52.49545 -14.32814) (xy 52.68595 -14.32814) (xy 52.68595 -14.169644)
				(arc
					(start 52.778406 -14.077188)
					(mid 53.198377 -13.756023)
					(end 52.877212 -14.175994)
				)
				(xy 52.82565 -14.227556) (xy 52.82565 -14.32814)
				(arc
					(start 53.009546 -14.32814)
					(mid 53.39334 -13.944727)
					(end 53.0098 -13.56106)
				)
			)
		)
	)
	(zone
		(layer "In7.Cu")
		(hatch none 0.5)
		(connect_pads
			(clearance 0)
		)
		(min_thickness 0.25)
		(keepout
			(tracks not_allowed)
			(vias allowed)
			(pads allowed)
			(copperpour not_allowed)
			(footprints allowed)
		)
		(placement
			(enabled no)
			(sheetname "")
		)
		(fill
			(thermal_gap 0.5)
			(thermal_bridge_width 0.5)
			(island_removal_mode 0)
		)
		(polygon
			(pts
				(arc
					(start 84.348828 -59.595258)
					(mid 84.354625 -59.108766)
					(end 83.868006 -59.106054)
				)
				(xy 83.758532 -59.21502) (xy 83.822794 -59.279282)
				(arc
					(start 83.89239 -59.279282)
					(mid 84.338678 -59.349132)
					(end 83.89239 -59.418982)
				)
				(xy 83.764882 -59.418982) (xy 83.659472 -59.313572) (xy 83.524598 -59.448192) (xy 83.62188 -59.545474)
				(arc
					(start 83.62188 -59.687206)
					(mid 83.55203 -60.133494)
					(end 83.48218 -59.687206)
				)
				(xy 83.48218 -59.603386) (xy 83.425538 -59.546744)
				(arc
					(start 83.309968 -59.661806)
					(mid 83.308952 -60.146946)
					(end 83.794092 -60.147962)
				)
			)
		)
	)
	(zone
		(net "GND")
		(layer "In7.Cu")
		(hatch none 0.5)
		(connect_pads
			(clearance 0.5)
		)
		(min_thickness 0.25)
		(fill yes
			(thermal_gap 0.5)
			(thermal_bridge_width 0.5)
			(island_removal_mode 0)
		)
		(polygon
			(pts
				(xy 21.082 -13.081) (xy 19.685 -14.478) (xy 19.685 -19.431) (xy 14.859 -24.257) (xy 12.827 -24.257)
				(xy 11.303 -25.781) (xy 11.303 -27.686) (xy 11.049 -27.94) (xy 6.731 -27.94) (xy 4.953 -29.718)
				(xy 4.699 -29.972) (xy 4.699 -32.893) (xy 4.318 -33.274) (xy 1.143 -33.274) (xy 0.889 -33.528) (xy 0.762254 -33.654746)
				(xy 0.762254 -33.908746) (xy 0.762254 -72.771254) (xy 1.016 -73.025) (xy 8.382 -73.025) (xy 11.684 -73.025)
				(xy 14.7955 -69.9135) (xy 14.7955 -66.5099) (xy 13.9446 -65.659) (xy 10.033 -65.659) (xy 9.779 -65.913)
				(xy 9.271 -65.913) (xy 9.017 -65.659) (xy 9.017 -55.499) (xy 9.398 -55.118) (xy 9.652 -55.118) (xy 9.779 -55.118)
				(xy 10.033 -55.372) (xy 10.287 -55.372) (xy 10.541 -55.118) (xy 10.541 -54.61) (xy 10.033 -54.102)
				(xy 10.033 -52.451) (xy 9.525 -51.943) (xy 9.144 -51.562) (xy 9.144 -50.419) (xy 8.128 -49.403)
				(xy 5.207 -49.403) (xy 5.08 -49.276) (xy 5.08 -43.815) (xy 5.334 -43.561) (xy 7.112 -43.561) (xy 8.509 -43.561)
				(xy 9.652 -42.418) (xy 10.668 -41.402) (xy 12.573 -41.402) (xy 13.716 -42.545) (xy 21.971 -42.545)
				(xy 22.225 -42.291) (xy 22.606 -41.91) (xy 22.606 -40.132) (xy 27.94 -34.798) (xy 27.94 -34.29)
				(xy 27.94 -30.988) (xy 27.94 -25.527) (xy 27.94 -18.796) (xy 27.94 -13.716) (xy 27.686 -13.462)
				(xy 27.305 -13.081)
			)
		)
	)
	(zone
		(layer "In7.Cu")
		(hatch none 0.5)
		(connect_pads
			(clearance 0)
		)
		(min_thickness 0.25)
		(keepout
			(tracks not_allowed)
			(vias allowed)
			(pads allowed)
			(copperpour not_allowed)
			(footprints allowed)
		)
		(placement
			(enabled no)
			(sheetname "")
		)
		(fill
			(thermal_gap 0.5)
			(thermal_bridge_width 0.5)
			(island_removal_mode 0)
		)
		(polygon
			(pts
				(arc
					(start 13.55598 -47.66056)
					(mid 13.17244 -47.27702)
					(end 12.7889 -47.66056)
				)
				(arc
					(start 12.7889 -48.617886)
					(mid 13.172313 -49.00168)
					(end 13.55598 -48.61814)
				)
				(xy 13.55598 -48.4251) (xy 13.464286 -48.4251)
				(arc
					(start 13.403834 -48.485552)
					(mid 12.983863 -48.806717)
					(end 13.305028 -48.386746)
				)
				(xy 13.406374 -48.2854) (xy 13.55598 -48.2854) (xy 13.55598 -48.0949) (xy 13.507974 -48.0949)
				(arc
					(start 13.305028 -47.891954)
					(mid 12.983863 -47.471983)
					(end 13.403834 -47.793148)
				)
				(xy 13.55598 -47.945294)
			)
		)
	)
	(zone
		(layer "In7.Cu")
		(hatch none 0.5)
		(connect_pads
			(clearance 0)
		)
		(min_thickness 0.25)
		(keepout
			(tracks not_allowed)
			(vias allowed)
			(pads allowed)
			(copperpour not_allowed)
			(footprints allowed)
		)
		(placement
			(enabled no)
			(sheetname "")
		)
		(fill
			(thermal_gap 0.5)
			(thermal_bridge_width 0.5)
			(island_removal_mode 0)
		)
		(polygon
			(pts
				(arc
					(start 10.009886 -59.171078)
					(mid 9.615678 -58.798714)
					(end 9.243314 -59.192922)
				)
				(xy 9.240774 -59.192922) (xy 9.266174 -60.081668) (xy 9.266428 -60.081922)
				(arc
					(start 9.268714 -60.081922)
					(mid 9.662922 -60.454286)
					(end 10.035286 -60.060078)
				)
				(xy 10.037826 -60.060078) (xy 10.032238 -59.86145) (xy 9.960356 -59.86145)
				(arc
					(start 9.883394 -59.938412)
					(mid 9.463423 -60.259577)
					(end 9.784588 -59.839606)
				)
				(xy 9.902444 -59.72175) (xy 10.028174 -59.72175) (xy 10.02284 -59.53125) (xy 9.877044 -59.53125)
				(arc
					(start 9.759188 -59.413394)
					(mid 9.438023 -58.993423)
					(end 9.857994 -59.314588)
				)
				(xy 9.934956 -59.39155) (xy 10.018776 -59.39155) (xy 10.012426 -59.171078)
			)
		)
	)
	(zone
		(layer "In7.Cu")
		(hatch none 0.5)
		(connect_pads
			(clearance 0)
		)
		(min_thickness 0.25)
		(keepout
			(tracks not_allowed)
			(vias allowed)
			(pads allowed)
			(copperpour not_allowed)
			(footprints allowed)
		)
		(placement
			(enabled no)
			(sheetname "")
		)
		(fill
			(thermal_gap 0.5)
			(thermal_bridge_width 0.5)
			(island_removal_mode 0)
		)
		(polygon
			(pts
				(arc
					(start 10.01014 -55.626254)
					(mid 9.626727 -55.24246)
					(end 9.24306 -55.626)
				)
				(arc
					(start 9.24306 -56.515)
					(mid 9.6266 -56.89854)
					(end 10.01014 -56.515)
				)
				(xy 10.01014 -56.30545) (xy 9.934956 -56.30545)
				(arc
					(start 9.857994 -56.382412)
					(mid 9.438023 -56.703577)
					(end 9.759188 -56.283606)
				)
				(xy 9.877044 -56.16575) (xy 10.01014 -56.16575) (xy 10.01014 -55.97525) (xy 9.877044 -55.97525)
				(arc
					(start 9.759188 -55.857394)
					(mid 9.438023 -55.437423)
					(end 9.857994 -55.758588)
				)
				(xy 9.934956 -55.83555) (xy 10.01014 -55.83555)
			)
		)
	)
	(zone
		(layer "In7.Cu")
		(hatch none 0.5)
		(connect_pads
			(clearance 0)
		)
		(min_thickness 0.25)
		(keepout
			(tracks not_allowed)
			(vias allowed)
			(pads allowed)
			(copperpour not_allowed)
			(footprints allowed)
		)
		(placement
			(enabled no)
			(sheetname "")
		)
		(fill
			(thermal_gap 0.5)
			(thermal_bridge_width 0.5)
			(island_removal_mode 0)
		)
		(polygon
			(pts
				(arc
					(start 10.009886 -62.727078)
					(mid 9.615678 -62.354714)
					(end 9.243314 -62.748922)
				)
				(xy 9.240774 -62.748922) (xy 9.266174 -63.637668) (xy 9.266428 -63.637922)
				(arc
					(start 9.268714 -63.637922)
					(mid 9.662922 -64.010286)
					(end 10.035286 -63.616078)
				)
				(xy 10.037826 -63.616078) (xy 10.033508 -63.46825) (xy 9.909556 -63.46825)
				(arc
					(start 9.883394 -63.494412)
					(mid 9.463423 -63.815577)
					(end 9.784588 -63.395606)
				)
				(xy 9.851644 -63.32855) (xy 10.029698 -63.32855) (xy 10.02411 -63.13805) (xy 9.927844 -63.13805)
				(arc
					(start 9.759188 -62.969394)
					(mid 9.438023 -62.549423)
					(end 9.857994 -62.870588)
				)
				(xy 9.985756 -62.99835) (xy 10.0203 -62.99835) (xy 10.012426 -62.727078)
			)
		)
	)
	(zone
		(layer "In7.Cu")
		(hatch none 0.5)
		(connect_pads
			(clearance 0)
		)
		(min_thickness 0.25)
		(keepout
			(tracks not_allowed)
			(vias allowed)
			(pads allowed)
			(copperpour not_allowed)
			(footprints allowed)
		)
		(placement
			(enabled no)
			(sheetname "")
		)
		(fill
			(thermal_gap 0.5)
			(thermal_bridge_width 0.5)
			(island_removal_mode 0)
		)
		(polygon
			(pts
				(arc
					(start 49.454054 -13.4366)
					(mid 49.0728 -13.817473)
					(end 49.4538 -14.1986)
				)
				(xy 49.61255 -14.1986) (xy 49.61255 -14.075156)
				(arc
					(start 49.586388 -14.048994)
					(mid 49.265223 -13.629023)
					(end 49.685194 -13.950188)
				)
				(xy 49.75225 -14.017244) (xy 49.75225 -14.1986) (xy 49.94275 -14.1986) (xy 49.94275 -13.991844)
				(arc
					(start 49.984406 -13.950188)
					(mid 50.404377 -13.629023)
					(end 50.083212 -14.048994)
				)
				(xy 50.08245 -14.049756) (xy 50.08245 -14.1986)
				(arc
					(start 50.2158 -14.1986)
					(mid 50.5968 -13.8176)
					(end 50.2158 -13.4366)
				)
			)
		)
	)
	(zone
		(net "P1V0")
		(layer "In7.Cu")
		(hatch none 0.5)
		(connect_pads
			(clearance 0.5)
		)
		(min_thickness 0.25)
		(fill yes
			(thermal_gap 0.5)
			(thermal_bridge_width 0.5)
			(island_removal_mode 0)
		)
		(polygon
			(pts
				(xy 94.996 -46.355) (xy 95.377 -45.974) (xy 95.377 -45.212) (xy 95.504 -45.085) (xy 95.885 -44.704)
				(xy 96.012 -44.577) (xy 96.266 -44.323) (xy 96.266 -43.688) (xy 96.52 -43.434) (xy 96.774 -43.434)
				(xy 97.028 -43.688) (xy 97.028 -44.323) (xy 97.282 -44.577) (xy 101.346 -44.577) (xy 101.727 -44.196)
				(xy 101.727 -43.561) (xy 101.473 -43.307) (xy 99.314 -43.307) (xy 98.806 -42.799) (xy 98.806 -37.465)
				(xy 99.441 -36.83) (xy 101.854 -36.83) (xy 102.489 -36.195) (xy 102.489 -35.687) (xy 102.489 -34.544)
				(xy 102.235 -34.29) (xy 101.6 -34.29) (xy 101.219 -33.909) (xy 100.457 -33.909) (xy 99.187 -32.639)
				(xy 98.171 -32.639) (xy 97.663 -32.639) (xy 96.52 -31.496) (xy 96.52 -30.226) (xy 96.52 -28.321)
				(xy 96.52 -28.067) (xy 96.266 -27.813) (xy 95.377 -27.813) (xy 95.25 -27.94) (xy 92.583 -27.94)
				(xy 92.075 -27.432) (xy 91.567 -27.432) (xy 91.2876 -27.432) (xy 91.2114 -27.432) (xy 89.2556 -25.4762)
				(xy 89.2556 -25.4) (xy 89.2556 -21.3614) (xy 89.4334 -21.1836) (xy 89.5096 -21.1074) (xy 89.662 -20.955)
				(xy 92.583 -18.034) (xy 92.583 -17.145) (xy 92.202 -16.764) (xy 87.249 -16.764) (xy 85.979 -18.034)
				(xy 85.979 -19.939) (xy 85.979 -21.463) (xy 86.995 -22.479) (xy 86.995 -25.019) (xy 86.995 -27.051)
				(xy 88.519 -28.575) (xy 88.519 -28.829) (xy 88.519 -29.718) (xy 88.9 -30.099) (xy 89.281 -30.48)
				(xy 89.281 -34.925) (xy 90.805 -36.449) (xy 90.805 -38.735) (xy 91.44 -39.37) (xy 91.44 -41.91)
				(xy 92.329 -42.799) (xy 92.329 -43.688) (xy 92.2655 -43.7515) (xy 92.2655 -45.2755) (xy 92.329 -45.339)
				(xy 93.345 -46.355)
			)
		)
	)
	(zone
		(layer "In7.Cu")
		(hatch none 0.5)
		(connect_pads
			(clearance 0)
		)
		(min_thickness 0.25)
		(keepout
			(tracks not_allowed)
			(vias allowed)
			(pads allowed)
			(copperpour not_allowed)
			(footprints allowed)
		)
		(placement
			(enabled no)
			(sheetname "")
		)
		(fill
			(thermal_gap 0.5)
			(thermal_bridge_width 0.5)
			(island_removal_mode 0)
		)
		(polygon
			(pts
				(arc
					(start 91.403424 -53.414168)
					(mid 91.076653 -53.050941)
					(end 90.71356 -53.377846)
				)
				(xy 90.71102 -53.377592) (xy 90.702892 -53.5305) (xy 90.833956 -53.5305)
				(arc
					(start 90.85834 -53.50637)
					(mid 91.220153 -53.234219)
					(end 90.948002 -53.596032)
				)
				(xy 90.923872 -53.620416) (xy 90.886788 -53.6575) (xy 90.833956 -53.6575) (xy 90.696288 -53.6575)
				(xy 90.692224 -53.7337) (xy 90.843354 -53.7337) (xy 90.896186 -53.7337)
				(arc
					(start 90.918538 -53.756306)
					(mid 91.196409 -54.11219)
					(end 90.82151 -53.8607)
				)
				(xy 90.68562 -53.8607) (xy 90.681556 -53.93817)
				(arc
					(start 90.684096 -53.938424)
					(mid 91.010994 -54.30139)
					(end 91.37396 -53.974492)
				)
				(xy 91.3765 -53.974746) (xy 91.405964 -53.414422) (xy 91.40571 -53.414168)
			)
		)
	)
	(zone
		(net "PV_VDDR")
		(layer "In7.Cu")
		(hatch none 0.5)
		(connect_pads
			(clearance 0.5)
		)
		(min_thickness 0.25)
		(fill yes
			(thermal_gap 0.5)
			(thermal_bridge_width 0.5)
			(island_removal_mode 0)
		)
		(polygon
			(pts
				(xy 204.7875 -67.7545) (xy 207.391 -65.151) (xy 207.391 -19.05) (xy 206.883 -18.542) (xy 204.597 -18.542)
				(xy 201.422 -18.542) (xy 200.533 -17.653) (xy 200.533 -6.604) (xy 197.612 -3.683) (xy 195.707 -3.683)
				(xy 191.643 -3.683) (xy 191.135 -4.191) (xy 191.135 -9.906) (xy 186.69 -14.351) (xy 186.69 -23.749)
				(xy 186.309 -24.13) (xy 185.547 -24.892) (xy 184.531 -24.892) (xy 180.467 -28.956) (xy 180.467 -38.354)
				(xy 182.88 -40.767) (xy 186.309 -40.767) (xy 191.516 -45.974) (xy 191.77 -46.228) (xy 191.77 -58.166)
				(xy 195.707 -62.103) (xy 195.707 -66.929) (xy 195.707 -67.564) (xy 196.596 -68.453) (xy 204.089 -68.453)
			)
		)
		(polygon
			(pts
				(xy 198.755 -48.26) (xy 198.755 -51.308) (xy 198.755 -51.816) (xy 199.644 -52.705) (xy 199.644 -55.88)
				(xy 200.152 -56.388) (xy 200.914 -56.388) (xy 201.295 -56.007) (xy 201.295 -52.959) (xy 201.422 -52.832)
				(xy 201.93 -52.832) (xy 202.311 -52.451) (xy 202.311 -51.816) (xy 202.311 -51.562) (xy 202.184 -51.435)
				(xy 202.184 -49.53) (xy 203.581 -48.133) (xy 203.581 -47.244) (xy 203.2 -46.863) (xy 202.819 -46.863)
				(xy 200.025 -46.863) (xy 199.644 -46.863) (xy 198.755 -47.752) (xy 198.755 -48.133)
			)
		)
		(polygon
			(pts
				(xy 184.277 -26.924) (xy 183.896 -26.924) (xy 183.515 -27.305) (xy 183.515 -27.813) (xy 184.15 -28.448)
				(xy 189.992 -28.448) (xy 191.008 -29.464) (xy 191.008 -34.544) (xy 192.786 -36.322) (xy 197.612 -36.322)
				(xy 197.866 -36.068) (xy 197.866 -31.115) (xy 194.056 -27.305) (xy 184.658 -27.305)
			)
		)
	)
	(zone
		(net "P12V")
		(layer "In7.Cu")
		(hatch none 0.5)
		(connect_pads
			(clearance 0.5)
		)
		(min_thickness 0.25)
		(fill yes
			(thermal_gap 0.5)
			(thermal_bridge_width 0.5)
			(island_removal_mode 0)
		)
		(polygon
			(pts
				(xy 15.748 -10.414) (xy 15.494 -10.668) (xy 15.494 -14.859) (xy 14.859 -15.494) (xy 1.397 -15.494)
				(xy 0.762254 -16.128746) (xy 0.762254 -32.512254) (xy 1.143 -32.893) (xy 4.064 -32.893) (xy 4.318 -32.639)
				(xy 4.318 -29.718) (xy 4.445 -29.591) (xy 8.763 -25.273) (xy 10.16 -23.876) (xy 11.303 -23.876)
				(xy 12.065 -23.114) (xy 13.589 -23.114) (xy 14.986 -21.717) (xy 16.002 -21.717) (xy 19.304 -18.415)
				(xy 19.304 -10.795) (xy 18.923 -10.414)
			)
		)
	)
	(zone
		(net "GND")
		(layer "In7.Cu")
		(hatch none 0.5)
		(connect_pads
			(clearance 0.5)
		)
		(min_thickness 0.25)
		(fill yes
			(thermal_gap 0.5)
			(thermal_bridge_width 0.5)
			(island_removal_mode 0)
		)
		(polygon
			(pts
				(xy 21.082 -70.231) (xy 37.211 -70.231) (xy 43.942 -70.231) (xy 46.101 -68.072) (xy 46.355 -68.072)
				(xy 62.611 -68.072) (xy 64.516 -66.167) (xy 64.77 -65.913) (xy 64.77 -63.119) (xy 64.262 -62.611)
				(xy 57.023 -62.611) (xy 56.896 -62.484) (xy 56.769 -62.357) (xy 56.515 -62.103) (xy 56.515 -56.769)
				(xy 56.134 -56.388) (xy 54.229 -56.388) (xy 52.832 -56.388) (xy 52.324 -55.88) (xy 33.274 -55.88)
				(xy 31.75 -54.356) (xy 28.829 -54.356) (xy 26.416 -56.769) (xy 25.273 -56.769) (xy 23.876 -55.372)
				(xy 19.685 -55.372) (xy 18.288 -56.769) (xy 17.272 -57.785) (xy 17.272 -59.055) (xy 16.637 -59.69)
				(xy 16.637 -66.929) (xy 17.272 -67.564) (xy 18.288 -67.564) (xy 18.415 -67.564)
			)
		)
	)
	(zone
		(layer "In7.Cu")
		(hatch none 0.5)
		(connect_pads
			(clearance 0)
		)
		(min_thickness 0.25)
		(keepout
			(tracks not_allowed)
			(vias allowed)
			(pads allowed)
			(copperpour not_allowed)
			(footprints allowed)
		)
		(placement
			(enabled no)
			(sheetname "")
		)
		(fill
			(thermal_gap 0.5)
			(thermal_bridge_width 0.5)
			(island_removal_mode 0)
		)
		(polygon
			(pts
				(arc
					(start 63.627254 -14.3256)
					(mid 63.246 -14.706473)
					(end 63.627 -15.0876)
				)
				(xy 63.76035 -15.0876) (xy 63.76035 -14.938756)
				(arc
					(start 63.759588 -14.937994)
					(mid 63.438423 -14.518023)
					(end 63.858394 -14.839188)
				)
				(xy 63.90005 -14.880844) (xy 63.90005 -15.0876) (xy 64.09055 -15.0876) (xy 64.09055 -14.906244)
				(xy 64.11595 -14.880844)
				(arc
					(start 64.157606 -14.839188)
					(mid 64.577577 -14.518023)
					(end 64.256412 -14.937994)
				)
				(xy 64.23025 -14.964156) (xy 64.23025 -15.0876)
				(arc
					(start 64.389 -15.0876)
					(mid 64.77 -14.7066)
					(end 64.389 -14.3256)
				)
			)
		)
	)
	(zone
		(layer "In7.Cu")
		(hatch none 0.5)
		(connect_pads
			(clearance 0)
		)
		(min_thickness 0.25)
		(keepout
			(tracks not_allowed)
			(vias allowed)
			(pads allowed)
			(copperpour not_allowed)
			(footprints allowed)
		)
		(placement
			(enabled no)
			(sheetname "")
		)
		(fill
			(thermal_gap 0.5)
			(thermal_bridge_width 0.5)
			(island_removal_mode 0)
		)
		(polygon
			(pts
				(arc
					(start 10.01014 -60.960254)
					(mid 9.626727 -60.57646)
					(end 9.24306 -60.96)
				)
				(arc
					(start 9.24306 -61.849)
					(mid 9.6266 -62.23254)
					(end 10.01014 -61.849)
				)
				(xy 10.01014 -61.63945) (xy 9.934956 -61.63945)
				(arc
					(start 9.857994 -61.716412)
					(mid 9.438023 -62.037577)
					(end 9.759188 -61.617606)
				)
				(xy 9.877044 -61.49975) (xy 10.01014 -61.49975) (xy 10.01014 -61.30925) (xy 9.877044 -61.30925)
				(arc
					(start 9.759188 -61.191394)
					(mid 9.438023 -60.771423)
					(end 9.857994 -61.092588)
				)
				(xy 9.934956 -61.16955) (xy 10.01014 -61.16955)
			)
		)
	)
	(zone
		(layer "In7.Cu")
		(hatch none 0.5)
		(connect_pads
			(clearance 0)
		)
		(min_thickness 0.25)
		(keepout
			(tracks not_allowed)
			(vias allowed)
			(pads allowed)
			(copperpour not_allowed)
			(footprints allowed)
		)
		(placement
			(enabled no)
			(sheetname "")
		)
		(fill
			(thermal_gap 0.5)
			(thermal_bridge_width 0.5)
			(island_removal_mode 0)
		)
		(polygon
			(pts
				(arc
					(start 83.701636 -55.68061)
					(mid 83.668625 -55.193446)
					(end 83.18119 -55.226204)
				)
				(xy 83.011518 -55.420768)
				(arc
					(start 83.215226 -55.420768)
					(mid 83.666778 -55.414)
					(end 83.23961 -55.560468)
				)
				(xy 82.889598 -55.560468)
				(arc
					(start 82.803746 -55.65902)
					(mid 82.771283 -55.702716)
					(end 82.746088 -55.750968)
				)
				(arc
					(start 82.879692 -55.750968)
					(mid 83.282077 -55.955008)
					(end 82.835496 -55.890668)
				)
				(arc
					(start 82.718656 -55.890668)
					(mid 82.944985 -56.210383)
					(end 83.324446 -56.113172)
				)
			)
		)
	)
	(zone
		(layer "In7.Cu")
		(hatch none 0.5)
		(connect_pads
			(clearance 0)
		)
		(min_thickness 0.25)
		(keepout
			(tracks not_allowed)
			(vias allowed)
			(pads allowed)
			(copperpour not_allowed)
			(footprints allowed)
		)
		(placement
			(enabled no)
			(sheetname "")
		)
		(fill
			(thermal_gap 0.5)
			(thermal_bridge_width 0.5)
			(island_removal_mode 0)
		)
		(polygon
			(pts
				(arc
					(start 14.949678 -46.601126)
					(mid 15.270843 -47.021097)
					(end 14.850872 -46.699932)
				)
				(xy 14.71295 -46.56201) (xy 14.71295 -46.44898) (xy 14.52245 -46.44898) (xy 14.52245 -46.561756)
				(arc
					(start 14.384274 -46.699932)
					(mid 13.964303 -47.021097)
					(end 14.285468 -46.601126)
				)
				(xy 14.38275 -46.503844) (xy 14.38275 -46.44898)
				(arc
					(start 14.153134 -46.44898)
					(mid 13.76934 -46.832393)
					(end 14.15288 -47.21606)
				)
				(arc
					(start 15.082266 -47.21606)
					(mid 15.465806 -46.83252)
					(end 15.082266 -46.44898)
				)
				(xy 14.85265 -46.44898) (xy 14.85265 -46.504098)
			)
		)
	)
	(zone
		(net "P12V")
		(layer "In7.Cu")
		(hatch none 0.5)
		(connect_pads
			(clearance 0.5)
		)
		(min_thickness 0.25)
		(fill yes
			(thermal_gap 0.5)
			(thermal_bridge_width 0.5)
			(island_removal_mode 0)
		)
		(polygon
			(pts
				(xy 71.755 -72.136) (xy 74.3585 -69.5325) (xy 74.549 -69.342) (xy 77.724 -69.342) (xy 77.851 -69.469)
				(xy 78.359 -69.977) (xy 80.264 -69.977) (xy 80.5815 -69.6595) (xy 82.3595 -69.6595) (xy 84.074 -71.374)
				(xy 85.852 -71.374) (xy 86.106 -71.12) (xy 86.106 -70.485) (xy 83.82 -68.199) (xy 83.439 -67.818)
				(xy 82.169 -66.548) (xy 77.089 -66.548) (xy 75.819 -67.818) (xy 73.025 -67.818) (xy 70.104 -70.739)
				(xy 70.104 -71.628) (xy 70.612 -72.136)
			)
		)
	)
	(zone
		(layer "In7.Cu")
		(hatch none 0.5)
		(connect_pads
			(clearance 0)
		)
		(min_thickness 0.25)
		(keepout
			(tracks not_allowed)
			(vias allowed)
			(pads allowed)
			(copperpour not_allowed)
			(footprints allowed)
		)
		(placement
			(enabled no)
			(sheetname "")
		)
		(fill
			(thermal_gap 0.5)
			(thermal_bridge_width 0.5)
			(island_removal_mode 0)
		)
		(polygon
			(pts
				(arc
					(start 10.01014 -57.404254)
					(mid 9.626727 -57.02046)
					(end 9.24306 -57.404)
				)
				(arc
					(start 9.24306 -58.293)
					(mid 9.6266 -58.67654)
					(end 10.01014 -58.293)
				)
				(xy 10.01014 -58.13425) (xy 9.884156 -58.13425)
				(arc
					(start 9.857994 -58.160412)
					(mid 9.438023 -58.481577)
					(end 9.759188 -58.061606)
				)
				(xy 9.826244 -57.99455) (xy 10.01014 -57.99455) (xy 10.01014 -57.80405) (xy 9.927844 -57.80405)
				(arc
					(start 9.759188 -57.635394)
					(mid 9.438023 -57.215423)
					(end 9.857994 -57.536588)
				)
				(xy 9.985756 -57.66435) (xy 10.01014 -57.66435)
			)
		)
	)
	(zone
		(layer "In7.Cu")
		(hatch none 0.5)
		(connect_pads
			(clearance 0)
		)
		(min_thickness 0.25)
		(keepout
			(tracks not_allowed)
			(vias allowed)
			(pads allowed)
			(copperpour not_allowed)
			(footprints allowed)
		)
		(placement
			(enabled no)
			(sheetname "")
		)
		(fill
			(thermal_gap 0.5)
			(thermal_bridge_width 0.5)
			(island_removal_mode 0)
		)
		(polygon
			(pts
				(arc
					(start 10.01014 -64.516254)
					(mid 9.626727 -64.13246)
					(end 9.24306 -64.516)
				)
				(arc
					(start 9.24306 -65.405)
					(mid 9.6266 -65.78854)
					(end 10.01014 -65.405)
				)
				(xy 10.01014 -65.19545) (xy 9.934956 -65.19545)
				(arc
					(start 9.857994 -65.272412)
					(mid 9.438023 -65.593577)
					(end 9.759188 -65.173606)
				)
				(xy 9.877044 -65.05575) (xy 10.01014 -65.05575) (xy 10.01014 -64.86525) (xy 9.877044 -64.86525)
				(arc
					(start 9.759188 -64.747394)
					(mid 9.438023 -64.327423)
					(end 9.857994 -64.648588)
				)
				(xy 9.934956 -64.72555) (xy 10.01014 -64.72555)
			)
		)
	)
	(zone
		(net "GND")
		(layer "In7.Cu")
		(hatch none 0.5)
		(connect_pads
			(clearance 0.5)
		)
		(min_thickness 0.25)
		(fill yes
			(thermal_gap 0.5)
			(thermal_bridge_width 0.5)
			(island_removal_mode 0)
		)
		(polygon
			(pts
				(xy 173.13021 -48.41621) (xy 167.132 -45.466) (xy 166.13124 -44.89323) (xy 162.994086 -42.628566)
				(xy 160.7058 -40.6146) (xy 158.8897 -39.2557) (xy 158.877 -39.243) (xy 114.935 -39.243) (xy 110.109 -39.243)
				(xy 109.855 -39.497) (xy 105.283 -39.497) (xy 105.156 -39.624) (xy 104.775 -39.624) (xy 104.521 -39.37)
				(xy 104.521 -39.116) (xy 104.394 -38.989) (xy 102.87 -37.465) (xy 102.87 -37.211) (xy 102.616 -36.957)
				(xy 102.362 -36.957) (xy 102.235 -36.83) (xy 102.235 -36.576) (xy 104.521 -34.29) (xy 106.934 -31.877)
				(xy 109.728 -31.877) (xy 110.109 -32.258) (xy 112.268 -32.258) (xy 112.776 -32.258) (xy 113.157 -32.258)
				(xy 115.189 -34.29) (xy 117.221 -34.29) (xy 117.602 -33.909) (xy 117.602 -31.115) (xy 118.364 -30.353)
				(xy 118.872 -29.845) (xy 156.083 -29.845) (xy 170.688 -15.24) (xy 170.688 -10.414) (xy 170.434 -10.16)
				(xy 170.434 -8.763) (xy 170.434 -5.969) (xy 170.434 -4.445) (xy 170.434 -4.318) (xy 169.672 -3.556)
				(xy 169.672 -3.048) (xy 169.291 -2.667) (xy 156.337 -2.667) (xy 155.575 -3.429) (xy 155.575 -3.937)
				(xy 152.654 -6.858) (xy 152.654 -8.255) (xy 152.654 -8.89) (xy 151.892 -9.652) (xy 150.622 -10.922)
				(xy 135.636 -10.922) (xy 134.874 -10.16) (xy 134.874 -7.747) (xy 134.874 -4.318) (xy 135.128 -4.064)
				(xy 135.128 -3.556) (xy 135.128 -2.921) (xy 134.747 -2.54) (xy 115.824 -2.54) (xy 115.443 -2.159)
				(xy 115.443 -1.016) (xy 115.697 -0.762) (xy 135.636 -0.762) (xy 170.18 -0.762) (xy 188.976 -0.762)
				(xy 189.611 -1.397) (xy 189.611 -3.175) (xy 188.976 -3.81) (xy 188.976 -7.112) (xy 189.484 -7.62)
				(xy 189.484 -9.525) (xy 184.15 -14.859) (xy 184.15 -20.574) (xy 178.562 -26.162) (xy 178.562 -39.751)
				(xy 178.562 -45.339) (xy 177.32121 -46.57979) (xy 177.32121 -48.41621) (xy 179.705 -50.8) (xy 180.848 -50.8)
				(xy 182.118 -52.07) (xy 182.118 -52.451) (xy 181.61 -52.959) (xy 177.673 -52.959)
			)
		)
	)
	(zone
		(layer "In7.Cu")
		(hatch none 0.5)
		(connect_pads
			(clearance 0)
		)
		(min_thickness 0.25)
		(keepout
			(tracks not_allowed)
			(vias allowed)
			(pads allowed)
			(copperpour not_allowed)
			(footprints allowed)
		)
		(placement
			(enabled no)
			(sheetname "")
		)
		(fill
			(thermal_gap 0.5)
			(thermal_bridge_width 0.5)
			(island_removal_mode 0)
		)
		(polygon
			(pts
				(arc
					(start 80.264254 -60.0329)
					(mid 79.9211 -60.375673)
					(end 80.264 -60.7187)
				)
				(arc
					(start 81.0514 -60.7187)
					(mid 81.3943 -60.3758)
					(end 81.0514 -60.0329)
				)
				(xy 80.91297 -60.0329) (xy 80.91297 -60.138564)
				(arc
					(start 80.946752 -60.1726)
					(mid 81.213019 -60.537419)
					(end 80.8482 -60.271152)
				)
				(xy 80.77327 -60.196476) (xy 80.77327 -60.0329) (xy 80.58277 -60.0329) (xy 80.58277 -60.155836)
				(arc
					(start 80.4672 -60.271152)
					(mid 80.102381 -60.537419)
					(end 80.368648 -60.1726)
				)
				(xy 80.44307 -60.097924) (xy 80.44307 -60.0329)
			)
		)
	)
	(zone
		(layer "In7.Cu")
		(hatch none 0.5)
		(connect_pads
			(clearance 0)
		)
		(min_thickness 0.25)
		(keepout
			(tracks not_allowed)
			(vias allowed)
			(pads allowed)
			(copperpour not_allowed)
			(footprints allowed)
		)
		(placement
			(enabled no)
			(sheetname "")
		)
		(fill
			(thermal_gap 0.5)
			(thermal_bridge_width 0.5)
			(island_removal_mode 0)
		)
		(polygon
			(pts
				(arc
					(start 65.786 -14.3002)
					(mid 65.405 -14.6812)
					(end 65.786 -15.0622)
				)
				(xy 65.94475 -15.0622) (xy 65.94475 -14.938756)
				(arc
					(start 65.918588 -14.912594)
					(mid 65.597423 -14.492623)
					(end 66.017394 -14.813788)
				)
				(xy 66.08445 -14.880844) (xy 66.08445 -15.0622) (xy 66.27495 -15.0622) (xy 66.27495 -14.855444)
				(arc
					(start 66.316606 -14.813788)
					(mid 66.736577 -14.492623)
					(end 66.415412 -14.912594)
				)
				(xy 66.41465 -14.913356) (xy 66.41465 -15.0622)
				(arc
					(start 66.547746 -15.0622)
					(mid 66.929 -14.681327)
					(end 66.548 -14.3002)
				)
			)
		)
	)
	(zone
		(net "GND")
		(layer "In7.Cu")
		(hatch none 0.5)
		(connect_pads
			(clearance 0.5)
		)
		(min_thickness 0.25)
		(fill yes
			(thermal_gap 0.5)
			(thermal_bridge_width 0.5)
			(island_removal_mode 0)
		)
		(polygon
			(pts
				(xy 31.496 -45.593) (xy 32.512 -45.593) (xy 34.417 -47.498) (xy 38.735 -47.498) (xy 39.116 -47.117)
				(xy 39.116 -46.736) (xy 37.338 -44.958) (xy 37.338 -42.164) (xy 37.084 -41.91) (xy 33.655 -41.91)
				(xy 31.242 -44.323) (xy 31.242 -45.339)
			)
		)
	)
	(zone
		(layer "In7.Cu")
		(hatch none 0.5)
		(connect_pads
			(clearance 0)
		)
		(min_thickness 0.25)
		(keepout
			(tracks not_allowed)
			(vias allowed)
			(pads allowed)
			(copperpour not_allowed)
			(footprints allowed)
		)
		(placement
			(enabled no)
			(sheetname "")
		)
		(fill
			(thermal_gap 0.5)
			(thermal_bridge_width 0.5)
			(island_removal_mode 0)
		)
		(polygon
			(pts
				(arc
					(start 61.317378 -45.848016)
					(mid 60.910088 -45.489868)
					(end 60.551822 -45.897038)
				)
				(arc
					(start 60.607448 -46.75886)
					(mid 61.014864 -47.117)
					(end 61.373004 -46.709584)
				)
				(xy 61.36259 -46.550072) (xy 61.273182 -46.550072)
				(arc
					(start 61.22162 -46.601634)
					(mid 60.801649 -46.922799)
					(end 61.122814 -46.502828)
				)
				(xy 61.21527 -46.410372) (xy 61.3537 -46.410372) (xy 61.341508 -46.219872) (xy 61.183266 -46.219872)
				(arc
					(start 61.067188 -46.103794)
					(mid 60.746023 -45.683823)
					(end 61.165994 -46.004988)
				)
				(xy 61.241178 -46.080172) (xy 61.332364 -46.080172)
			)
		)
	)
	(zone
		(layers "In7.Cu" "In9.Cu")
		(hatch none 0.5)
		(connect_pads
			(clearance 0)
		)
		(min_thickness 0.25)
		(keepout
			(tracks not_allowed)
			(vias allowed)
			(pads allowed)
			(copperpour not_allowed)
			(footprints allowed)
		)
		(placement
			(enabled no)
			(sheetname "")
		)
		(fill yes
			(thermal_gap 0.5)
			(thermal_bridge_width 0.5)
			(island_removal_mode 0)
		)
		(polygon
			(pts
				(xy 70.485 -41.91) (xy 70.485 -38.1) (xy 72.263 -38.1) (xy 72.263 -41.91)
			)
		)
	)
	(zone
		(net "GND")
		(layer "In8.Cu")
		(hatch none 0.5)
		(connect_pads
			(clearance 0.5)
		)
		(min_thickness 0.25)
		(fill yes
			(thermal_gap 0.5)
			(thermal_bridge_width 0.5)
			(island_removal_mode 0)
		)
		(polygon
			(pts
				(arc
					(start 106.000042 -0.763016)
					(mid 105.83247 -0.832426)
					(end 105.76306 -0.999998)
				)
				(arc
					(start 105.76306 -10.700004)
					(mid 105.246685 -11.946643)
					(end 104.000046 -12.463018)
				)
				(arc
					(start 100.000054 -12.463018)
					(mid 98.753415 -11.946643)
					(end 98.23704 -10.700004)
				)
				(xy 98.23704 -5.244592) (xy 97.448624 -5.244592) (xy 88.562942 -5.244592)
				(arc
					(start 88.562942 -10.150094)
					(mid 86.849966 -11.86307)
					(end 85.13699 -10.150094)
				)
				(xy 85.13699 -5.244592) (xy 15.463012 -5.244592)
				(arc
					(start 15.463012 -13.699998)
					(mid 14.946637 -14.946637)
					(end 13.699998 -15.463012)
				)
				(arc
					(start 0.999998 -15.463012)
					(mid 0.832426 -15.532422)
					(end 0.763016 -15.699994)
				)
				(arc
					(start 0.763016 -72.799956)
					(mid 0.832426 -72.967528)
					(end 0.999998 -73.036938)
				)
				(arc
					(start 209.00009 -73.036938)
					(mid 209.167662 -72.967528)
					(end 209.237072 -72.799956)
				)
				(arc
					(start 209.237072 -0.999998)
					(mid 209.167662 -0.832426)
					(end 209.00009 -0.763016)
				)
			)
		)
		(polygon
			(pts
				(arc
					(start 2.31394 -66.220848)
					(mid 1.930273 -65.837562)
					(end 1.54686 -66.221102)
				)
				(arc
					(start 1.54686 -67.178682)
					(mid 1.9304 -67.562222)
					(end 2.31394 -67.178682)
				)
			)
		)
		(polygon
			(pts
				(arc
					(start 3.8354 -64.7065)
					(mid 3.451733 -64.323214)
					(end 3.06832 -64.706754)
				)
				(arc
					(start 3.06832 -65.664334)
					(mid 3.45186 -66.047874)
					(end 3.8354 -65.664334)
				)
			)
		)
		(polygon
			(pts
				(arc
					(start 10.01014 -64.515746)
					(mid 9.626473 -64.13246)
					(end 9.24306 -64.516)
				)
				(arc
					(start 9.24306 -65.405)
					(mid 9.6266 -65.78854)
					(end 10.01014 -65.405)
				)
			)
		)
		(polygon
			(pts
				(arc
					(start 2.31394 -63.221108)
					(mid 1.9304 -62.837568)
					(end 1.54686 -63.221108)
				)
				(arc
					(start 1.54686 -64.178942)
					(mid 1.930527 -64.562228)
					(end 2.31394 -64.178688)
				)
			)
		)
		(polygon
			(pts
				(arc
					(start 10.009886 -62.727078)
					(mid 9.615678 -62.354714)
					(end 9.243314 -62.748922)
				)
				(xy 9.240774 -62.748922) (xy 9.266174 -63.637668) (xy 9.266428 -63.637922)
				(arc
					(start 9.268714 -63.637922)
					(mid 9.662922 -64.010286)
					(end 10.035286 -63.616078)
				)
				(xy 10.037826 -63.616078) (xy 10.012426 -62.727078)
			)
		)
		(polygon
			(pts
				(arc
					(start 101.734366 -61.66993)
					(mid 101.189299 -61.660676)
					(end 101.185472 -62.20587)
				)
				(arc
					(start 101.795072 -62.817756)
					(mid 102.337616 -62.818772)
					(end 102.338632 -62.276228)
				)
			)
		)
		(polygon
			(pts
				(arc
					(start 3.8354 -61.706506)
					(mid 3.451733 -61.32322)
					(end 3.06832 -61.70676)
				)
				(arc
					(start 3.06832 -62.66434)
					(mid 3.45186 -63.04788)
					(end 3.8354 -62.66434)
				)
			)
		)
		(polygon
			(pts
				(arc
					(start 10.01014 -60.959746)
					(mid 9.626473 -60.57646)
					(end 9.24306 -60.96)
				)
				(arc
					(start 9.24306 -61.849)
					(mid 9.6266 -62.23254)
					(end 10.01014 -61.849)
				)
			)
		)
		(polygon
			(pts
				(arc
					(start 99.781106 -60.369704)
					(mid 99.238816 -60.378086)
					(end 99.247198 -60.920376)
				)
				(xy 99.24542 -60.922154) (xy 99.86518 -61.523372) (xy 99.865434 -61.523372)
				(arc
					(start 99.866958 -61.521848)
					(mid 100.409565 -61.513655)
					(end 100.40112 -60.971176)
				)
				(xy 100.402898 -60.969398) (xy 99.782884 -60.367926)
			)
		)
		(polygon
			(pts
				(arc
					(start 81.0514 -60.7187)
					(mid 81.3943 -60.3758)
					(end 81.0514 -60.0329)
				)
				(arc
					(start 80.263746 -60.0329)
					(mid 79.9211 -60.375927)
					(end 80.264 -60.7187)
				)
			)
		)
		(polygon
			(pts
				(arc
					(start 2.31394 -60.22086)
					(mid 1.930273 -59.837574)
					(end 1.54686 -60.221114)
				)
				(arc
					(start 1.54686 -61.178694)
					(mid 1.9304 -61.562234)
					(end 2.31394 -61.178694)
				)
			)
		)
		(polygon
			(pts
				(arc
					(start 84.348828 -59.595258)
					(mid 84.354625 -59.108766)
					(end 83.868006 -59.106054)
				)
				(arc
					(start 83.309968 -59.661806)
					(mid 83.308952 -60.146946)
					(end 83.794092 -60.147962)
				)
			)
		)
		(polygon
			(pts
				(arc
					(start 10.009886 -59.171078)
					(mid 9.615678 -58.798714)
					(end 9.243314 -59.192922)
				)
				(xy 9.240774 -59.192922) (xy 9.266174 -60.081668) (xy 9.266428 -60.081922)
				(arc
					(start 9.268714 -60.081922)
					(mid 9.662922 -60.454286)
					(end 10.035286 -60.060078)
				)
				(xy 10.037826 -60.060078) (xy 10.012426 -59.171078)
			)
		)
		(polygon
			(pts
				(arc
					(start 3.7084 -58.706766)
					(mid 3.32486 -58.323226)
					(end 2.94132 -58.706766)
				)
				(arc
					(start 2.94132 -59.6646)
					(mid 3.324987 -60.047886)
					(end 3.7084 -59.664346)
				)
			)
		)
		(polygon
			(pts
				(arc
					(start 10.01014 -57.403746)
					(mid 9.626473 -57.02046)
					(end 9.24306 -57.404)
				)
				(arc
					(start 9.24306 -58.293)
					(mid 9.6266 -58.67654)
					(end 10.01014 -58.293)
				)
			)
		)
		(polygon
			(pts
				(arc
					(start 10.01014 -55.625746)
					(mid 9.626473 -55.24246)
					(end 9.24306 -55.626)
				)
				(arc
					(start 9.24306 -56.515)
					(mid 9.6266 -56.89854)
					(end 10.01014 -56.515)
				)
			)
		)
		(polygon
			(pts
				(arc
					(start 83.701636 -55.68061)
					(mid 83.668625 -55.193446)
					(end 83.18119 -55.226204)
				)
				(arc
					(start 82.803746 -55.65902)
					(mid 82.83702 -56.146446)
					(end 83.324446 -56.113172)
				)
			)
		)
		(polygon
			(pts
				(arc
					(start 91.580462 -55.242714)
					(mid 91.688158 -54.76621)
					(end 91.211654 -54.658514)
				)
				(xy 91.210384 -54.656482) (xy 90.73769 -54.954678) (xy 90.73769 -54.954932)
				(arc
					(start 90.73896 -54.956964)
					(mid 90.631264 -55.433468)
					(end 91.107768 -55.541164)
				)
				(xy 91.109038 -55.543196) (xy 91.581732 -55.244746)
			)
		)
		(polygon
			(pts
				(arc
					(start 86.030054 -54.801008)
					(mid 85.689948 -54.450234)
					(end 85.339174 -54.79034)
				)
				(arc
					(start 85.330538 -55.356506)
					(mid 85.670517 -55.707536)
					(end 86.021418 -55.367428)
				)
			)
		)
		(polygon
			(pts
				(arc
					(start 87.528908 -54.284118)
					(mid 87.190326 -53.93182)
					(end 86.838028 -54.270402)
				)
				(arc
					(start 86.826852 -54.834028)
					(mid 87.165307 -55.186583)
					(end 87.517732 -54.847998)
				)
			)
		)
		(polygon
			(pts
				(arc
					(start 80.9117 -54.1274)
					(mid 80.5688 -53.7845)
					(end 80.2259 -54.1274)
				)
				(arc
					(start 80.2259 -54.686454)
					(mid 80.568927 -55.0291)
					(end 80.9117 -54.6862)
				)
			)
		)
		(polygon
			(pts
				(arc
					(start 84.586572 -54.022498)
					(mid 84.247863 -53.670456)
					(end 83.895692 -54.009036)
				)
				(arc
					(start 83.885024 -54.567836)
					(mid 84.22386 -54.91988)
					(end 84.575904 -54.581044)
				)
			)
		)
		(polygon
			(pts
				(arc
					(start 10.2616 -53.66766)
					(mid 10.2616 -54.38394)
					(end 10.2616 -53.66766)
				)
			)
		)
		(polygon
			(pts
				(arc
					(start 90.156792 -53.552598)
					(mid 89.845768 -53.175928)
					(end 89.46896 -53.486812)
				)
				(arc
					(start 89.415874 -54.043326)
					(mid 89.727024 -54.420008)
					(end 90.103706 -54.108858)
				)
			)
		)
		(polygon
			(pts
				(arc
					(start 88.633808 -53.399182)
					(mid 88.277446 -53.065172)
					(end 87.943436 -53.421534)
				)
				(xy 87.940896 -53.421534) (xy 87.95893 -53.98008)
				(arc
					(start 87.96147 -53.98008)
					(mid 88.317832 -54.31409)
					(end 88.651842 -53.957728)
				)
				(xy 88.654382 -53.957728) (xy 88.636348 -53.399436) (xy 88.636094 -53.399182)
			)
		)
		(polygon
			(pts
				(arc
					(start 91.403424 -53.414168)
					(mid 91.076653 -53.050941)
					(end 90.71356 -53.377846)
				)
				(xy 90.71102 -53.377592) (xy 90.681556 -53.93817)
				(arc
					(start 90.684096 -53.938424)
					(mid 91.010994 -54.30139)
					(end 91.37396 -53.974492)
				)
				(xy 91.3765 -53.974746) (xy 91.405964 -53.414422) (xy 91.40571 -53.414168)
			)
		)
		(polygon
			(pts
				(arc
					(start 86.443058 -53.20792)
					(mid 86.103968 -52.85613)
					(end 85.752178 -53.19522)
				)
				(arc
					(start 85.741764 -53.758592)
					(mid 86.080727 -54.110638)
					(end 86.432644 -53.771546)
				)
			)
		)
		(polygon
			(pts
				(arc
					(start 82.0293 -53.0098)
					(mid 81.6864 -52.6669)
					(end 81.3435 -53.0098)
				)
				(arc
					(start 81.3435 -53.594254)
					(mid 81.686527 -53.9369)
					(end 82.0293 -53.594)
				)
			)
		)
		(polygon
			(pts
				(arc
					(start 9.2202 -52.907946)
					(mid 8.839073 -52.5272)
					(end 8.4582 -52.9082)
				)
				(arc
					(start 8.4582 -53.8988)
					(mid 8.8392 -54.2798)
					(end 9.2202 -53.8988)
				)
			)
		)
		(polygon
			(pts
				(arc
					(start 10.2616 -52.42306)
					(mid 10.2616 -53.13934)
					(end 10.2616 -52.42306)
				)
			)
		)
		(polygon
			(pts
				(arc
					(start 9.5504 -51.38166)
					(mid 9.5504 -52.09794)
					(end 9.5504 -51.38166)
				)
			)
		)
		(polygon
			(pts
				(arc
					(start 8.509 -50.621946)
					(mid 8.127873 -50.2412)
					(end 7.747 -50.6222)
				)
				(arc
					(start 7.747 -51.6128)
					(mid 8.128 -51.9938)
					(end 8.509 -51.6128)
				)
			)
		)
		(polygon
			(pts
				(arc
					(start 9.5504 -50.13706)
					(mid 9.5504 -50.85334)
					(end 9.5504 -50.13706)
				)
			)
		)
		(polygon
			(pts
				(arc
					(start 13.55598 -47.66056)
					(mid 13.17244 -47.27702)
					(end 12.7889 -47.66056)
				)
				(arc
					(start 12.7889 -48.618394)
					(mid 13.172567 -49.00168)
					(end 13.55598 -48.61814)
				)
			)
		)
		(polygon
			(pts
				(arc
					(start 51.041554 -47.64278)
					(mid 50.663729 -47.253654)
					(end 50.274474 -47.63135)
				)
				(arc
					(start 50.262028 -48.49495)
					(mid 50.63998 -48.884078)
					(end 51.029108 -48.506126)
				)
			)
		)
		(polygon
			(pts
				(arc
					(start 15.082266 -47.21606)
					(mid 15.465806 -46.83252)
					(end 15.082266 -46.44898)
				)
				(arc
					(start 14.152626 -46.44898)
					(mid 13.76934 -46.832647)
					(end 14.15288 -47.21606)
				)
			)
		)
		(polygon
			(pts
				(arc
					(start 61.317378 -45.848016)
					(mid 60.910088 -45.489868)
					(end 60.551822 -45.897038)
				)
				(arc
					(start 60.607448 -46.75886)
					(mid 61.014864 -47.117)
					(end 61.373004 -46.709584)
				)
			)
		)
		(polygon
			(pts
				(xy 107.224068 -44.6786) (xy 107.199684 -44.666408) (xy 107.163362 -44.6786) (xy 98.742754 -44.6786)
				(xy 98.0186 -45.402754) (xy 98.0186 -50.355246) (xy 98.2726 -50.609246) (xy 98.2726 -56.905906)
				(xy 98.2345 -56.944006) (xy 98.2345 -57.101994) (xy 102.664006 -61.5315) (xy 119.047006 -61.5315)
				(xy 119.301006 -61.7855) (xy 135.557006 -61.7855) (xy 136.9695 -63.197994) (xy 136.9695 -64.848994)
				(xy 142.415006 -70.2945) (xy 166.575994 -70.2945) (xy 166.6875 -70.182994) (xy 168.9735 -67.896994)
				(xy 168.9735 -65.961006) (xy 166.5605 -63.548006) (xy 166.5605 -60.119006) (xy 151.589994 -45.1485)
				(xy 117.650006 -45.1485) (xy 117.5385 -45.260006) (xy 117.5385 -45.3136) (xy 109.156246 -45.3136)
				(xy 108.7374 -44.894754) (xy 108.648246 -44.8056) (xy 107.478068 -44.8056) (xy 107.27817 -44.705778)
				(xy 107.251246 -44.6786)
			)
		)
		(polygon
			(pts
				(arc
					(start 43.41114 -44.5389)
					(mid 43.79468 -44.15536)
					(end 43.41114 -43.77182)
				)
				(arc
					(start 42.453306 -43.77182)
					(mid 42.07002 -44.155487)
					(end 42.45356 -44.5389)
				)
			)
		)
		(polygon
			(pts
				(xy 8.543798 -43.688) (xy 5.114798 -43.688) (xy 5.114798 -49.276) (xy 8.543798 -49.276)
			)
		)
		(polygon
			(pts
				(arc
					(start 45.007276 -43.53306)
					(mid 44.615103 -43.907837)
					(end 44.98975 -44.30014)
				)
				(arc
					(start 45.947838 -44.32173)
					(mid 46.340014 -43.946826)
					(end 45.96511 -43.55465)
				)
			)
		)
		(polygon
			(pts
				(arc
					(start 49.692052 -37.74567)
					(mid 49.15027 -37.771832)
					(end 49.176432 -38.313614)
				)
				(arc
					(start 49.81321 -38.892226)
					(mid 50.356403 -38.869633)
					(end 50.33137 -38.326568)
				)
			)
		)
		(polygon
			(pts
				(arc
					(start 60.04179 -35.379406)
					(mid 59.658123 -34.99612)
					(end 59.27471 -35.37966)
				)
				(arc
					(start 59.27471 -36.33724)
					(mid 59.65825 -36.72078)
					(end 60.04179 -36.33724)
				)
			)
		)
		(polygon
			(pts
				(arc
					(start 53.479954 -35.696652)
					(mid 53.862478 -35.311969)
					(end 53.477668 -34.929572)
				)
				(arc
					(start 52.52339 -34.93262)
					(mid 52.14112 -35.31743)
					(end 52.52593 -35.6997)
				)
			)
		)
		(polygon
			(pts
				(arc
					(start 52.16652 -34.47034)
					(mid 52.55006 -34.0868)
					(end 52.16652 -33.70326)
				)
				(arc
					(start 51.282092 -33.70326)
					(mid 50.898806 -34.086927)
					(end 51.282346 -34.47034)
				)
			)
		)
		(polygon
			(pts
				(arc
					(start 78.12024 -30.823154)
					(mid 77.762614 -31.150687)
					(end 78.090014 -31.508446)
				)
				(arc
					(start 78.648814 -31.53283)
					(mid 79.006446 -31.20517)
					(end 78.678786 -30.847538)
				)
			)
		)
		(polygon
			(pts
				(arc
					(start 78.538832 -30.2387)
					(mid 78.878175 -29.892117)
					(end 78.531466 -29.5529)
				)
				(arc
					(start 77.972666 -29.55925)
					(mid 77.633576 -29.90596)
					(end 77.980286 -30.24505)
				)
			)
		)
		(polygon
			(pts
				(arc
					(start 38.65372 -29.336746)
					(mid 38.270053 -28.95346)
					(end 37.88664 -29.337)
				)
				(arc
					(start 37.88664 -30.2006)
					(mid 38.27018 -30.58414)
					(end 38.65372 -30.2006)
				)
			)
		)
		(polygon
			(pts
				(arc
					(start 53.535326 -28.897834)
					(mid 53.151786 -28.514294)
					(end 52.768246 -28.897834)
				)
				(arc
					(start 52.768246 -29.827474)
					(mid 53.151913 -30.21076)
					(end 53.535326 -29.82722)
				)
			)
		)
		(polygon
			(pts
				(arc
					(start 69.52234 -27.52344)
					(mid 69.140705 -27.138123)
					(end 68.75526 -27.51963)
				)
				(arc
					(start 68.75145 -28.403296)
					(mid 69.133212 -28.788614)
					(end 69.51853 -28.406852)
				)
			)
		)
		(polygon
			(pts
				(arc
					(start 50.25263 -20.79498)
					(mid 50.63617 -20.41144)
					(end 50.25263 -20.0279)
				)
				(arc
					(start 49.294796 -20.0279)
					(mid 48.91151 -20.411567)
					(end 49.29505 -20.79498)
				)
			)
		)
		(polygon
			(pts
				(arc
					(start 21.053044 -15.872206)
					(mid 21.43633 -15.488539)
					(end 21.05279 -15.105126)
				)
				(arc
					(start 20.09521 -15.105126)
					(mid 19.71167 -15.488666)
					(end 20.09521 -15.872206)
				)
			)
		)
		(polygon
			(pts
				(arc
					(start 64.389 -15.0876)
					(mid 64.77 -14.7066)
					(end 64.389 -14.3256)
				)
				(arc
					(start 63.626746 -14.3256)
					(mid 63.246 -14.706727)
					(end 63.627 -15.0876)
				)
			)
		)
		(polygon
			(pts
				(arc
					(start 73.7108 -15.09014)
					(mid 74.09434 -14.7066)
					(end 73.7108 -14.32306)
				)
				(arc
					(start 72.846946 -14.32306)
					(mid 72.46366 -14.706727)
					(end 72.8472 -15.09014)
				)
			)
		)
		(polygon
			(pts
				(arc
					(start 66.548254 -15.0622)
					(mid 66.929 -14.681073)
					(end 66.548 -14.3002)
				)
				(arc
					(start 65.786 -14.3002)
					(mid 65.405 -14.6812)
					(end 65.786 -15.0622)
				)
			)
		)
		(polygon
			(pts
				(arc
					(start 68.834 -14.98854)
					(mid 69.21754 -14.605)
					(end 68.834 -14.22146)
				)
				(arc
					(start 68.071746 -14.22146)
					(mid 67.68846 -14.605127)
					(end 68.072 -14.98854)
				)
			)
		)
		(polygon
			(pts
				(arc
					(start 81.077054 -14.96314)
					(mid 81.46034 -14.579473)
					(end 81.0768 -14.19606)
				)
				(arc
					(start 80.2132 -14.19606)
					(mid 79.82966 -14.5796)
					(end 80.2132 -14.96314)
				)
			)
		)
		(polygon
			(pts
				(arc
					(start 78.2828 -14.96314)
					(mid 78.66634 -14.5796)
					(end 78.2828 -14.19606)
				)
				(arc
					(start 77.418946 -14.19606)
					(mid 77.03566 -14.579727)
					(end 77.4192 -14.96314)
				)
			)
		)
		(polygon
			(pts
				(arc
					(start 34.290254 -14.96314)
					(mid 34.67354 -14.579473)
					(end 34.29 -14.19606)
				)
				(arc
					(start 33.4264 -14.19606)
					(mid 33.04286 -14.5796)
					(end 33.4264 -14.96314)
				)
			)
		)
		(polygon
			(pts
				(arc
					(start 30.277054 -14.96314)
					(mid 30.66034 -14.579473)
					(end 30.2768 -14.19606)
				)
				(arc
					(start 29.4132 -14.19606)
					(mid 29.02966 -14.5796)
					(end 29.4132 -14.96314)
				)
			)
		)
		(polygon
			(pts
				(arc
					(start 83.1596 -14.32814)
					(mid 83.54314 -13.9446)
					(end 83.1596 -13.56106)
				)
				(arc
					(start 82.295746 -13.56106)
					(mid 81.91246 -13.944727)
					(end 82.296 -14.32814)
				)
			)
		)
		(polygon
			(pts
				(arc
					(start 53.010054 -14.32814)
					(mid 53.39334 -13.944473)
					(end 53.0098 -13.56106)
				)
				(arc
					(start 52.1462 -13.56106)
					(mid 51.76266 -13.9446)
					(end 52.1462 -14.32814)
				)
			)
		)
		(polygon
			(pts
				(arc
					(start 50.2158 -14.1986)
					(mid 50.5968 -13.8176)
					(end 50.2158 -13.4366)
				)
				(arc
					(start 49.453546 -13.4366)
					(mid 49.0728 -13.817727)
					(end 49.4538 -14.1986)
				)
			)
		)
		(polygon
			(pts
				(arc
					(start 46.177454 -14.1986)
					(mid 46.5582 -13.817473)
					(end 46.1772 -13.4366)
				)
				(arc
					(start 45.466 -13.4366)
					(mid 45.085 -13.8176)
					(end 45.466 -14.1986)
				)
			)
		)
		(polygon
			(pts
				(arc
					(start 42.281856 -14.20114)
					(mid 42.665142 -13.817473)
					(end 42.281602 -13.43406)
				)
				(arc
					(start 41.418002 -13.43406)
					(mid 41.034462 -13.8176)
					(end 41.418002 -14.20114)
				)
			)
		)
		(polygon
			(pts
				(arc
					(start 38.281864 -14.20114)
					(mid 38.66515 -13.817473)
					(end 38.28161 -13.43406)
				)
				(arc
					(start 37.41801 -13.43406)
					(mid 37.03447 -13.8176)
					(end 37.41801 -14.20114)
				)
			)
		)
		(polygon
			(pts
				(arc
					(start 26.276554 -14.20114)
					(mid 26.65984 -13.817473)
					(end 26.2763 -13.43406)
				)
				(arc
					(start 25.4127 -13.43406)
					(mid 25.02916 -13.8176)
					(end 25.4127 -14.20114)
				)
			)
		)
		(polygon
			(pts
				(arc
					(start 22.5298 -14.20114)
					(mid 22.91334 -13.8176)
					(end 22.5298 -13.43406)
				)
				(arc
					(start 21.665946 -13.43406)
					(mid 21.28266 -13.817727)
					(end 21.6662 -14.20114)
				)
			)
		)
		(polygon
			(pts
				(arc
					(start 48.184054 -14.1732)
					(mid 48.5648 -13.792073)
					(end 48.1838 -13.4112)
				)
				(arc
					(start 47.46371 -13.4112)
					(mid 47.08271 -13.7922)
					(end 47.46371 -14.1732)
				)
			)
		)
		(polygon
			(pts
				(arc
					(start 44.211494 -12.98194)
					(mid 44.59478 -12.598273)
					(end 44.21124 -12.21486)
				)
				(arc
					(start 43.25366 -12.21486)
					(mid 42.87012 -12.5984)
					(end 43.25366 -12.98194)
				)
			)
		)
		(polygon
			(pts
				(arc
					(start 40.40124 -12.73048)
					(mid 40.78478 -12.34694)
					(end 40.40124 -11.9634)
				)
				(arc
					(start 39.443406 -11.9634)
					(mid 39.06012 -12.347067)
					(end 39.44366 -12.73048)
				)
			)
		)
		(polygon
			(pts
				(arc
					(start 59.997594 -11.320018)
					(mid 60.381134 -10.936478)
					(end 59.997594 -10.552938)
				)
				(arc
					(start 59.07786 -10.552938)
					(mid 58.694574 -10.936605)
					(end 59.078114 -11.320018)
				)
			)
		)
		(polygon
			(pts
				(arc
					(start 84.310474 -10.79627)
					(mid 84.694014 -10.41273)
					(end 84.310474 -10.02919)
				)
				(arc
					(start 83.388708 -10.02919)
					(mid 83.005422 -10.412857)
					(end 83.388962 -10.79627)
				)
			)
		)
		(polygon
			(pts
				(arc
					(start 80.328516 -10.7188)
					(mid 80.712056 -10.33526)
					(end 80.328516 -9.95172)
				)
				(arc
					(start 79.370682 -9.95172)
					(mid 78.987396 -10.335387)
					(end 79.370936 -10.7188)
				)
			)
		)
		(polygon
			(pts
				(arc
					(start 76.328524 -10.668)
					(mid 76.712064 -10.28446)
					(end 76.328524 -9.90092)
				)
				(arc
					(start 75.37069 -9.90092)
					(mid 74.987404 -10.284587)
					(end 75.370944 -10.668)
				)
			)
		)
		(polygon
			(pts
				(arc
					(start 72.328532 -10.668)
					(mid 72.712072 -10.28446)
					(end 72.328532 -9.90092)
				)
				(arc
					(start 71.370698 -9.90092)
					(mid 70.987412 -10.284587)
					(end 71.370952 -10.668)
				)
			)
		)
		(polygon
			(pts
				(arc
					(start 68.303394 -10.668)
					(mid 68.68668 -10.284333)
					(end 68.30314 -9.90092)
				)
				(arc
					(start 67.34556 -9.90092)
					(mid 66.96202 -10.28446)
					(end 67.34556 -10.668)
				)
			)
		)
		(polygon
			(pts
				(arc
					(start 50.310542 -10.64387)
					(mid 50.694082 -10.26033)
					(end 50.310542 -9.87679)
				)
				(arc
					(start 49.388776 -9.87679)
					(mid 49.00549 -10.260457)
					(end 49.38903 -10.64387)
				)
			)
		)
		(polygon
			(pts
				(arc
					(start 62.328044 -10.634218)
					(mid 62.71133 -10.250551)
					(end 62.32779 -9.867138)
				)
				(arc
					(start 61.40831 -9.867138)
					(mid 61.02477 -10.250678)
					(end 61.40831 -10.634218)
				)
			)
		)
		(polygon
			(pts
				(arc
					(start 48.327818 -10.634218)
					(mid 48.711358 -10.250678)
					(end 48.327818 -9.867138)
				)
				(arc
					(start 47.408084 -9.867138)
					(mid 47.024798 -10.250805)
					(end 47.408338 -10.634218)
				)
			)
		)
		(polygon
			(pts
				(arc
					(start 44.327826 -10.634218)
					(mid 44.711366 -10.250678)
					(end 44.327826 -9.867138)
				)
				(arc
					(start 43.408092 -9.867138)
					(mid 43.024806 -10.250805)
					(end 43.408346 -10.634218)
				)
			)
		)
		(polygon
			(pts
				(arc
					(start 40.327834 -10.634218)
					(mid 40.711374 -10.250678)
					(end 40.327834 -9.867138)
				)
				(arc
					(start 39.4081 -9.867138)
					(mid 39.024814 -10.250805)
					(end 39.408354 -10.634218)
				)
			)
		)
		(polygon
			(pts
				(arc
					(start 36.328096 -10.634218)
					(mid 36.711382 -10.250551)
					(end 36.327842 -9.867138)
				)
				(arc
					(start 35.408362 -9.867138)
					(mid 35.024822 -10.250678)
					(end 35.408362 -10.634218)
				)
			)
		)
		(polygon
			(pts
				(arc
					(start 32.328104 -10.634218)
					(mid 32.71139 -10.250551)
					(end 32.32785 -9.867138)
				)
				(arc
					(start 31.40837 -9.867138)
					(mid 31.02483 -10.250678)
					(end 31.40837 -10.634218)
				)
			)
		)
		(polygon
			(pts
				(arc
					(start 28.328112 -10.634218)
					(mid 28.711398 -10.250551)
					(end 28.327858 -9.867138)
				)
				(arc
					(start 27.408378 -9.867138)
					(mid 27.024838 -10.250678)
					(end 27.408378 -10.634218)
				)
			)
		)
		(polygon
			(pts
				(arc
					(start 24.327866 -10.634218)
					(mid 24.711406 -10.250678)
					(end 24.327866 -9.867138)
				)
				(arc
					(start 23.408132 -9.867138)
					(mid 23.024846 -10.250805)
					(end 23.408386 -10.634218)
				)
			)
		)
		(polygon
			(pts
				(arc
					(start 20.327874 -10.634218)
					(mid 20.711414 -10.250678)
					(end 20.327874 -9.867138)
				)
				(arc
					(start 19.40814 -9.867138)
					(mid 19.024854 -10.250805)
					(end 19.408394 -10.634218)
				)
			)
		)
		(polygon
			(pts
				(xy 169.242994 -1.9685) (xy 152.321006 -1.9685) (xy 144.701006 -9.5885) (xy 135.303006 -9.5885)
				(xy 131.239006 -13.6525) (xy 114.094006 -13.6525) (xy 108.252006 -19.4945) (xy 100.786438 -19.4945)
				(xy 100.783644 -19.49196) (xy 100.707952 -19.4945) (xy 100.632006 -19.4945) (xy 100.629466 -19.49704)
				(xy 100.62591 -19.49704) (xy 100.574094 -19.552412) (xy 100.5205 -19.606006) (xy 100.5205 -19.609562)
				(xy 98.61296 -21.644356) (xy 98.61804 -21.80209) (xy 98.6536 -21.835364) (xy 98.6536 -24.447754)
				(xy 97.2566 -25.844754) (xy 97.2566 -32.067246) (xy 97.599754 -32.4104) (xy 99.123754 -32.4104)
				(xy 100.520754 -33.8074) (xy 104.076246 -33.8074) (xy 104.1654 -33.718246) (xy 104.711246 -33.1724)
				(xy 109.718602 -33.1724) (xy 109.771688 -33.179004) (xy 109.780324 -33.1724) (xy 109.791246 -33.1724)
				(xy 109.829092 -33.134554) (xy 110.008924 -32.9946) (xy 110.731554 -32.9946) (xy 111.036354 -33.2994)
				(xy 112.585246 -33.2994) (xy 114.744246 -31.1404) (xy 117.738906 -31.1404) (xy 117.777006 -31.1785)
				(xy 117.934994 -31.1785) (xy 119.077994 -30.0355) (xy 158.447994 -30.0355) (xy 173.1645 -15.318994)
				(xy 173.1645 -11.351006) (xy 172.5295 -10.716006) (xy 172.5295 -7.795006) (xy 170.8785 -6.144006)
				(xy 170.8785 -4.366006) (xy 170.1165 -3.604006) (xy 170.1165 -2.842006)
			)
		)
	)
	(zone
		(net "PV_VDDR")
		(layer "In8.Cu")
		(hatch none 0.5)
		(connect_pads
			(clearance 0.5)
		)
		(min_thickness 0.25)
		(fill yes
			(thermal_gap 0.5)
			(thermal_bridge_width 0.5)
			(island_removal_mode 0)
		)
		(polygon
			(pts
				(xy 152.478994 -2.3495) (xy 144.858994 -9.9695) (xy 135.460994 -9.9695) (xy 131.5085 -13.921994)
				(xy 131.396994 -14.0335) (xy 114.251994 -14.0335) (xy 108.409994 -19.8755) (xy 100.79355 -19.8755)
				(xy 98.9584 -21.833078) (xy 98.9584 -24.574246) (xy 97.5614 -25.971246) (xy 97.5614 -31.940754)
				(xy 97.726246 -32.1056) (xy 99.250246 -32.1056) (xy 100.647246 -33.5026) (xy 103.949754 -33.5026)
				(xy 104.584754 -32.8676) (xy 109.675676 -32.8676) (xy 109.855508 -32.727646) (xy 109.893354 -32.6898)
				(xy 109.904276 -32.6898) (xy 109.912912 -32.683196) (xy 109.965998 -32.6898) (xy 110.858046 -32.6898)
				(xy 111.162846 -32.9946) (xy 112.458754 -32.9946) (xy 114.617754 -30.8356) (xy 117.738906 -30.8356)
				(xy 118.920006 -29.6545) (xy 158.290006 -29.6545) (xy 163.370514 -24.574246) (xy 172.7835 -15.161006)
				(xy 172.7835 -11.508994) (xy 172.1485 -10.873994) (xy 172.1485 -7.952994) (xy 170.4975 -6.301994)
				(xy 170.4975 -4.523994) (xy 169.7355 -3.761994) (xy 169.7355 -2.999994) (xy 169.085006 -2.3495)
			)
		)
	)
	(zone
		(net "PV_VDDR")
		(layer "In8.Cu")
		(hatch none 0.5)
		(connect_pads
			(clearance 0.5)
		)
		(min_thickness 0.25)
		(fill yes
			(thermal_gap 0.5)
			(thermal_bridge_width 0.5)
			(island_removal_mode 0)
		)
		(polygon
			(pts
				(xy 98.869246 -44.9834) (xy 98.3234 -45.529246) (xy 98.3234 -50.228754) (xy 98.5774 -50.482754)
				(xy 98.5774 -56.905906) (xy 102.821994 -61.1505) (xy 119.204994 -61.1505) (xy 119.458994 -61.4045)
				(xy 135.714994 -61.4045) (xy 137.3505 -63.040006) (xy 137.3505 -64.691006) (xy 142.572994 -69.9135)
				(xy 166.418006 -69.9135) (xy 168.5925 -67.739006) (xy 168.5925 -66.118994) (xy 166.1795 -63.705994)
				(xy 166.1795 -60.276994) (xy 156.385514 -50.482754) (xy 151.432006 -45.5295) (xy 117.754146 -45.5295)
				(xy 117.665246 -45.6184) (xy 109.029754 -45.6184) (xy 108.9406 -45.529246) (xy 108.521754 -45.1104)
				(xy 107.466638 -45.1104) (xy 107.430316 -45.122592) (xy 107.405932 -45.1104) (xy 107.378754 -45.1104)
				(xy 107.35183 -45.083222) (xy 107.151932 -44.9834)
			)
		)
	)
	(zone
		(layer "Cmts.User")
		(hatch none 0.5)
		(connect_pads
			(clearance 0)
		)
		(min_thickness 0.25)
		(keepout
			(tracks allowed)
			(vias allowed)
			(pads allowed)
			(copperpour allowed)
			(footprints allowed)
		)
		(placement
			(enabled no)
			(sheetname "")
		)
		(fill
			(thermal_gap 0.5)
			(thermal_bridge_width 0.5)
			(island_removal_mode 0)
		)
		(polygon
			(pts
				(xy 80.772 -10.922) (xy 78.994 -10.922) (xy 78.994 -9.906) (xy 80.772 -9.906)
			)
		)
	)
	(zone
		(layer "Cmts.User")
		(hatch none 0.5)
		(connect_pads
			(clearance 0)
		)
		(min_thickness 0.25)
		(keepout
			(tracks allowed)
			(vias allowed)
			(pads allowed)
			(copperpour allowed)
			(footprints allowed)
		)
		(placement
			(enabled no)
			(sheetname "")
		)
		(fill
			(thermal_gap 0.5)
			(thermal_bridge_width 0.5)
			(island_removal_mode 0)
		)
		(polygon
			(pts
				(xy 7.62 -52.0446) (xy 7.62 -50.2666) (xy 10.5664 -50.2666) (xy 10.5664 -52.0446)
			)
		)
	)
	(zone
		(layer "Cmts.User")
		(hatch none 0.5)
		(connect_pads
			(clearance 0)
		)
		(min_thickness 0.25)
		(keepout
			(tracks allowed)
			(vias allowed)
			(pads allowed)
			(copperpour allowed)
			(footprints allowed)
		)
		(placement
			(enabled no)
			(sheetname "")
		)
		(fill
			(thermal_gap 0.5)
			(thermal_bridge_width 0.5)
			(island_removal_mode 0)
		)
		(polygon
			(pts
				(xy 52.578 -34.544) (xy 50.8 -34.544) (xy 50.8 -33.528) (xy 52.578 -33.528)
			)
		)
	)
	(zone
		(layer "Cmts.User")
		(hatch none 0.5)
		(connect_pads
			(clearance 0)
		)
		(min_thickness 0.25)
		(keepout
			(tracks allowed)
			(vias allowed)
			(pads allowed)
			(copperpour allowed)
			(footprints allowed)
		)
		(placement
			(enabled no)
			(sheetname "")
		)
		(fill
			(thermal_gap 0.5)
			(thermal_bridge_width 0.5)
			(island_removal_mode 0)
		)
		(polygon
			(pts
				(xy 1.397 -64.643) (xy 1.397 -62.865) (xy 2.413 -62.865) (xy 2.413 -64.643)
			)
		)
	)
	(zone
		(layer "Cmts.User")
		(hatch none 0.5)
		(connect_pads
			(clearance 0)
		)
		(min_thickness 0.25)
		(keepout
			(tracks allowed)
			(vias allowed)
			(pads allowed)
			(copperpour allowed)
			(footprints allowed)
		)
		(placement
			(enabled no)
			(sheetname "")
		)
		(fill
			(thermal_gap 0.5)
			(thermal_bridge_width 0.5)
			(island_removal_mode 0)
		)
		(polygon
			(pts
				(xy 60.486544 -11.474196) (xy 58.708544 -11.474196) (xy 58.708544 -10.458196) (xy 60.486544 -10.458196)
			)
		)
	)
	(zone
		(layer "Cmts.User")
		(hatch none 0.5)
		(connect_pads
			(clearance 0)
		)
		(min_thickness 0.25)
		(keepout
			(tracks allowed)
			(vias allowed)
			(pads allowed)
			(copperpour allowed)
			(footprints allowed)
		)
		(placement
			(enabled no)
			(sheetname "")
		)
		(fill
			(thermal_gap 0.5)
			(thermal_bridge_width 0.5)
			(island_removal_mode 0)
		)
		(polygon
			(pts
				(xy 83.693 -14.478) (xy 81.915 -14.478) (xy 81.915 -13.462) (xy 83.693 -13.462)
			)
		)
	)
	(zone
		(layer "Cmts.User")
		(hatch none 0.5)
		(connect_pads
			(clearance 0)
		)
		(min_thickness 0.25)
		(keepout
			(tracks allowed)
			(vias allowed)
			(pads allowed)
			(copperpour allowed)
			(footprints allowed)
		)
		(placement
			(enabled no)
			(sheetname "")
		)
		(fill
			(thermal_gap 0.5)
			(thermal_bridge_width 0.5)
			(island_removal_mode 0)
		)
		(polygon
			(pts
				(xy 43.815 -44.704) (xy 42.037 -44.704) (xy 42.037 -43.688) (xy 43.815 -43.688)
			)
		)
	)
	(zone
		(layer "Cmts.User")
		(hatch none 0.5)
		(connect_pads
			(clearance 0)
		)
		(min_thickness 0.25)
		(keepout
			(tracks allowed)
			(vias allowed)
			(pads allowed)
			(copperpour allowed)
			(footprints allowed)
		)
		(placement
			(enabled no)
			(sheetname "")
		)
		(fill
			(thermal_gap 0.5)
			(thermal_bridge_width 0.5)
			(island_removal_mode 0)
		)
		(polygon
			(pts
				(xy 46.355 -44.45) (xy 44.577 -44.45) (xy 44.577 -43.434) (xy 46.355 -43.434)
			)
		)
	)
	(zone
		(layer "Cmts.User")
		(hatch none 0.5)
		(connect_pads
			(clearance 0)
		)
		(min_thickness 0.25)
		(keepout
			(tracks allowed)
			(vias allowed)
			(pads allowed)
			(copperpour allowed)
			(footprints allowed)
		)
		(placement
			(enabled no)
			(sheetname "")
		)
		(fill
			(thermal_gap 0.5)
			(thermal_bridge_width 0.5)
			(island_removal_mode 0)
		)
		(polygon
			(pts
				(xy 68.58 -28.829) (xy 68.58 -27.051) (xy 69.596 -27.051) (xy 69.596 -28.829)
			)
		)
	)
	(zone
		(layer "Cmts.User")
		(hatch none 0.5)
		(connect_pads
			(clearance 0)
		)
		(min_thickness 0.25)
		(keepout
			(tracks allowed)
			(vias allowed)
			(pads allowed)
			(copperpour allowed)
			(footprints allowed)
		)
		(placement
			(enabled no)
			(sheetname "")
		)
		(fill
			(thermal_gap 0.5)
			(thermal_bridge_width 0.5)
			(island_removal_mode 0)
		)
		(polygon
			(pts
				(xy 142.5956 -48.1584) (xy 142.5956 -44.2214) (xy 151.4983 -44.2214) (xy 151.4983 -48.1584)
			)
		)
	)
	(zone
		(layer "Cmts.User")
		(hatch none 0.5)
		(connect_pads
			(clearance 0)
		)
		(min_thickness 0.25)
		(keepout
			(tracks allowed)
			(vias allowed)
			(pads allowed)
			(copperpour allowed)
			(footprints allowed)
		)
		(placement
			(enabled no)
			(sheetname "")
		)
		(fill
			(thermal_gap 0.5)
			(thermal_bridge_width 0.5)
			(island_removal_mode 0)
		)
		(polygon
			(pts
				(xy 42.672 -14.351) (xy 40.894 -14.351) (xy 40.894 -13.335) (xy 42.672 -13.335)
			)
		)
	)
	(zone
		(layer "Cmts.User")
		(hatch none 0.5)
		(connect_pads
			(clearance 0)
		)
		(min_thickness 0.25)
		(keepout
			(tracks allowed)
			(vias allowed)
			(pads allowed)
			(copperpour allowed)
			(footprints allowed)
		)
		(placement
			(enabled no)
			(sheetname "")
		)
		(fill
			(thermal_gap 0.5)
			(thermal_bridge_width 0.5)
			(island_removal_mode 0)
		)
		(polygon
			(pts
				(xy 32.766 -10.795) (xy 30.988 -10.795) (xy 30.988 -9.779) (xy 32.766 -9.779)
			)
		)
	)
	(zone
		(layer "Cmts.User")
		(hatch none 0.5)
		(connect_pads
			(clearance 0)
		)
		(min_thickness 0.25)
		(keepout
			(tracks allowed)
			(vias allowed)
			(pads allowed)
			(copperpour allowed)
			(footprints allowed)
		)
		(placement
			(enabled no)
			(sheetname "")
		)
		(fill
			(thermal_gap 0.5)
			(thermal_bridge_width 0.5)
			(island_removal_mode 0)
		)
		(polygon
			(pts
				(xy 81.534 -15.113) (xy 79.756 -15.113) (xy 79.756 -14.097) (xy 81.534 -14.097)
			)
		)
	)
	(zone
		(layer "Cmts.User")
		(hatch none 0.5)
		(connect_pads
			(clearance 0)
		)
		(min_thickness 0.25)
		(keepout
			(tracks allowed)
			(vias allowed)
			(pads allowed)
			(copperpour allowed)
			(footprints allowed)
		)
		(placement
			(enabled no)
			(sheetname "")
		)
		(fill
			(thermal_gap 0.5)
			(thermal_bridge_width 0.5)
			(island_removal_mode 0)
		)
		(polygon
			(pts
				(xy 38.735 -14.351) (xy 36.957 -14.351) (xy 36.957 -13.335) (xy 38.735 -13.335)
			)
		)
	)
	(zone
		(layer "Cmts.User")
		(hatch none 0.5)
		(connect_pads
			(clearance 0)
		)
		(min_thickness 0.25)
		(keepout
			(tracks allowed)
			(vias allowed)
			(pads allowed)
			(copperpour allowed)
			(footprints allowed)
		)
		(placement
			(enabled no)
			(sheetname "")
		)
		(fill
			(thermal_gap 0.5)
			(thermal_bridge_width 0.5)
			(island_removal_mode 0)
		)
		(polygon
			(pts
				(xy 192.659 -0.509778) (xy 192.659 -12.193778) (xy 127.983234 -12.193778) (xy 127.983234 -0.509778)
			)
		)
	)
	(zone
		(layer "Cmts.User")
		(hatch none 0.5)
		(connect_pads
			(clearance 0)
		)
		(min_thickness 0.25)
		(keepout
			(tracks allowed)
			(vias allowed)
			(pads allowed)
			(copperpour allowed)
			(footprints allowed)
		)
		(placement
			(enabled no)
			(sheetname "")
		)
		(fill
			(thermal_gap 0.5)
			(thermal_bridge_width 0.5)
			(island_removal_mode 0)
		)
		(polygon
			(pts
				(xy 46.736 -14.224) (xy 44.958 -14.224) (xy 44.958 -13.208) (xy 46.736 -13.208)
			)
		)
	)
	(zone
		(layer "Cmts.User")
		(hatch none 0.5)
		(connect_pads
			(clearance 0)
		)
		(min_thickness 0.25)
		(keepout
			(tracks allowed)
			(vias allowed)
			(pads allowed)
			(copperpour allowed)
			(footprints allowed)
		)
		(placement
			(enabled no)
			(sheetname "")
		)
		(fill
			(thermal_gap 0.5)
			(thermal_bridge_width 0.5)
			(island_removal_mode 0)
		)
		(polygon
			(pts
				(xy 1.397 -67.564) (xy 1.397 -65.786) (xy 2.413 -65.786) (xy 2.413 -67.564)
			)
		)
	)
	(zone
		(layer "Cmts.User")
		(hatch none 0.5)
		(connect_pads
			(clearance 0)
		)
		(min_thickness 0.25)
		(keepout
			(tracks allowed)
			(vias allowed)
			(pads allowed)
			(copperpour allowed)
			(footprints allowed)
		)
		(placement
			(enabled no)
			(sheetname "")
		)
		(fill
			(thermal_gap 0.5)
			(thermal_bridge_width 0.5)
			(island_removal_mode 0)
		)
		(polygon
			(pts
				(xy 12.7 -49.022) (xy 12.7 -47.244) (xy 13.716 -47.244) (xy 13.716 -49.022)
			)
		)
	)
	(zone
		(layer "Cmts.User")
		(hatch none 0.5)
		(connect_pads
			(clearance 0)
		)
		(min_thickness 0.25)
		(keepout
			(tracks allowed)
			(vias allowed)
			(pads allowed)
			(copperpour allowed)
			(footprints allowed)
		)
		(placement
			(enabled no)
			(sheetname "")
		)
		(fill
			(thermal_gap 0.5)
			(thermal_bridge_width 0.5)
			(island_removal_mode 0)
		)
		(polygon
			(pts
				(xy 20.701 -10.795) (xy 18.923 -10.795) (xy 18.923 -9.779) (xy 20.701 -9.779)
			)
		)
	)
	(zone
		(layer "Cmts.User")
		(hatch none 0.5)
		(connect_pads
			(clearance 0)
		)
		(min_thickness 0.25)
		(keepout
			(tracks allowed)
			(vias allowed)
			(pads allowed)
			(copperpour allowed)
			(footprints allowed)
		)
		(placement
			(enabled no)
			(sheetname "")
		)
		(fill
			(thermal_gap 0.5)
			(thermal_bridge_width 0.5)
			(island_removal_mode 0)
		)
		(polygon
			(pts
				(xy 48.768 -10.668) (xy 46.99 -10.668) (xy 46.99 -9.652) (xy 48.768 -9.652)
			)
		)
	)
	(zone
		(layer "Cmts.User")
		(hatch none 0.5)
		(connect_pads
			(clearance 0)
		)
		(min_thickness 0.25)
		(keepout
			(tracks allowed)
			(vias allowed)
			(pads allowed)
			(copperpour allowed)
			(footprints allowed)
		)
		(placement
			(enabled no)
			(sheetname "")
		)
		(fill
			(thermal_gap 0.5)
			(thermal_bridge_width 0.5)
			(island_removal_mode 0)
		)
		(polygon
			(pts
				(xy 50.834544 -10.712196) (xy 49.056544 -10.712196) (xy 49.056544 -9.696196) (xy 50.834544 -9.696196)
			)
		)
	)
	(zone
		(layer "Cmts.User")
		(hatch none 0.5)
		(connect_pads
			(clearance 0)
		)
		(min_thickness 0.25)
		(keepout
			(tracks allowed)
			(vias allowed)
			(pads allowed)
			(copperpour allowed)
			(footprints allowed)
		)
		(placement
			(enabled no)
			(sheetname "")
		)
		(fill
			(thermal_gap 0.5)
			(thermal_bridge_width 0.5)
			(island_removal_mode 0)
		)
		(polygon
			(pts
				(xy 37.846 -30.607) (xy 37.846 -28.829) (xy 38.862 -28.829) (xy 38.862 -30.607)
			)
		)
	)
	(zone
		(layer "Cmts.User")
		(hatch none 0.5)
		(connect_pads
			(clearance 0)
		)
		(min_thickness 0.25)
		(keepout
			(tracks allowed)
			(vias allowed)
			(pads allowed)
			(copperpour allowed)
			(footprints allowed)
		)
		(placement
			(enabled no)
			(sheetname "")
		)
		(fill
			(thermal_gap 0.5)
			(thermal_bridge_width 0.5)
			(island_removal_mode 0)
		)
		(polygon
			(pts
				(xy 76.708 -10.795) (xy 74.93 -10.795) (xy 74.93 -9.779) (xy 76.708 -9.779)
			)
		)
	)
	(zone
		(layer "Cmts.User")
		(hatch none 0.5)
		(connect_pads
			(clearance 0)
		)
		(min_thickness 0.25)
		(keepout
			(tracks allowed)
			(vias allowed)
			(pads allowed)
			(copperpour allowed)
			(footprints allowed)
		)
		(placement
			(enabled no)
			(sheetname "")
		)
		(fill
			(thermal_gap 0.5)
			(thermal_bridge_width 0.5)
			(island_removal_mode 0)
		)
		(polygon
			(pts
				(xy 69.469 -15.113) (xy 63.119 -15.113) (xy 63.119 -14.097) (xy 69.469 -14.097)
			)
		)
	)
	(zone
		(layer "Cmts.User")
		(hatch none 0.5)
		(connect_pads
			(clearance 0)
		)
		(min_thickness 0.25)
		(keepout
			(tracks allowed)
			(vias allowed)
			(pads allowed)
			(copperpour allowed)
			(footprints allowed)
		)
		(placement
			(enabled no)
			(sheetname "")
		)
		(fill
			(thermal_gap 0.5)
			(thermal_bridge_width 0.5)
			(island_removal_mode 0)
		)
		(polygon
			(pts
				(xy 190.645034 -59.69) (xy 190.645034 -71.869808) (xy 125.476 -71.869808) (xy 125.476 -59.69)
			)
		)
	)
	(zone
		(layer "Cmts.User")
		(hatch none 0.5)
		(connect_pads
			(clearance 0)
		)
		(min_thickness 0.25)
		(keepout
			(tracks allowed)
			(vias allowed)
			(pads allowed)
			(copperpour allowed)
			(footprints allowed)
		)
		(placement
			(enabled no)
			(sheetname "")
		)
		(fill
			(thermal_gap 0.5)
			(thermal_bridge_width 0.5)
			(island_removal_mode 0)
		)
		(polygon
			(pts
				(xy 78.74 -15.113) (xy 76.962 -15.113) (xy 76.962 -14.097) (xy 78.74 -14.097)
			)
		)
	)
	(zone
		(layer "Cmts.User")
		(hatch none 0.5)
		(connect_pads
			(clearance 0)
		)
		(min_thickness 0.25)
		(keepout
			(tracks allowed)
			(vias allowed)
			(pads allowed)
			(copperpour allowed)
			(footprints allowed)
		)
		(placement
			(enabled no)
			(sheetname "")
		)
		(fill
			(thermal_gap 0.5)
			(thermal_bridge_width 0.5)
			(island_removal_mode 0)
		)
		(polygon
			(pts
				(xy 50.8 -14.351) (xy 49.022 -14.351) (xy 49.022 -13.335) (xy 50.8 -13.335)
			)
		)
	)
	(zone
		(layer "Cmts.User")
		(hatch none 0.5)
		(connect_pads
			(clearance 0)
		)
		(min_thickness 0.25)
		(keepout
			(tracks allowed)
			(vias allowed)
			(pads allowed)
			(copperpour allowed)
			(footprints allowed)
		)
		(placement
			(enabled no)
			(sheetname "")
		)
		(fill
			(thermal_gap 0.5)
			(thermal_bridge_width 0.5)
			(island_removal_mode 0)
		)
		(polygon
			(pts
				(xy 99.822 -4.191) (xy 99.822 -11.6078) (xy 14.605 -11.6078) (xy 14.605 -4.191)
			)
		)
	)
	(zone
		(layer "Cmts.User")
		(hatch none 0.5)
		(connect_pads
			(clearance 0)
		)
		(min_thickness 0.25)
		(keepout
			(tracks allowed)
			(vias allowed)
			(pads allowed)
			(copperpour allowed)
			(footprints allowed)
		)
		(placement
			(enabled no)
			(sheetname "")
		)
		(fill
			(thermal_gap 0.5)
			(thermal_bridge_width 0.5)
			(island_removal_mode 0)
		)
		(polygon
			(pts
				(xy 44.577 -13.081) (xy 42.799 -13.081) (xy 42.799 -12.065) (xy 44.577 -12.065)
			)
		)
	)
	(zone
		(layer "Cmts.User")
		(hatch none 0.5)
		(connect_pads
			(clearance 0)
		)
		(min_thickness 0.25)
		(keepout
			(tracks allowed)
			(vias allowed)
			(pads allowed)
			(copperpour allowed)
			(footprints allowed)
		)
		(placement
			(enabled no)
			(sheetname "")
		)
		(fill
			(thermal_gap 0.5)
			(thermal_bridge_width 0.5)
			(island_removal_mode 0)
		)
		(polygon
			(pts
				(xy 8.3312 -54.3306) (xy 8.3312 -52.5526) (xy 11.2776 -52.5526) (xy 11.2776 -54.3306)
			)
		)
	)
	(zone
		(layer "Cmts.User")
		(hatch none 0.5)
		(connect_pads
			(clearance 0)
		)
		(min_thickness 0.25)
		(keepout
			(tracks allowed)
			(vias allowed)
			(pads allowed)
			(copperpour allowed)
			(footprints allowed)
		)
		(placement
			(enabled no)
			(sheetname "")
		)
		(fill
			(thermal_gap 0.5)
			(thermal_bridge_width 0.5)
			(island_removal_mode 0)
		)
		(polygon
			(pts
				(xy 72.771 -10.795) (xy 70.993 -10.795) (xy 70.993 -9.779) (xy 72.771 -9.779)
			)
		)
	)
	(zone
		(layer "Cmts.User")
		(hatch none 0.5)
		(connect_pads
			(clearance 0)
		)
		(min_thickness 0.25)
		(keepout
			(tracks allowed)
			(vias allowed)
			(pads allowed)
			(copperpour allowed)
			(footprints allowed)
		)
		(placement
			(enabled no)
			(sheetname "")
		)
		(fill
			(thermal_gap 0.5)
			(thermal_bridge_width 0.5)
			(island_removal_mode 0)
		)
		(polygon
			(pts
				(xy 53.467 -14.478) (xy 51.689 -14.478) (xy 51.689 -13.462) (xy 53.467 -13.462)
			)
		)
	)
	(zone
		(layer "Cmts.User")
		(hatch none 0.5)
		(connect_pads
			(clearance 0)
		)
		(min_thickness 0.25)
		(keepout
			(tracks allowed)
			(vias allowed)
			(pads allowed)
			(copperpour allowed)
			(footprints allowed)
		)
		(placement
			(enabled no)
			(sheetname "")
		)
		(fill
			(thermal_gap 0.5)
			(thermal_bridge_width 0.5)
			(island_removal_mode 0)
		)
		(polygon
			(pts
				(xy 2.921 -66.04) (xy 2.921 -64.262) (xy 3.937 -64.262) (xy 3.937 -66.04)
			)
		)
	)
	(zone
		(layer "Cmts.User")
		(hatch none 0.5)
		(connect_pads
			(clearance 0)
		)
		(min_thickness 0.25)
		(keepout
			(tracks allowed)
			(vias allowed)
			(pads allowed)
			(copperpour allowed)
			(footprints allowed)
		)
		(placement
			(enabled no)
			(sheetname "")
		)
		(fill
			(thermal_gap 0.5)
			(thermal_bridge_width 0.5)
			(island_removal_mode 0)
		)
		(polygon
			(pts
				(xy 22.987 -14.224) (xy 21.209 -14.224) (xy 21.209 -13.208) (xy 22.987 -13.208)
			)
		)
	)
	(zone
		(layer "Cmts.User")
		(hatch none 0.5)
		(connect_pads
			(clearance 0)
		)
		(min_thickness 0.25)
		(keepout
			(tracks allowed)
			(vias allowed)
			(pads allowed)
			(copperpour allowed)
			(footprints allowed)
		)
		(placement
			(enabled no)
			(sheetname "")
		)
		(fill
			(thermal_gap 0.5)
			(thermal_bridge_width 0.5)
			(island_removal_mode 0)
		)
		(polygon
			(pts
				(xy 50.165 -48.895) (xy 50.165 -47.117) (xy 51.181 -47.117) (xy 51.181 -48.895)
			)
		)
	)
	(zone
		(layer "Cmts.User")
		(hatch none 0.5)
		(connect_pads
			(clearance 0)
		)
		(min_thickness 0.25)
		(keepout
			(tracks allowed)
			(vias allowed)
			(pads allowed)
			(copperpour allowed)
			(footprints allowed)
		)
		(placement
			(enabled no)
			(sheetname "")
		)
		(fill
			(thermal_gap 0.5)
			(thermal_bridge_width 0.5)
			(island_removal_mode 0)
		)
		(polygon
			(pts
				(xy 28.702 -10.795) (xy 26.924 -10.795) (xy 26.924 -9.779) (xy 28.702 -9.779)
			)
		)
	)
	(zone
		(layer "Cmts.User")
		(hatch none 0.5)
		(connect_pads
			(clearance 0)
		)
		(min_thickness 0.25)
		(keepout
			(tracks allowed)
			(vias allowed)
			(pads allowed)
			(copperpour allowed)
			(footprints allowed)
		)
		(placement
			(enabled no)
			(sheetname "")
		)
		(fill
			(thermal_gap 0.5)
			(thermal_bridge_width 0.5)
			(island_removal_mode 0)
		)
		(polygon
			(pts
				(xy 60.452 -47.244) (xy 60.452 -45.466) (xy 61.468 -45.466) (xy 61.468 -47.244)
			)
		)
	)
	(zone
		(layer "Cmts.User")
		(hatch none 0.5)
		(connect_pads
			(clearance 0)
		)
		(min_thickness 0.25)
		(keepout
			(tracks allowed)
			(vias allowed)
			(pads allowed)
			(copperpour allowed)
			(footprints allowed)
		)
		(placement
			(enabled no)
			(sheetname "")
		)
		(fill
			(thermal_gap 0.5)
			(thermal_bridge_width 0.5)
			(island_removal_mode 0)
		)
		(polygon
			(pts
				(xy 21.463 -16.002) (xy 19.685 -16.002) (xy 19.685 -14.986) (xy 21.463 -14.986)
			)
		)
	)
	(zone
		(layer "Cmts.User")
		(hatch none 0.5)
		(connect_pads
			(clearance 0)
		)
		(min_thickness 0.25)
		(keepout
			(tracks allowed)
			(vias allowed)
			(pads allowed)
			(copperpour allowed)
			(footprints allowed)
		)
		(placement
			(enabled no)
			(sheetname "")
		)
		(fill
			(thermal_gap 0.5)
			(thermal_bridge_width 0.5)
			(island_removal_mode 0)
		)
		(polygon
			(pts
				(xy 68.707 -10.922) (xy 66.929 -10.922) (xy 66.929 -9.906) (xy 68.707 -9.906)
			)
		)
	)
	(zone
		(layer "Cmts.User")
		(hatch none 0.5)
		(connect_pads
			(clearance 0)
		)
		(min_thickness 0.25)
		(keepout
			(tracks allowed)
			(vias allowed)
			(pads allowed)
			(copperpour allowed)
			(footprints allowed)
		)
		(placement
			(enabled no)
			(sheetname "")
		)
		(fill
			(thermal_gap 0.5)
			(thermal_bridge_width 0.5)
			(island_removal_mode 0)
		)
		(polygon
			(pts
				(xy 62.865 -10.795) (xy 61.087 -10.795) (xy 61.087 -9.779) (xy 62.865 -9.779)
			)
		)
	)
	(zone
		(layer "Cmts.User")
		(hatch none 0.5)
		(connect_pads
			(clearance 0)
		)
		(min_thickness 0.25)
		(keepout
			(tracks allowed)
			(vias allowed)
			(pads allowed)
			(copperpour allowed)
			(footprints allowed)
		)
		(placement
			(enabled no)
			(sheetname "")
		)
		(fill
			(thermal_gap 0.5)
			(thermal_bridge_width 0.5)
			(island_removal_mode 0)
		)
		(polygon
			(pts
				(xy 2.794 -60.071) (xy 2.794 -58.293) (xy 3.81 -58.293) (xy 3.81 -60.071)
			)
		)
	)
	(zone
		(layer "Cmts.User")
		(hatch none 0.5)
		(connect_pads
			(clearance 0)
		)
		(min_thickness 0.25)
		(keepout
			(tracks allowed)
			(vias allowed)
			(pads allowed)
			(copperpour allowed)
			(footprints allowed)
		)
		(placement
			(enabled no)
			(sheetname "")
		)
		(fill
			(thermal_gap 0.5)
			(thermal_bridge_width 0.5)
			(island_removal_mode 0)
		)
		(polygon
			(pts
				(xy 50.04435 -39.311072) (xy 48.78705 -38.053772) (xy 49.505616 -37.33546) (xy 50.762916 -38.592506)
			)
		)
	)
	(zone
		(layer "Cmts.User")
		(hatch none 0.5)
		(connect_pads
			(clearance 0)
		)
		(min_thickness 0.25)
		(keepout
			(tracks allowed)
			(vias allowed)
			(pads allowed)
			(copperpour allowed)
			(footprints allowed)
		)
		(placement
			(enabled no)
			(sheetname "")
		)
		(fill
			(thermal_gap 0.5)
			(thermal_bridge_width 0.5)
			(island_removal_mode 0)
		)
		(polygon
			(pts
				(xy 1.397 -61.595) (xy 1.397 -59.817) (xy 2.413 -59.817) (xy 2.413 -61.595)
			)
		)
	)
	(zone
		(layer "Cmts.User")
		(hatch none 0.5)
		(connect_pads
			(clearance 0)
		)
		(min_thickness 0.25)
		(keepout
			(tracks allowed)
			(vias allowed)
			(pads allowed)
			(copperpour allowed)
			(footprints allowed)
		)
		(placement
			(enabled no)
			(sheetname "")
		)
		(fill
			(thermal_gap 0.5)
			(thermal_bridge_width 0.5)
			(island_removal_mode 0)
		)
		(polygon
			(pts
				(xy 52.705 -30.353) (xy 52.705 -28.575) (xy 53.721 -28.575) (xy 53.721 -30.353)
			)
		)
	)
	(zone
		(layer "Cmts.User")
		(hatch none 0.5)
		(connect_pads
			(clearance 0)
		)
		(min_thickness 0.25)
		(keepout
			(tracks allowed)
			(vias allowed)
			(pads allowed)
			(copperpour allowed)
			(footprints allowed)
		)
		(placement
			(enabled no)
			(sheetname "")
		)
		(fill
			(thermal_gap 0.5)
			(thermal_bridge_width 0.5)
			(island_removal_mode 0)
		)
		(polygon
			(pts
				(xy 44.704 -10.795) (xy 42.926 -10.795) (xy 42.926 -9.779) (xy 44.704 -9.779)
			)
		)
	)
	(zone
		(layer "Cmts.User")
		(hatch none 0.5)
		(connect_pads
			(clearance 0)
		)
		(min_thickness 0.25)
		(keepout
			(tracks allowed)
			(vias allowed)
			(pads allowed)
			(copperpour allowed)
			(footprints allowed)
		)
		(placement
			(enabled no)
			(sheetname "")
		)
		(fill
			(thermal_gap 0.5)
			(thermal_bridge_width 0.5)
			(island_removal_mode 0)
		)
		(polygon
			(pts
				(xy 24.638 -10.668) (xy 22.86 -10.668) (xy 22.86 -9.652) (xy 24.638 -9.652)
			)
		)
	)
	(zone
		(layer "Cmts.User")
		(hatch none 0.5)
		(connect_pads
			(clearance 0)
		)
		(min_thickness 0.25)
		(keepout
			(tracks allowed)
			(vias allowed)
			(pads allowed)
			(copperpour allowed)
			(footprints allowed)
		)
		(placement
			(enabled no)
			(sheetname "")
		)
		(fill
			(thermal_gap 0.5)
			(thermal_bridge_width 0.5)
			(island_removal_mode 0)
		)
		(polygon
			(pts
				(xy 84.709 -10.922) (xy 82.931 -10.922) (xy 82.931 -9.906) (xy 84.709 -9.906)
			)
		)
	)
	(zone
		(layer "Cmts.User")
		(hatch none 0.5)
		(connect_pads
			(clearance 0)
		)
		(min_thickness 0.25)
		(keepout
			(tracks allowed)
			(vias allowed)
			(pads allowed)
			(copperpour allowed)
			(footprints allowed)
		)
		(placement
			(enabled no)
			(sheetname "")
		)
		(fill
			(thermal_gap 0.5)
			(thermal_bridge_width 0.5)
			(island_removal_mode 0)
		)
		(polygon
			(pts
				(xy 153.289 -47.498) (xy 156.337 -50.546) (xy 156.591 -50.546) (xy 156.845 -50.292) (xy 156.845 -50.038)
				(xy 153.797 -46.99) (xy 152.2476 -45.4406) (xy 151.9174 -45.4406) (xy 151.765 -45.593) (xy 151.765 -45.974)
			)
		)
	)
	(zone
		(layer "Cmts.User")
		(hatch none 0.5)
		(connect_pads
			(clearance 0)
		)
		(min_thickness 0.25)
		(keepout
			(tracks allowed)
			(vias allowed)
			(pads allowed)
			(copperpour allowed)
			(footprints allowed)
		)
		(placement
			(enabled no)
			(sheetname "")
		)
		(fill
			(thermal_gap 0.5)
			(thermal_bridge_width 0.5)
			(island_removal_mode 0)
		)
		(polygon
			(pts
				(xy 48.675544 -14.268196) (xy 46.897544 -14.268196) (xy 46.897544 -13.252196) (xy 48.675544 -13.252196)
			)
		)
	)
	(zone
		(layer "Cmts.User")
		(hatch none 0.5)
		(connect_pads
			(clearance 0)
		)
		(min_thickness 0.25)
		(keepout
			(tracks allowed)
			(vias allowed)
			(pads allowed)
			(copperpour allowed)
			(footprints allowed)
		)
		(placement
			(enabled no)
			(sheetname "")
		)
		(fill
			(thermal_gap 0.5)
			(thermal_bridge_width 0.5)
			(island_removal_mode 0)
		)
		(polygon
			(pts
				(xy 79.3496 -60.6298) (xy 79.3496 -59.2582) (xy 84.1248 -59.2582) (xy 84.1248 -60.6298)
			)
		)
	)
	(zone
		(layer "Cmts.User")
		(hatch none 0.5)
		(connect_pads
			(clearance 0)
		)
		(min_thickness 0.25)
		(keepout
			(tracks allowed)
			(vias allowed)
			(pads allowed)
			(copperpour allowed)
			(footprints allowed)
		)
		(placement
			(enabled no)
			(sheetname "")
		)
		(fill
			(thermal_gap 0.5)
			(thermal_bridge_width 0.5)
			(island_removal_mode 0)
		)
		(polygon
			(pts
				(xy 50.673 -20.955) (xy 48.895 -20.955) (xy 48.895 -19.939) (xy 50.673 -19.939)
			)
		)
	)
	(zone
		(layer "Cmts.User")
		(hatch none 0.5)
		(connect_pads
			(clearance 0)
		)
		(min_thickness 0.25)
		(keepout
			(tracks allowed)
			(vias allowed)
			(pads allowed)
			(copperpour allowed)
			(footprints allowed)
		)
		(placement
			(enabled no)
			(sheetname "")
		)
		(fill
			(thermal_gap 0.5)
			(thermal_bridge_width 0.5)
			(island_removal_mode 0)
		)
		(polygon
			(pts
				(xy 74.168 -15.113) (xy 72.39 -15.113) (xy 72.39 -14.097) (xy 74.168 -14.097)
			)
		)
	)
	(zone
		(layer "Cmts.User")
		(hatch none 0.5)
		(connect_pads
			(clearance 0)
		)
		(min_thickness 0.25)
		(keepout
			(tracks allowed)
			(vias allowed)
			(pads allowed)
			(copperpour allowed)
			(footprints allowed)
		)
		(placement
			(enabled no)
			(sheetname "")
		)
		(fill
			(thermal_gap 0.5)
			(thermal_bridge_width 0.5)
			(island_removal_mode 0)
		)
		(polygon
			(pts
				(xy 2.921 -63.119) (xy 2.921 -61.341) (xy 3.937 -61.341) (xy 3.937 -63.119)
			)
		)
	)
	(zone
		(layer "Cmts.User")
		(hatch none 0.5)
		(connect_pads
			(clearance 0)
		)
		(min_thickness 0.25)
		(keepout
			(tracks allowed)
			(vias allowed)
			(pads allowed)
			(copperpour allowed)
			(footprints allowed)
		)
		(placement
			(enabled no)
			(sheetname "")
		)
		(fill
			(thermal_gap 0.5)
			(thermal_bridge_width 0.5)
			(island_removal_mode 0)
		)
		(polygon
			(pts
				(xy 15.494 -47.371) (xy 13.716 -47.371) (xy 13.716 -46.355) (xy 15.494 -46.355)
			)
		)
	)
	(zone
		(layer "Cmts.User")
		(hatch none 0.5)
		(connect_pads
			(clearance 0)
		)
		(min_thickness 0.25)
		(keepout
			(tracks allowed)
			(vias allowed)
			(pads allowed)
			(copperpour allowed)
			(footprints allowed)
		)
		(placement
			(enabled no)
			(sheetname "")
		)
		(fill
			(thermal_gap 0.5)
			(thermal_bridge_width 0.5)
			(island_removal_mode 0)
		)
		(polygon
			(pts
				(xy 30.734 -14.986) (xy 28.956 -14.986) (xy 28.956 -13.97) (xy 30.734 -13.97)
			)
		)
	)
	(zone
		(layer "Cmts.User")
		(hatch none 0.5)
		(connect_pads
			(clearance 0)
		)
		(min_thickness 0.25)
		(keepout
			(tracks allowed)
			(vias allowed)
			(pads allowed)
			(copperpour allowed)
			(footprints allowed)
		)
		(placement
			(enabled no)
			(sheetname "")
		)
		(fill
			(thermal_gap 0.5)
			(thermal_bridge_width 0.5)
			(island_removal_mode 0)
		)
		(polygon
			(pts
				(xy 34.798 -14.986) (xy 33.02 -14.986) (xy 33.02 -13.97) (xy 34.798 -13.97)
			)
		)
	)
	(zone
		(layer "Cmts.User")
		(hatch none 0.5)
		(connect_pads
			(clearance 0)
		)
		(min_thickness 0.25)
		(keepout
			(tracks allowed)
			(vias allowed)
			(pads allowed)
			(copperpour allowed)
			(footprints allowed)
		)
		(placement
			(enabled no)
			(sheetname "")
		)
		(fill
			(thermal_gap 0.5)
			(thermal_bridge_width 0.5)
			(island_removal_mode 0)
		)
		(polygon
			(pts
				(xy 40.767 -12.827) (xy 38.989 -12.827) (xy 38.989 -11.811) (xy 40.767 -11.811)
			)
		)
	)
	(zone
		(layer "Cmts.User")
		(hatch none 0.5)
		(connect_pads
			(clearance 0)
		)
		(min_thickness 0.25)
		(keepout
			(tracks allowed)
			(vias allowed)
			(pads allowed)
			(copperpour allowed)
			(footprints allowed)
		)
		(placement
			(enabled no)
			(sheetname "")
		)
		(fill
			(thermal_gap 0.5)
			(thermal_bridge_width 0.5)
			(island_removal_mode 0)
		)
		(polygon
			(pts
				(xy 40.767 -10.668) (xy 38.989 -10.668) (xy 38.989 -9.652) (xy 40.767 -9.652)
			)
		)
	)
	(zone
		(layer "Cmts.User")
		(hatch none 0.5)
		(connect_pads
			(clearance 0)
		)
		(min_thickness 0.25)
		(keepout
			(tracks allowed)
			(vias allowed)
			(pads allowed)
			(copperpour allowed)
			(footprints allowed)
		)
		(placement
			(enabled no)
			(sheetname "")
		)
		(fill
			(thermal_gap 0.5)
			(thermal_bridge_width 0.5)
			(island_removal_mode 0)
		)
		(polygon
			(pts
				(xy 26.797 -14.351) (xy 25.019 -14.351) (xy 25.019 -13.335) (xy 26.797 -13.335)
			)
		)
	)
	(zone
		(layer "Cmts.User")
		(hatch none 0.5)
		(connect_pads
			(clearance 0)
		)
		(min_thickness 0.25)
		(keepout
			(tracks allowed)
			(vias allowed)
			(pads allowed)
			(copperpour allowed)
			(footprints allowed)
		)
		(placement
			(enabled no)
			(sheetname "")
		)
		(fill
			(thermal_gap 0.5)
			(thermal_bridge_width 0.5)
			(island_removal_mode 0)
		)
		(polygon
			(pts
				(xy 53.848 -35.814) (xy 52.07 -35.814) (xy 52.07 -34.798) (xy 53.848 -34.798)
			)
		)
	)
	(zone
		(layer "Cmts.User")
		(hatch none 0.5)
		(connect_pads
			(clearance 0)
		)
		(min_thickness 0.25)
		(keepout
			(tracks allowed)
			(vias allowed)
			(pads allowed)
			(copperpour allowed)
			(footprints allowed)
		)
		(placement
			(enabled no)
			(sheetname "")
		)
		(fill
			(thermal_gap 0.5)
			(thermal_bridge_width 0.5)
			(island_removal_mode 0)
		)
		(polygon
			(pts
				(xy 101.98735 -63.187072) (xy 100.73005 -61.929772) (xy 101.448616 -61.21146) (xy 102.705916 -62.468506)
			)
		)
	)
	(zone
		(layer "Cmts.User")
		(hatch none 0.5)
		(connect_pads
			(clearance 0)
		)
		(min_thickness 0.25)
		(keepout
			(tracks allowed)
			(vias allowed)
			(pads allowed)
			(copperpour allowed)
			(footprints allowed)
		)
		(placement
			(enabled no)
			(sheetname "")
		)
		(fill
			(thermal_gap 0.5)
			(thermal_bridge_width 0.5)
			(island_removal_mode 0)
		)
		(polygon
			(pts
				(xy 114.3 -56.469534) (xy 108.49864 -56.469534) (xy 108.19384 -56.774334) (xy 108.19384 -58.196734)
				(xy 106.426 -59.944) (xy 86.487 -59.944) (xy 85.89264 -59.314334) (xy 76.62164 -59.314334) (xy 74.74204 -57.434734)
				(xy 74.74204 -56.469534) (xy 74.74204 -25.416002) (xy 74.803 -25.416002) (xy 78.613 -21.606002)
				(xy 89.264998 -21.606002) (xy 92.075 -18.796) (xy 108.218478 -18.796) (xy 119.660162 -30.237684)
				(xy 119.629682 -42.921682) (xy 121.539 -44.831) (xy 121.539 -49.28235)
			)
		)
	)
	(zone
		(layer "Cmts.User")
		(hatch none 0.5)
		(connect_pads
			(clearance 0)
		)
		(min_thickness 0.25)
		(keepout
			(tracks allowed)
			(vias allowed)
			(pads allowed)
			(copperpour allowed)
			(footprints allowed)
		)
		(placement
			(enabled no)
			(sheetname "")
		)
		(fill
			(thermal_gap 0.5)
			(thermal_bridge_width 0.5)
			(island_removal_mode 0)
		)
		(polygon
			(pts
				(xy 100.08235 -61.917072) (xy 98.82505 -60.659772) (xy 99.543616 -59.94146) (xy 100.800916 -61.198506)
			)
		)
	)
	(zone
		(layer "Cmts.User")
		(hatch none 0.5)
		(connect_pads
			(clearance 0)
		)
		(min_thickness 0.25)
		(keepout
			(tracks allowed)
			(vias allowed)
			(pads allowed)
			(copperpour allowed)
			(footprints allowed)
		)
		(placement
			(enabled no)
			(sheetname "")
		)
		(fill
			(thermal_gap 0.5)
			(thermal_bridge_width 0.5)
			(island_removal_mode 0)
		)
		(polygon
			(pts
				(xy 36.703 -10.795) (xy 34.925 -10.795) (xy 34.925 -9.779) (xy 36.703 -9.779)
			)
		)
	)
	(zone
		(layer "Cmts.User")
		(hatch none 0.5)
		(connect_pads
			(clearance 0)
		)
		(min_thickness 0.25)
		(keepout
			(tracks allowed)
			(vias allowed)
			(pads allowed)
			(copperpour allowed)
			(footprints allowed)
		)
		(placement
			(enabled no)
			(sheetname "")
		)
		(fill
			(thermal_gap 0.5)
			(thermal_bridge_width 0.5)
			(island_removal_mode 0)
		)
		(polygon
			(pts
				(xy 59.182 -36.703) (xy 59.182 -34.925) (xy 60.198 -34.925) (xy 60.198 -36.703)
			)
		)
	)
	(zone
		(layer "Cmts.User")
		(hatch none 0.5)
		(connect_pads
			(clearance 0)
		)
		(min_thickness 0.25)
		(keepout
			(tracks allowed)
			(vias allowed)
			(pads allowed)
			(copperpour allowed)
			(footprints allowed)
		)
		(placement
			(enabled no)
			(sheetname "")
		)
		(fill
			(thermal_gap 0.5)
			(thermal_bridge_width 0.5)
			(island_removal_mode 0)
		)
		(polygon
			(pts
				(xy 9.144 -65.786) (xy 9.144 -55.245) (xy 10.16 -55.245) (xy 10.16 -65.786)
			)
		)
	)
	(zone
		(net "PV_VDDR")
		(layer "In9.Cu")
		(hatch none 0.5)
		(connect_pads
			(clearance 0.5)
		)
		(min_thickness 0.25)
		(fill yes
			(thermal_gap 0.5)
			(thermal_bridge_width 0.5)
			(island_removal_mode 0)
		)
		(polygon
			(pts
				(xy 163.068 -4.953) (xy 163.068 -4.064) (xy 163.195 -3.937) (xy 163.195 -3.683) (xy 163.195 -2.921)
				(xy 163.068 -2.794) (xy 158.369 -2.794) (xy 158.242 -2.921) (xy 158.242 -3.81) (xy 158.242 -8.509)
				(xy 158.75 -9.017) (xy 162.433 -9.017) (xy 163.322 -8.128) (xy 163.322 -6.731) (xy 163.322 -5.207)
			)
		)
	)
	(zone
		(net "P3V3_STBY")
		(layer "In9.Cu")
		(hatch none 0.5)
		(connect_pads
			(clearance 0.5)
		)
		(min_thickness 0.25)
		(fill yes
			(thermal_gap 0.5)
			(thermal_bridge_width 0.5)
			(island_removal_mode 0)
		)
		(polygon
			(pts
				(xy 23.8125 -45.1485) (xy 23.3045 -45.6565) (xy 23.114 -45.847) (xy 19.177 -45.847) (xy 16.637 -48.387)
				(xy 16.637 -49.657) (xy 12.319 -53.975) (xy 11.8745 -54.4195) (xy 11.8745 -58.1025) (xy 10.922 -59.055)
				(xy 10.922 -62.992) (xy 10.922 -65.532) (xy 11.049 -65.659) (xy 11.049 -66.421) (xy 10.795 -66.675)
				(xy 10.668 -66.675) (xy 10.541 -66.548) (xy 9.398 -66.548) (xy 9.144 -66.802) (xy 9.144 -67.691)
				(xy 9.398 -67.945) (xy 9.525 -67.945) (xy 11.684 -67.945) (xy 12.065 -67.945) (xy 13.208 -66.802)
				(xy 13.208 -66.421) (xy 13.208 -65.532) (xy 12.573 -64.897) (xy 12.573 -63.119) (xy 12.573 -60.706)
				(xy 12.573 -59.944) (xy 13.97 -58.547) (xy 13.97 -57.277) (xy 14.224 -57.023) (xy 14.605 -57.023)
				(xy 15.494 -57.023) (xy 22.987 -49.53) (xy 23.622 -49.53) (xy 27.559 -49.53) (xy 28.2575 -50.2285)
				(xy 29.083 -51.054) (xy 29.337 -51.054) (xy 34.544 -51.054) (xy 34.925 -51.054) (xy 35.814 -50.165)
				(xy 35.941 -50.038) (xy 35.941 -49.53) (xy 35.687 -49.276) (xy 35.56 -49.276) (xy 35.052 -49.276)
				(xy 34.544 -49.784) (xy 33.401 -49.784) (xy 29.591 -49.784) (xy 28.575 -48.768) (xy 28.575 -46.101)
				(xy 31.75 -42.926) (xy 31.75 -40.64) (xy 31.75 -40.005) (xy 32.131 -39.624) (xy 32.512 -39.624)
				(xy 33.782 -39.624) (xy 33.909 -39.751) (xy 34.036 -39.878) (xy 36.83 -39.878) (xy 37.084 -40.132)
				(xy 37.084 -40.64) (xy 37.338 -40.894) (xy 37.719 -41.275) (xy 38.354 -41.275) (xy 38.989 -41.275)
				(xy 40.386 -42.672) (xy 40.386 -45.085) (xy 40.767 -45.466) (xy 41.91 -46.609) (xy 42.418 -46.609)
				(xy 42.545 -46.482) (xy 42.545 -44.958) (xy 42.037 -44.45) (xy 42.037 -43.942) (xy 42.418 -43.561)
				(xy 46.736 -43.561) (xy 47.117 -43.18) (xy 48.895 -43.18) (xy 49.276 -42.799) (xy 49.276 -42.164)
				(xy 49.276 -41.148) (xy 48.514 -40.386) (xy 47.498 -40.386) (xy 43.434 -40.386) (xy 43.307 -40.386)
				(xy 42.164 -39.243) (xy 41.402 -39.243) (xy 40.513 -38.354) (xy 40.005 -38.354) (xy 39.243 -37.592)
				(xy 38.862 -37.592) (xy 35.052 -37.592) (xy 34.29 -36.83) (xy 33.401 -36.83) (xy 30.099 -36.83)
				(xy 28.575 -36.83) (xy 28.448 -36.83) (xy 28.194 -36.83) (xy 27.432 -37.592) (xy 27.432 -38.481)
				(xy 27.432 -40.386) (xy 23.8125 -44.0055)
			)
		)
	)
	(zone
		(layer "In9.Cu")
		(hatch none 0.5)
		(connect_pads
			(clearance 0)
		)
		(min_thickness 0.25)
		(keepout
			(tracks not_allowed)
			(vias allowed)
			(pads allowed)
			(copperpour not_allowed)
			(footprints allowed)
		)
		(placement
			(enabled no)
			(sheetname "")
		)
		(fill
			(thermal_gap 0.5)
			(thermal_bridge_width 0.5)
			(island_removal_mode 0)
		)
		(polygon
			(pts
				(arc
					(start 75.371198 -9.90092)
					(mid 74.987404 -10.284333)
					(end 75.370944 -10.668)
				)
				(xy 75.614784 -10.668) (xy 75.614784 -10.627106)
				(arc
					(start 75.503532 -10.515854)
					(mid 75.182367 -10.095883)
					(end 75.602338 -10.417048)
				)
				(xy 75.754484 -10.569194) (xy 75.754484 -10.668) (xy 75.944984 -10.668) (xy 75.944984 -10.569194)
				(arc
					(start 76.09713 -10.417048)
					(mid 76.517101 -10.095883)
					(end 76.195936 -10.515854)
				)
				(xy 76.142596 -10.569194) (xy 76.084684 -10.627106) (xy 76.084684 -10.668)
				(arc
					(start 76.328524 -10.668)
					(mid 76.712064 -10.28446)
					(end 76.328524 -9.90092)
				)
			)
		)
	)
	(zone
		(layer "In9.Cu")
		(hatch none 0.5)
		(connect_pads
			(clearance 0)
		)
		(min_thickness 0.25)
		(keepout
			(tracks not_allowed)
			(vias allowed)
			(pads allowed)
			(copperpour not_allowed)
			(footprints allowed)
		)
		(placement
			(enabled no)
			(sheetname "")
		)
		(fill
			(thermal_gap 0.5)
			(thermal_bridge_width 0.5)
			(island_removal_mode 0)
		)
		(polygon
			(pts
				(arc
					(start 43.4086 -9.867138)
					(mid 43.024806 -10.250551)
					(end 43.408346 -10.634218)
				)
				(xy 43.633136 -10.634218) (xy 43.633136 -10.574274)
				(arc
					(start 43.540934 -10.482072)
					(mid 43.219769 -10.062101)
					(end 43.63974 -10.383266)
				)
				(xy 43.772836 -10.516362) (xy 43.772836 -10.634218) (xy 43.963336 -10.634218) (xy 43.963336 -10.516362)
				(arc
					(start 44.096432 -10.383266)
					(mid 44.516403 -10.062101)
					(end 44.195238 -10.482072)
				)
				(xy 44.160948 -10.516362) (xy 44.103036 -10.574274) (xy 44.103036 -10.634218)
				(arc
					(start 44.327826 -10.634218)
					(mid 44.711366 -10.250678)
					(end 44.327826 -9.867138)
				)
			)
		)
	)
	(zone
		(net "GND")
		(layer "In9.Cu")
		(hatch none 0.5)
		(connect_pads
			(clearance 0.5)
		)
		(min_thickness 0.25)
		(fill yes
			(thermal_gap 0.5)
			(thermal_bridge_width 0.5)
			(island_removal_mode 0)
		)
		(polygon
			(pts
				(xy 187.579 -31.623) (xy 187.579 -27.686) (xy 188.087 -27.178) (xy 190.119 -27.178) (xy 191.897 -25.4)
				(xy 197.612 -25.4) (xy 202.184 -29.972) (xy 202.311 -30.099) (xy 202.311 -32.766) (xy 203.6445 -34.0995)
				(xy 203.6445 -37.719) (xy 199.16775 -42.19575) (xy 199.136 -42.19575) (xy 194.8815 -46.45025) (xy 194.8815 -46.482)
				(xy 194.8815 -51.3715) (xy 193.802 -52.451) (xy 189.357 -52.451) (xy 186.69 -52.451) (xy 185.547 -52.451)
				(xy 176.657 -52.451) (xy 171.45 -47.244) (xy 171.45 -45.974) (xy 174.244 -43.18) (xy 178.562 -43.18)
				(xy 181.229 -43.18) (xy 181.356 -43.18) (xy 186.055 -38.481) (xy 186.055 -33.147)
			)
		)
	)
	(zone
		(layer "In9.Cu")
		(hatch none 0.5)
		(connect_pads
			(clearance 0)
		)
		(min_thickness 0.25)
		(keepout
			(tracks not_allowed)
			(vias allowed)
			(pads allowed)
			(copperpour not_allowed)
			(footprints allowed)
		)
		(placement
			(enabled no)
			(sheetname "")
		)
		(fill
			(thermal_gap 0.5)
			(thermal_bridge_width 0.5)
			(island_removal_mode 0)
		)
		(polygon
			(pts
				(xy 27.963368 -10.516362)
				(arc
					(start 28.096464 -10.383266)
					(mid 28.516435 -10.062101)
					(end 28.19527 -10.482072)
				)
				(xy 28.16098 -10.516362) (xy 28.103068 -10.574274) (xy 28.103068 -10.634218)
				(arc
					(start 28.327604 -10.634218)
					(mid 28.711398 -10.250805)
					(end 28.327858 -9.867138)
				)
				(arc
					(start 27.408378 -9.867138)
					(mid 27.024838 -10.250678)
					(end 27.408378 -10.634218)
				)
				(xy 27.633168 -10.634218) (xy 27.633168 -10.574274)
				(arc
					(start 27.540966 -10.482072)
					(mid 27.219801 -10.062101)
					(end 27.639772 -10.383266)
				)
				(xy 27.772868 -10.516362) (xy 27.772868 -10.634218) (xy 27.963368 -10.634218)
			)
		)
	)
	(zone
		(layer "In9.Cu")
		(hatch none 0.5)
		(connect_pads
			(clearance 0)
		)
		(min_thickness 0.25)
		(keepout
			(tracks not_allowed)
			(vias allowed)
			(pads allowed)
			(copperpour not_allowed)
			(footprints allowed)
		)
		(placement
			(enabled no)
			(sheetname "")
		)
		(fill
			(thermal_gap 0.5)
			(thermal_bridge_width 0.5)
			(island_removal_mode 0)
		)
		(polygon
			(pts
				(arc
					(start 47.408592 -9.867138)
					(mid 47.024798 -10.250551)
					(end 47.408338 -10.634218)
				)
				(xy 47.60595 -10.634218) (xy 47.60595 -10.547096)
				(arc
					(start 47.540926 -10.482072)
					(mid 47.219761 -10.062101)
					(end 47.639732 -10.383266)
				)
				(xy 47.74565 -10.489184) (xy 47.74565 -10.634218) (xy 47.93615 -10.634218) (xy 47.93615 -10.54354)
				(xy 47.990506 -10.489184)
				(arc
					(start 48.096424 -10.383266)
					(mid 48.516395 -10.062101)
					(end 48.19523 -10.482072)
				)
				(xy 48.133762 -10.54354) (xy 48.07585 -10.601452) (xy 48.07585 -10.634218)
				(arc
					(start 48.327818 -10.634218)
					(mid 48.711358 -10.250678)
					(end 48.327818 -9.867138)
				)
			)
		)
	)
	(zone
		(layer "In9.Cu")
		(hatch none 0.5)
		(connect_pads
			(clearance 0)
		)
		(min_thickness 0.25)
		(keepout
			(tracks not_allowed)
			(vias allowed)
			(pads allowed)
			(copperpour not_allowed)
			(footprints allowed)
		)
		(placement
			(enabled no)
			(sheetname "")
		)
		(fill
			(thermal_gap 0.5)
			(thermal_bridge_width 0.5)
			(island_removal_mode 0)
		)
		(polygon
			(pts
				(arc
					(start 71.371206 -9.90092)
					(mid 70.987412 -10.284333)
					(end 71.370952 -10.668)
				)
				(xy 71.614792 -10.668) (xy 71.614792 -10.627106)
				(arc
					(start 71.50354 -10.515854)
					(mid 71.182375 -10.095883)
					(end 71.602346 -10.417048)
				)
				(xy 71.754492 -10.569194) (xy 71.754492 -10.668) (xy 71.944992 -10.668) (xy 71.944992 -10.569194)
				(arc
					(start 72.097138 -10.417048)
					(mid 72.517109 -10.095883)
					(end 72.195944 -10.515854)
				)
				(xy 72.142604 -10.569194) (xy 72.084692 -10.627106) (xy 72.084692 -10.668)
				(arc
					(start 72.328532 -10.668)
					(mid 72.712072 -10.28446)
					(end 72.328532 -9.90092)
				)
			)
		)
	)
	(zone
		(net "GND")
		(layer "In9.Cu")
		(hatch none 0.5)
		(connect_pads
			(clearance 0.5)
		)
		(min_thickness 0.25)
		(fill yes
			(thermal_gap 0.5)
			(thermal_bridge_width 0.5)
			(island_removal_mode 0)
		)
		(polygon
			(pts
				(xy 115.823746 -0.762254) (xy 115.189 -1.397) (xy 115.189 -5.08) (xy 115.189 -10.541) (xy 115.1636 -10.5664)
				(xy 115.1636 -14.3256) (xy 115.697 -14.859) (xy 133.731 -14.859) (xy 137.033 -11.557) (xy 153.543 -11.557)
				(xy 155.575 -9.525) (xy 155.575 -1.143) (xy 155.194254 -0.762254)
			)
		)
	)
	(zone
		(net "P1V0")
		(layer "In9.Cu")
		(hatch none 0.5)
		(connect_pads
			(clearance 0.5)
		)
		(min_thickness 0.25)
		(fill yes
			(thermal_gap 0.5)
			(thermal_bridge_width 0.5)
			(island_removal_mode 0)
		)
		(polygon
			(pts
				(xy 98.806 -38.989) (xy 98.806 -37.465) (xy 99.822 -36.449) (xy 102.235 -36.449) (xy 102.743 -35.941)
				(xy 102.743 -34.544) (xy 102.489 -34.29) (xy 101.6 -34.29) (xy 100.965 -33.655) (xy 99.695 -33.655)
				(xy 99.568 -33.782) (xy 99.568 -35.052) (xy 99.314 -35.306) (xy 98.298 -35.306) (xy 98.044 -35.052)
				(xy 98.044 -33.147) (xy 97.79 -32.893) (xy 97.663 -32.766) (xy 97.663 -30.861) (xy 97.282 -30.48)
				(xy 96.774 -30.48) (xy 96.52 -30.226) (xy 96.52 -28.321) (xy 96.52 -27.686) (xy 96.52 -27.559) (xy 96.266 -27.305)
				(xy 96.012 -27.051) (xy 95.25 -26.289) (xy 95.25 -20.32) (xy 92.329 -17.399) (xy 91.948 -17.399)
				(xy 89.789 -17.399) (xy 85.852 -21.336) (xy 85.852 -22.225) (xy 85.852 -24.511) (xy 85.598 -24.765)
				(xy 85.471 -24.892) (xy 85.471 -30.861) (xy 85.725 -31.115) (xy 86.995 -31.115) (xy 87.122 -31.242)
				(xy 87.503 -31.623) (xy 87.503 -32.004) (xy 88.646 -33.147) (xy 88.646 -33.274) (xy 88.646 -34.29)
				(xy 90.678 -36.322) (xy 90.678 -38.354) (xy 91.313 -38.989) (xy 95.758 -38.989) (xy 96.266 -39.497)
				(xy 97.79 -39.497) (xy 98.044 -39.243) (xy 98.552 -39.243)
			)
		)
	)
	(zone
		(layer "In9.Cu")
		(hatch none 0.5)
		(connect_pads
			(clearance 0)
		)
		(min_thickness 0.25)
		(keepout
			(tracks not_allowed)
			(vias allowed)
			(pads allowed)
			(copperpour not_allowed)
			(footprints allowed)
		)
		(placement
			(enabled no)
			(sheetname "")
		)
		(fill
			(thermal_gap 0.5)
			(thermal_bridge_width 0.5)
			(island_removal_mode 0)
		)
		(polygon
			(pts
				(xy 101.581458 -62.49289) (xy 101.60381 -62.470792)
				(arc
					(start 101.811328 -62.470792)
					(mid 102.333496 -62.546992)
					(end 101.811328 -62.623192)
				)
				(xy 101.666802 -62.623192) (xy 101.634036 -62.655958)
				(arc
					(start 101.795072 -62.817756)
					(mid 102.337616 -62.818772)
					(end 102.338632 -62.276228)
				)
				(arc
					(start 101.734366 -61.66993)
					(mid 101.189299 -61.660676)
					(end 101.185472 -62.20587)
				)
				(xy 101.347016 -62.367922) (xy 101.380036 -62.334648) (xy 101.38029 -62.20587)
				(arc
					(start 101.380544 -62.19063)
					(mid 101.457775 -61.668317)
					(end 101.532944 -62.190884)
				)
				(xy 101.532436 -62.366398) (xy 101.532436 -62.397894) (xy 101.532436 -62.398148) (xy 101.510084 -62.420246)
				(xy 101.454458 -62.475872) (xy 101.52634 -62.548008)
			)
		)
	)
	(zone
		(layer "In9.Cu")
		(hatch none 0.5)
		(connect_pads
			(clearance 0)
		)
		(min_thickness 0.25)
		(keepout
			(tracks not_allowed)
			(vias allowed)
			(pads allowed)
			(copperpour not_allowed)
			(footprints allowed)
		)
		(placement
			(enabled no)
			(sheetname "")
		)
		(fill
			(thermal_gap 0.5)
			(thermal_bridge_width 0.5)
			(island_removal_mode 0)
		)
		(polygon
			(pts
				(xy 23.98903 -10.490708)
				(arc
					(start 24.096472 -10.383266)
					(mid 24.516443 -10.062101)
					(end 24.195278 -10.482072)
				)
				(xy 24.135334 -10.542016) (xy 24.077422 -10.599928) (xy 24.077422 -10.634218)
				(arc
					(start 24.327866 -10.634218)
					(mid 24.711406 -10.250678)
					(end 24.327866 -9.867138)
				)
				(arc
					(start 23.40864 -9.867138)
					(mid 23.024846 -10.250551)
					(end 23.408386 -10.634218)
				)
				(xy 23.607522 -10.634218) (xy 23.607522 -10.54862)
				(arc
					(start 23.540974 -10.482072)
					(mid 23.219809 -10.062101)
					(end 23.63978 -10.383266)
				)
				(xy 23.747222 -10.490708) (xy 23.747222 -10.634218) (xy 23.937722 -10.634218) (xy 23.937722 -10.542016)
			)
		)
	)
	(zone
		(net "P3V3_STBY")
		(layer "In9.Cu")
		(hatch none 0.5)
		(connect_pads
			(clearance 0.5)
		)
		(min_thickness 0.25)
		(fill yes
			(thermal_gap 0.5)
			(thermal_bridge_width 0.5)
			(island_removal_mode 0)
		)
		(polygon
			(pts
				(xy 60.3123 -24.4475) (xy 61.2394 -23.5204) (xy 61.341 -23.4188) (xy 61.341 -19.431) (xy 61.214 -19.304)
				(xy 60.833 -19.304) (xy 60.706 -19.431) (xy 59.182 -20.955) (xy 59.182 -21.2344) (xy 59.182 -23.8125)
				(xy 59.817 -24.4475)
			)
		)
	)
	(zone
		(layer "In9.Cu")
		(hatch none 0.5)
		(connect_pads
			(clearance 0)
		)
		(min_thickness 0.25)
		(keepout
			(tracks not_allowed)
			(vias allowed)
			(pads allowed)
			(copperpour not_allowed)
			(footprints allowed)
		)
		(placement
			(enabled no)
			(sheetname "")
		)
		(fill
			(thermal_gap 0.5)
			(thermal_bridge_width 0.5)
			(island_removal_mode 0)
		)
		(polygon
			(pts
				(xy 19.963384 -10.516362)
				(arc
					(start 20.09648 -10.383266)
					(mid 20.516451 -10.062101)
					(end 20.195286 -10.482072)
				)
				(xy 20.160996 -10.516362) (xy 20.103084 -10.574274) (xy 20.103084 -10.634218)
				(arc
					(start 20.327874 -10.634218)
					(mid 20.711414 -10.250678)
					(end 20.327874 -9.867138)
				)
				(arc
					(start 19.408648 -9.867138)
					(mid 19.024854 -10.250551)
					(end 19.408394 -10.634218)
				)
				(xy 19.633184 -10.634218) (xy 19.633184 -10.574274)
				(arc
					(start 19.540982 -10.482072)
					(mid 19.219817 -10.062101)
					(end 19.639788 -10.383266)
				)
				(xy 19.772884 -10.516362) (xy 19.772884 -10.634218) (xy 19.963384 -10.634218)
			)
		)
	)
	(zone
		(layer "In9.Cu")
		(hatch none 0.5)
		(connect_pads
			(clearance 0)
		)
		(min_thickness 0.25)
		(keepout
			(tracks not_allowed)
			(vias allowed)
			(pads allowed)
			(copperpour not_allowed)
			(footprints allowed)
		)
		(placement
			(enabled no)
			(sheetname "")
		)
		(fill
			(thermal_gap 0.5)
			(thermal_bridge_width 0.5)
			(island_removal_mode 0)
		)
		(polygon
			(pts
				(arc
					(start 99.781106 -60.369704)
					(mid 99.238816 -60.378086)
					(end 99.247198 -60.920376)
				)
				(xy 99.24542 -60.922154) (xy 99.378262 -61.050932) (xy 99.444302 -60.984892)
				(arc
					(start 99.444302 -60.902342)
					(mid 99.514152 -60.378425)
					(end 99.584002 -60.902342)
				)
				(xy 99.584002 -61.042804) (xy 99.478592 -61.148214) (xy 99.615244 -61.281056) (xy 99.719638 -61.176662)
				(arc
					(start 99.876864 -61.176662)
					(mid 100.400781 -61.246512)
					(end 99.876864 -61.316362)
				)
				(xy 99.77755 -61.316362) (xy 99.715574 -61.378338) (xy 99.86518 -61.523372) (xy 99.865434 -61.523372)
				(arc
					(start 99.866958 -61.521848)
					(mid 100.409565 -61.513655)
					(end 100.40112 -60.971176)
				)
				(xy 100.402898 -60.969398) (xy 99.782884 -60.367926)
			)
		)
	)
	(zone
		(layer "In9.Cu")
		(hatch none 0.5)
		(connect_pads
			(clearance 0)
		)
		(min_thickness 0.25)
		(keepout
			(tracks not_allowed)
			(vias allowed)
			(pads allowed)
			(copperpour not_allowed)
			(footprints allowed)
		)
		(placement
			(enabled no)
			(sheetname "")
		)
		(fill
			(thermal_gap 0.5)
			(thermal_bridge_width 0.5)
			(island_removal_mode 0)
		)
		(polygon
			(pts
				(arc
					(start 51.041554 -47.64278)
					(mid 50.663729 -47.253654)
					(end 50.274474 -47.63135)
				)
				(xy 50.271172 -47.865538) (xy 50.330608 -47.865538)
				(arc
					(start 50.42662 -47.769526)
					(mid 50.846591 -47.448361)
					(end 50.525426 -47.868332)
				)
				(xy 50.38852 -48.005238) (xy 50.26914 -48.005238) (xy 50.266346 -48.195738) (xy 50.439574 -48.195738)
				(arc
					(start 50.51298 -48.269144)
					(mid 50.834145 -48.689115)
					(end 50.414174 -48.36795)
				)
				(xy 50.381662 -48.335438) (xy 50.264314 -48.335438)
				(arc
					(start 50.262028 -48.49495)
					(mid 50.63998 -48.884078)
					(end 51.029108 -48.506126)
				)
				(xy 51.03368 -48.195738)
			)
		)
	)
	(zone
		(layer "In9.Cu")
		(hatch none 0.5)
		(connect_pads
			(clearance 0)
		)
		(min_thickness 0.25)
		(keepout
			(tracks not_allowed)
			(vias allowed)
			(pads allowed)
			(copperpour not_allowed)
			(footprints allowed)
		)
		(placement
			(enabled no)
			(sheetname "")
		)
		(fill
			(thermal_gap 0.5)
			(thermal_bridge_width 0.5)
			(island_removal_mode 0)
		)
		(polygon
			(pts
				(xy 31.96336 -10.516362)
				(arc
					(start 32.096456 -10.383266)
					(mid 32.516427 -10.062101)
					(end 32.195262 -10.482072)
				)
				(xy 32.160972 -10.516362) (xy 32.10306 -10.574274) (xy 32.10306 -10.634218)
				(arc
					(start 32.327596 -10.634218)
					(mid 32.71139 -10.250805)
					(end 32.32785 -9.867138)
				)
				(arc
					(start 31.40837 -9.867138)
					(mid 31.02483 -10.250678)
					(end 31.40837 -10.634218)
				)
				(xy 31.63316 -10.634218) (xy 31.63316 -10.574274)
				(arc
					(start 31.540958 -10.482072)
					(mid 31.219793 -10.062101)
					(end 31.639764 -10.383266)
				)
				(xy 31.77286 -10.516362) (xy 31.77286 -10.634218) (xy 31.96336 -10.634218)
			)
		)
	)
	(zone
		(layer "In9.Cu")
		(hatch none 0.5)
		(connect_pads
			(clearance 0)
		)
		(min_thickness 0.25)
		(keepout
			(tracks not_allowed)
			(vias allowed)
			(pads allowed)
			(copperpour not_allowed)
			(footprints allowed)
		)
		(placement
			(enabled no)
			(sheetname "")
		)
		(fill
			(thermal_gap 0.5)
			(thermal_bridge_width 0.5)
			(island_removal_mode 0)
		)
		(polygon
			(pts
				(arc
					(start 35.408362 -9.867138)
					(mid 35.024822 -10.250678)
					(end 35.408362 -10.634218)
				)
				(xy 35.633152 -10.634218) (xy 35.633152 -10.574274)
				(arc
					(start 35.54095 -10.482072)
					(mid 35.219785 -10.062101)
					(end 35.639756 -10.383266)
				)
				(xy 35.772852 -10.516362) (xy 35.772852 -10.634218) (xy 35.963352 -10.634218) (xy 35.963352 -10.516362)
				(arc
					(start 36.096448 -10.383266)
					(mid 36.516419 -10.062101)
					(end 36.195254 -10.482072)
				)
				(xy 36.160964 -10.516362) (xy 36.103052 -10.574274) (xy 36.103052 -10.634218)
				(arc
					(start 36.327588 -10.634218)
					(mid 36.711382 -10.250805)
					(end 36.327842 -9.867138)
				)
			)
		)
	)
	(zone
		(layer "In9.Cu")
		(hatch none 0.5)
		(connect_pads
			(clearance 0)
		)
		(min_thickness 0.25)
		(keepout
			(tracks not_allowed)
			(vias allowed)
			(pads allowed)
			(copperpour not_allowed)
			(footprints allowed)
		)
		(placement
			(enabled no)
			(sheetname "")
		)
		(fill
			(thermal_gap 0.5)
			(thermal_bridge_width 0.5)
			(island_removal_mode 0)
		)
		(polygon
			(pts
				(arc
					(start 79.37119 -9.95172)
					(mid 78.987396 -10.335133)
					(end 79.370936 -10.7188)
				)
				(xy 79.60995 -10.7188) (xy 79.60995 -10.67308)
				(arc
					(start 79.503524 -10.566654)
					(mid 79.182359 -10.146683)
					(end 79.60233 -10.467848)
				)
				(xy 79.74965 -10.615168) (xy 79.74965 -10.7188) (xy 79.94015 -10.7188) (xy 79.94015 -10.62482) (xy 79.949802 -10.615168)
				(arc
					(start 80.097122 -10.467848)
					(mid 80.517093 -10.146683)
					(end 80.195928 -10.566654)
				)
				(xy 80.137762 -10.62482) (xy 80.07985 -10.682732) (xy 80.07985 -10.7188)
				(arc
					(start 80.328516 -10.7188)
					(mid 80.712056 -10.33526)
					(end 80.328516 -9.95172)
				)
			)
		)
	)
	(zone
		(net "P12V")
		(layer "In9.Cu")
		(hatch none 0.5)
		(connect_pads
			(clearance 0.5)
		)
		(min_thickness 0.25)
		(fill yes
			(thermal_gap 0.5)
			(thermal_bridge_width 0.5)
			(island_removal_mode 0)
		)
		(polygon
			(pts
				(xy 0.762254 -29.972) (xy 0.762254 -53.340254) (xy 0.8255 -53.4035) (xy 0.8255 -55.4355) (xy 4.699 -59.309)
				(xy 4.953 -59.563) (xy 4.953 -70.485) (xy 7.493 -73.025) (xy 43.942 -73.025) (xy 46.863 -70.104)
				(xy 47.244 -69.723) (xy 54.356 -69.723) (xy 57.658 -73.025) (xy 58.674 -73.025) (xy 72.009 -73.025)
				(xy 74.803 -70.231) (xy 76.835 -70.231) (xy 79.629 -73.025) (xy 85.598 -73.025) (xy 203.581 -73.025)
				(xy 206.9465 -69.6595) (xy 206.9465 -66.8655) (xy 206.502 -66.421) (xy 206.121 -66.421) (xy 204.7875 -66.421)
				(xy 202.1205 -69.088) (xy 196.723 -69.088) (xy 196.215 -69.596) (xy 192.913 -69.596) (xy 192.786 -69.723)
				(xy 191.897 -70.612) (xy 101.981 -70.612) (xy 85.852 -70.612) (xy 85.725 -70.485) (xy 85.5345 -70.2945)
				(xy 84.836 -69.596) (xy 83.5406 -68.3006) (xy 77.8256 -68.3006) (xy 72.4154 -68.3006) (xy 71.12 -69.596)
				(xy 70.993 -69.723) (xy 58.928 -69.723) (xy 56.007 -66.802) (xy 44.831 -66.802) (xy 44.704 -66.929)
				(xy 44.45 -67.183) (xy 41.91 -69.723) (xy 41.783 -69.85) (xy 36.449 -69.85) (xy 31.877 -69.85) (xy 29.718 -69.85)
				(xy 27.305 -69.85) (xy 26.797 -69.85) (xy 10.541 -69.85) (xy 9.144 -68.453) (xy 8.89 -68.199) (xy 8.763 -68.072)
				(xy 8.763 -57.912) (xy 8.763 -55.753) (xy 6.858 -53.848) (xy 6.858 -51.689) (xy 6.858 -27.178) (xy 6.985 -27.051)
				(xy 8.763 -25.273) (xy 11.811 -25.273) (xy 15.367 -21.717) (xy 16.002 -21.717) (xy 19.304 -18.415)
				(xy 19.304 -11.176) (xy 19.304 -10.795) (xy 18.923 -10.414) (xy 15.748 -10.414) (xy 15.494 -10.668)
				(xy 15.494 -12.7) (xy 15.494 -14.478) (xy 15.494 -14.859) (xy 14.859 -15.494) (xy 14.478 -15.494)
				(xy 1.397 -15.494) (xy 0.762254 -16.128746)
			)
		)
	)
	(zone
		(layer "In9.Cu")
		(hatch none 0.5)
		(connect_pads
			(clearance 0)
		)
		(min_thickness 0.25)
		(keepout
			(tracks not_allowed)
			(vias allowed)
			(pads allowed)
			(copperpour not_allowed)
			(footprints allowed)
		)
		(placement
			(enabled no)
			(sheetname "")
		)
		(fill
			(thermal_gap 0.5)
			(thermal_bridge_width 0.5)
			(island_removal_mode 0)
		)
		(polygon
			(pts
				(arc
					(start 67.34556 -9.90092)
					(mid 66.96202 -10.28446)
					(end 67.34556 -10.668)
				)
				(xy 67.62115 -10.668) (xy 67.62115 -10.658856)
				(arc
					(start 67.478148 -10.515854)
					(mid 67.156983 -10.095883)
					(end 67.576954 -10.417048)
				)
				(xy 67.76085 -10.600944) (xy 67.76085 -10.668) (xy 67.95135 -10.668) (xy 67.95135 -10.537444)
				(arc
					(start 68.071746 -10.417048)
					(mid 68.491717 -10.095883)
					(end 68.170552 -10.515854)
				)
				(xy 68.148962 -10.537444) (xy 68.09105 -10.595356) (xy 68.09105 -10.668)
				(arc
					(start 68.302886 -10.668)
					(mid 68.68668 -10.284587)
					(end 68.30314 -9.90092)
				)
			)
		)
	)
	(zone
		(layer "In9.Cu")
		(hatch none 0.5)
		(connect_pads
			(clearance 0)
		)
		(min_thickness 0.25)
		(keepout
			(tracks not_allowed)
			(vias allowed)
			(pads allowed)
			(copperpour not_allowed)
			(footprints allowed)
		)
		(placement
			(enabled no)
			(sheetname "")
		)
		(fill
			(thermal_gap 0.5)
			(thermal_bridge_width 0.5)
			(island_removal_mode 0)
		)
		(polygon
			(pts
				(arc
					(start 39.408608 -9.867138)
					(mid 39.024814 -10.250551)
					(end 39.408354 -10.634218)
				)
				(xy 39.633144 -10.634218) (xy 39.633144 -10.574274)
				(arc
					(start 39.540942 -10.482072)
					(mid 39.219777 -10.062101)
					(end 39.639748 -10.383266)
				)
				(xy 39.772844 -10.516362) (xy 39.772844 -10.634218) (xy 39.963344 -10.634218) (xy 39.963344 -10.516362)
				(arc
					(start 40.09644 -10.383266)
					(mid 40.516411 -10.062101)
					(end 40.195246 -10.482072)
				)
				(xy 40.160956 -10.516362) (xy 40.103044 -10.574274) (xy 40.103044 -10.634218)
				(arc
					(start 40.327834 -10.634218)
					(mid 40.711374 -10.250678)
					(end 40.327834 -9.867138)
				)
			)
		)
	)
	(zone
		(net "PVNN")
		(layer "In9.Cu")
		(hatch none 0.5)
		(connect_pads
			(clearance 0.5)
		)
		(min_thickness 0.25)
		(fill yes
			(thermal_gap 0.5)
			(thermal_bridge_width 0.5)
			(island_removal_mode 0)
		)
		(polygon
			(pts
				(xy 91.948 -50.8) (xy 91.948 -54.991) (xy 91.948 -56.388) (xy 92.71 -57.15) (xy 95.25 -57.15) (xy 96.139 -58.039)
				(xy 98.679 -58.039) (xy 98.8695 -58.2295) (xy 99.441 -58.801) (xy 102.489 -61.849) (xy 102.489 -62.611)
				(xy 102.235 -62.865) (xy 101.854 -63.246) (xy 92.202 -63.246) (xy 92.075 -63.373) (xy 90.932 -64.516)
				(xy 83.185 -64.516) (xy 82.804 -64.516) (xy 82.3595 -64.9605) (xy 77.9145 -64.9605) (xy 77.089 -64.135)
				(xy 76.581 -64.135) (xy 76.327 -64.389) (xy 76.0095 -64.7065) (xy 73.4695 -64.7065) (xy 73.152 -65.024)
				(xy 69.723 -65.024) (xy 67.183 -65.024) (xy 65.024 -62.865) (xy 64.77 -62.865) (xy 64.643 -62.865)
				(xy 55.753 -62.865) (xy 54.737 -63.881) (xy 54.61 -64.008) (xy 54.61 -65.913) (xy 55.118 -66.421)
				(xy 56.261 -66.421) (xy 59.055 -69.215) (xy 60.325 -69.215) (xy 68.199 -69.215) (xy 70.993 -69.215)
				(xy 72.136 -68.072) (xy 76.962 -68.072) (xy 77.978 -67.056) (xy 78.232 -67.056) (xy 82.931 -67.056)
				(xy 83.312 -67.056) (xy 83.693 -67.056) (xy 84.328 -66.421) (xy 84.836 -66.421) (xy 92.075 -66.421)
				(xy 92.456 -66.04) (xy 93.091 -65.405) (xy 104.013 -65.405) (xy 105.41 -64.008) (xy 105.41 -61.722)
				(xy 104.648 -60.96) (xy 101.346 -57.658) (xy 101.346 -57.023) (xy 101.981 -56.388) (xy 101.981 -53.848)
				(xy 101.727 -53.594) (xy 101.473 -53.594) (xy 98.679 -50.8) (xy 98.679 -49.403) (xy 98.679 -48.26)
				(xy 99.441 -47.498) (xy 99.441 -45.593) (xy 99.441 -42.799) (xy 100.076 -42.164) (xy 100.076 -41.91)
				(xy 99.822 -41.656) (xy 97.028 -41.656) (xy 96.52 -41.656) (xy 95.504 -40.64) (xy 95.504 -40.132)
				(xy 94.742 -39.37) (xy 94.107 -39.37) (xy 91.948 -41.529)
			)
		)
	)
	(zone
		(net "PV_VDDR")
		(layer "In9.Cu")
		(hatch none 0.5)
		(connect_pads
			(clearance 0.5)
		)
		(min_thickness 0.25)
		(fill yes
			(thermal_gap 0.5)
			(thermal_bridge_width 0.5)
			(island_removal_mode 0)
		)
		(polygon
			(pts
				(xy 191.008 -1.397) (xy 191.008 -7.874) (xy 182.626 -16.256) (xy 182.626 -17.018) (xy 183.1975 -17.5895)
				(xy 191.0715 -17.5895) (xy 195.961 -12.7) (xy 195.961 -8.255) (xy 195.961 -8.001) (xy 197.358 -6.604)
				(xy 197.612 -6.604) (xy 200.406 -6.604) (xy 201.041 -5.969) (xy 201.295 -5.715) (xy 204.978 -5.715)
				(xy 205.232 -5.969) (xy 205.613 -6.35) (xy 205.613 -17.907) (xy 205.613 -29.464) (xy 204.724 -30.353)
				(xy 204.47 -30.353) (xy 203.073 -30.353) (xy 202.692 -30.734) (xy 202.692 -32.004) (xy 202.692 -32.512)
				(xy 204.089 -33.909) (xy 204.089 -37.973) (xy 199.517 -42.545) (xy 195.326 -46.736) (xy 195.326 -52.197)
				(xy 191.262 -56.261) (xy 190.627 -56.896) (xy 188.214 -56.896) (xy 187.071 -55.753) (xy 168.402 -55.753)
				(xy 166.624 -57.531) (xy 164.338 -57.531) (xy 162.687 -59.182) (xy 162.687 -67.437) (xy 162.433 -67.691)
				(xy 156.972 -67.691) (xy 156.21 -68.453) (xy 154.94 -68.453) (xy 154.686 -68.453) (xy 154.305 -68.072)
				(xy 154.051 -67.818) (xy 153.543 -67.818) (xy 153.289 -68.072) (xy 151.003 -68.072) (xy 150.749 -68.326)
				(xy 150.749 -69.596) (xy 151.384 -70.231) (xy 191.643 -70.231) (xy 192.659 -69.215) (xy 194.437 -69.215)
				(xy 195.072 -68.58) (xy 201.803 -68.58) (xy 204.851 -65.532) (xy 204.851 -51.816) (xy 209.169 -47.498)
				(xy 209.169 -3.683) (xy 206.375 -0.889) (xy 206.248 -0.762) (xy 191.389 -0.762) (xy 191.008 -1.143)
			)
		)
		(polygon
			(pts
				(xy 198.755 -48.26) (xy 198.755 -51.308) (xy 198.755 -51.816) (xy 199.644 -52.705) (xy 199.644 -55.88)
				(xy 200.152 -56.388) (xy 200.914 -56.388) (xy 201.295 -56.007) (xy 201.295 -52.959) (xy 201.422 -52.832)
				(xy 201.93 -52.832) (xy 202.311 -52.451) (xy 202.311 -51.816) (xy 202.311 -51.562) (xy 202.184 -51.435)
				(xy 202.184 -49.53) (xy 203.581 -48.133) (xy 203.581 -47.244) (xy 203.2 -46.863) (xy 202.819 -46.863)
				(xy 200.025 -46.863) (xy 199.644 -46.863) (xy 198.755 -47.752) (xy 198.755 -48.133)
			)
		)
	)
	(zone
		(net "GND")
		(layer "In9.Cu")
		(hatch none 0.5)
		(connect_pads
			(clearance 0.5)
		)
		(min_thickness 0.25)
		(fill yes
			(thermal_gap 0.5)
			(thermal_bridge_width 0.5)
			(island_removal_mode 0)
		)
		(polygon
			(pts
				(xy 10.033 -56.515) (xy 10.033 -66.04) (xy 10.287 -66.294) (xy 10.541 -66.294) (xy 10.668 -66.167)
				(xy 10.668 -53.721) (xy 14.351 -50.038) (xy 14.351 -49.022) (xy 22.352 -41.021) (xy 22.352 -33.274)
				(xy 25.527 -30.099) (xy 25.527 -26.543) (xy 27.178 -24.892) (xy 27.178 -23.114) (xy 25.4 -21.336)
				(xy 17.272 -21.336) (xy 15.621 -22.987) (xy 14.859 -22.987) (xy 14.478 -22.987) (xy 14.351 -23.114)
				(xy 11.303 -26.162) (xy 11.303 -26.797) (xy 10.795 -27.305) (xy 7.874 -27.305) (xy 7.239 -27.94)
				(xy 7.239 -29.972) (xy 7.239 -33.401) (xy 8.255 -34.417) (xy 8.255 -41.656) (xy 8.255 -43.307) (xy 8.636 -43.688)
				(xy 8.636 -49.149) (xy 8.509 -49.276) (xy 7.493 -49.276) (xy 7.112 -49.657) (xy 7.112 -50.419) (xy 7.112 -53.594)
				(xy 7.493 -53.975) (xy 8.636 -55.118) (xy 9.779 -55.118) (xy 10.033 -55.372)
			)
		)
	)
	(zone
		(net "GND")
		(layer "In9.Cu")
		(hatch none 0.5)
		(connect_pads
			(clearance 0.5)
		)
		(min_thickness 0.25)
		(fill yes
			(thermal_gap 0.5)
			(thermal_bridge_width 0.5)
			(island_removal_mode 0)
		)
		(polygon
			(pts
				(xy 43.815 -55.372) (xy 49.784 -55.372) (xy 51.562 -55.372) (xy 53.086 -56.896) (xy 53.086 -65.405)
				(xy 52.07 -66.421) (xy 47.244 -66.421) (xy 44.323 -66.421) (xy 41.402 -69.342) (xy 30.48 -69.342)
				(xy 21.209 -69.342) (xy 20.193 -69.342) (xy 18.542 -67.691) (xy 17.272 -67.691) (xy 16.383 -66.802)
				(xy 16.383 -58.039) (xy 19.05 -55.372) (xy 19.812 -55.372) (xy 40.894 -55.372)
			)
		)
	)
	(zone
		(net "GND")
		(layer "In9.Cu")
		(hatch none 0.5)
		(connect_pads
			(clearance 0.5)
		)
		(min_thickness 0.25)
		(fill yes
			(thermal_gap 0.5)
			(thermal_bridge_width 0.5)
			(island_removal_mode 0)
		)
		(polygon
			(pts
				(xy 148.336 -62.357) (xy 148.336 -62.992) (xy 148.336 -69.85) (xy 147.955 -70.231) (xy 114.808 -70.231)
				(xy 114.554 -70.231) (xy 114.3 -69.977) (xy 114.3 -68.453) (xy 114.046 -68.199) (xy 109.855 -68.199)
				(xy 107.061 -65.405) (xy 107.061 -64.77) (xy 108.839 -62.992) (xy 110.236 -62.992) (xy 111.379 -61.849)
				(xy 111.76 -61.468) (xy 144.272 -61.468) (xy 144.526 -61.722) (xy 147.828 -61.722) (xy 148.336 -62.23)
			)
		)
	)
	(zone
		(layer "In9.Cu")
		(hatch none 0.5)
		(connect_pads
			(clearance 0)
		)
		(min_thickness 0.25)
		(keepout
			(tracks not_allowed)
			(vias allowed)
			(pads allowed)
			(copperpour not_allowed)
			(footprints allowed)
		)
		(placement
			(enabled no)
			(sheetname "")
		)
		(fill
			(thermal_gap 0.5)
			(thermal_bridge_width 0.5)
			(island_removal_mode 0)
		)
		(polygon
			(pts
				(arc
					(start 82.296254 -13.56106)
					(mid 81.91246 -13.944473)
					(end 82.296 -14.32814)
				)
				(xy 82.48015 -14.32814) (xy 82.48015 -14.227556)
				(arc
					(start 82.428588 -14.175994)
					(mid 82.107423 -13.756023)
					(end 82.527394 -14.077188)
				)
				(xy 82.61985 -14.169644) (xy 82.61985 -14.32814) (xy 82.81035 -14.32814) (xy 82.81035 -14.195044)
				(xy 82.83575 -14.169644)
				(arc
					(start 82.928206 -14.077188)
					(mid 83.348177 -13.756023)
					(end 83.027012 -14.175994)
				)
				(xy 83.007962 -14.195044) (xy 82.95005 -14.252956) (xy 82.95005 -14.32814)
				(arc
					(start 83.1596 -14.32814)
					(mid 83.54314 -13.9446)
					(end 83.1596 -13.56106)
				)
			)
		)
	)
	(zone
		(net "GND")
		(layer "In9.Cu")
		(hatch none 0.5)
		(connect_pads
			(clearance 0.5)
		)
		(min_thickness 0.25)
		(fill yes
			(thermal_gap 0.5)
			(thermal_bridge_width 0.5)
			(island_removal_mode 0)
		)
		(polygon
			(pts
				(xy 28.956 -46.228) (xy 28.956 -48.514) (xy 29.845 -49.403) (xy 32.385 -49.403) (xy 33.02 -49.403)
				(xy 34.544 -49.403) (xy 34.925 -49.022) (xy 35.941 -49.022) (xy 36.322 -49.403) (xy 36.322 -50.165)
				(xy 35.814 -50.673) (xy 34.671 -51.816) (xy 33.147 -51.816) (xy 32.893 -52.07) (xy 32.893 -52.705)
				(xy 33.782 -53.594) (xy 35.179 -53.594) (xy 35.56 -53.213) (xy 35.56 -52.705) (xy 36.068 -52.197)
				(xy 36.576 -52.197) (xy 37.211 -52.197) (xy 37.465 -52.197) (xy 37.973 -52.705) (xy 40.386 -52.705)
				(xy 41.148 -53.467) (xy 45.974 -53.467) (xy 46.228 -53.213) (xy 46.228 -52.832) (xy 43.307 -49.911)
				(xy 43.307 -48.26) (xy 46.1137 -45.4533) (xy 46.1137 -44.6913) (xy 45.7454 -44.323) (xy 44.704 -44.323)
				(xy 44.577 -44.196) (xy 44.45 -44.069) (xy 44.069 -44.069) (xy 42.926 -45.212) (xy 42.926 -46.609)
				(xy 42.545 -46.99) (xy 41.783 -46.99) (xy 40.386 -45.593) (xy 40.132 -45.339) (xy 40.132 -42.926)
				(xy 38.735 -41.529) (xy 35.179 -41.529) (xy 34.163 -41.529) (xy 33.909 -41.783) (xy 33.782 -41.91)
				(xy 33.782 -42.926) (xy 33.528 -43.18) (xy 33.147 -43.18) (xy 32.893 -42.926) (xy 32.258 -42.926)
			)
		)
	)
	(zone
		(net "PV_VDDR")
		(layer "In10.Cu")
		(hatch none 0.5)
		(connect_pads
			(clearance 0.5)
		)
		(min_thickness 0.25)
		(fill yes
			(thermal_gap 0.5)
			(thermal_bridge_width 0.5)
			(island_removal_mode 0)
		)
		(polygon
			(pts
				(xy 155.8925 -0.763016) (xy 155.8925 -10.746994) (xy 155.145994 -11.4935) (xy 133.936994 -11.4935)
				(xy 131.5085 -13.921994) (xy 131.396994 -14.0335) (xy 114.251994 -14.0335) (xy 108.409994 -19.8755)
				(xy 101.424994 -19.8755) (xy 98.884994 -22.4155) (xy 98.831146 -22.4155) (xy 98.615246 -22.6314)
				(xy 98.234246 -22.6314) (xy 98.0694 -22.796246) (xy 98.0694 -25.463246) (xy 97.5614 -25.971246)
				(xy 97.5614 -31.940754) (xy 97.726246 -32.1056) (xy 98.234246 -32.1056) (xy 98.742246 -32.6136)
				(xy 99.250246 -32.6136) (xy 100.139246 -33.5026) (xy 103.949754 -33.5026) (xy 104.584754 -32.8676)
				(xy 109.675676 -32.8676) (xy 109.855508 -32.727646) (xy 109.893354 -32.6898) (xy 109.904276 -32.6898)
				(xy 109.912912 -32.683196) (xy 109.965998 -32.6898) (xy 110.858046 -32.6898) (xy 111.162846 -32.9946)
				(xy 112.331754 -32.9946) (xy 114.490754 -30.8356) (xy 117.738906 -30.8356) (xy 118.920006 -29.6545)
				(xy 158.290006 -29.6545) (xy 162.481514 -25.463246) (xy 172.7835 -15.161006) (xy 172.7835 -11.508994)
				(xy 172.260006 -10.9855) (xy 170.482006 -10.9855) (xy 170.2435 -10.746994) (xy 169.8625 -10.365994)
				(xy 169.8625 -6.017006) (xy 170.4975 -5.382006) (xy 170.4975 -4.523994) (xy 169.8625 -3.888994)
				(xy 169.8625 -0.763016)
			)
		)
	)
	(zone
		(layer "In10.Cu")
		(hatch none 0.5)
		(connect_pads
			(clearance 0)
		)
		(min_thickness 0.25)
		(keepout
			(tracks not_allowed)
			(vias allowed)
			(pads allowed)
			(copperpour not_allowed)
			(footprints allowed)
		)
		(placement
			(enabled no)
			(sheetname "")
		)
		(fill
			(thermal_gap 0.5)
			(thermal_bridge_width 0.5)
			(island_removal_mode 0)
		)
		(polygon
			(pts
				(xy 29.991812 -4.097528) (xy 30.708092 -4.097528) (xy 30.708092 -8.293608) (xy 29.991812 -8.293608)
			)
		)
	)
	(zone
		(layer "In10.Cu")
		(hatch none 0.5)
		(connect_pads
			(clearance 0)
		)
		(min_thickness 0.25)
		(keepout
			(tracks not_allowed)
			(vias allowed)
			(pads allowed)
			(copperpour not_allowed)
			(footprints allowed)
		)
		(placement
			(enabled no)
			(sheetname "")
		)
		(fill
			(thermal_gap 0.5)
			(thermal_bridge_width 0.5)
			(island_removal_mode 0)
		)
		(polygon
			(pts
				(arc
					(start 45.97146 -12.4968)
					(mid 45.987083 -12.534517)
					(end 46.0248 -12.55014)
				)
				(arc
					(start 46.4312 -12.55014)
					(mid 46.468917 -12.534517)
					(end 46.48454 -12.4968)
				)
				(arc
					(start 46.48454 -12.1412)
					(mid 46.468917 -12.103483)
					(end 46.4312 -12.08786)
				)
				(arc
					(start 46.0248 -12.08786)
					(mid 45.987083 -12.103483)
					(end 45.97146 -12.1412)
				)
			)
		)
	)
	(zone
		(layer "In10.Cu")
		(hatch none 0.5)
		(connect_pads
			(clearance 0)
		)
		(min_thickness 0.25)
		(keepout
			(tracks not_allowed)
			(vias allowed)
			(pads allowed)
			(copperpour not_allowed)
			(footprints allowed)
		)
		(placement
			(enabled no)
			(sheetname "")
		)
		(fill
			(thermal_gap 0.5)
			(thermal_bridge_width 0.5)
			(island_removal_mode 0)
		)
		(polygon
			(pts
				(xy 25.99182 -4.097528) (xy 26.7081 -4.097528) (xy 26.7081 -8.293608) (xy 25.99182 -8.293608)
			)
		)
	)
	(zone
		(layer "In10.Cu")
		(hatch none 0.5)
		(connect_pads
			(clearance 0)
		)
		(min_thickness 0.25)
		(keepout
			(tracks not_allowed)
			(vias allowed)
			(pads allowed)
			(copperpour not_allowed)
			(footprints allowed)
		)
		(placement
			(enabled no)
			(sheetname "")
		)
		(fill
			(thermal_gap 0.5)
			(thermal_bridge_width 0.5)
			(island_removal_mode 0)
		)
		(polygon
			(pts
				(arc
					(start 67.7418 -27.81554)
					(mid 67.779517 -27.799917)
					(end 67.79514 -27.7622)
				)
				(arc
					(start 67.79514 -27.3558)
					(mid 67.779517 -27.318083)
					(end 67.7418 -27.30246)
				)
				(arc
					(start 67.3862 -27.30246)
					(mid 67.348483 -27.318083)
					(end 67.33286 -27.3558)
				)
				(arc
					(start 67.33286 -27.7622)
					(mid 67.348483 -27.799917)
					(end 67.3862 -27.81554)
				)
			)
		)
	)
	(zone
		(layer "In10.Cu")
		(hatch none 0.5)
		(connect_pads
			(clearance 0)
		)
		(min_thickness 0.25)
		(keepout
			(tracks not_allowed)
			(vias allowed)
			(pads allowed)
			(copperpour not_allowed)
			(footprints allowed)
		)
		(placement
			(enabled no)
			(sheetname "")
		)
		(fill
			(thermal_gap 0.5)
			(thermal_bridge_width 0.5)
			(island_removal_mode 0)
		)
		(polygon
			(pts
				(arc
					(start 80.76946 -14.0208)
					(mid 80.785083 -14.058517)
					(end 80.8228 -14.07414)
				)
				(arc
					(start 81.2292 -14.07414)
					(mid 81.266917 -14.058517)
					(end 81.28254 -14.0208)
				)
				(arc
					(start 81.28254 -13.6652)
					(mid 81.266917 -13.627483)
					(end 81.2292 -13.61186)
				)
				(arc
					(start 80.8228 -13.61186)
					(mid 80.785083 -13.627483)
					(end 80.76946 -13.6652)
				)
			)
		)
	)
	(zone
		(net "P12V")
		(layer "In10.Cu")
		(hatch none 0.5)
		(connect_pads
			(clearance 0.5)
		)
		(min_thickness 0.25)
		(fill yes
			(thermal_gap 0.5)
			(thermal_bridge_width 0.5)
			(island_removal_mode 0)
		)
		(polygon
			(pts
				(xy 46.179994 -67.3735) (xy 42.369994 -71.1835) (xy 23.446994 -71.1835) (xy 22.7965 -71.833994)
				(xy 22.7965 -73.036938) (xy 73.5965 -73.036938) (xy 73.5965 -70.4215) (xy 58.722006 -70.4215) (xy 55.674006 -67.3735)
			)
		)
	)
	(zone
		(layer "In10.Cu")
		(hatch none 0.5)
		(connect_pads
			(clearance 0)
		)
		(min_thickness 0.25)
		(keepout
			(tracks not_allowed)
			(vias allowed)
			(pads allowed)
			(copperpour not_allowed)
			(footprints allowed)
		)
		(placement
			(enabled no)
			(sheetname "")
		)
		(fill
			(thermal_gap 0.5)
			(thermal_bridge_width 0.5)
			(island_removal_mode 0)
		)
		(polygon
			(pts
				(xy 6.349746 -65.602358) (xy 6.349746 -64.797432) (xy 4.800346 -64.797432) (xy 4.800346 -65.602104)
				(xy 4.8006 -65.602358)
			)
		)
	)
	(zone
		(layer "In10.Cu")
		(hatch none 0.5)
		(connect_pads
			(clearance 0)
		)
		(min_thickness 0.25)
		(keepout
			(tracks not_allowed)
			(vias allowed)
			(pads allowed)
			(copperpour not_allowed)
			(footprints allowed)
		)
		(placement
			(enabled no)
			(sheetname "")
		)
		(fill
			(thermal_gap 0.5)
			(thermal_bridge_width 0.5)
			(island_removal_mode 0)
		)
		(polygon
			(pts
				(arc
					(start 68.57746 -14.1478)
					(mid 68.593083 -14.185517)
					(end 68.6308 -14.20114)
				)
				(arc
					(start 69.0372 -14.20114)
					(mid 69.074917 -14.185517)
					(end 69.09054 -14.1478)
				)
				(arc
					(start 69.09054 -13.7922)
					(mid 69.074917 -13.754483)
					(end 69.0372 -13.73886)
				)
				(arc
					(start 68.6308 -13.73886)
					(mid 68.593083 -13.754483)
					(end 68.57746 -13.7922)
				)
			)
		)
	)
	(zone
		(net "PVNN")
		(layer "In10.Cu")
		(hatch none 0.5)
		(connect_pads
			(clearance 0.5)
		)
		(min_thickness 0.25)
		(fill yes
			(thermal_gap 0.5)
			(thermal_bridge_width 0.5)
			(island_removal_mode 0)
		)
		(polygon
			(pts
				(xy 92.534994 -39.3065) (xy 92.2655 -39.575994) (xy 92.2655 -55.039006) (xy 92.6465 -55.420006)
				(xy 92.6465 -56.309006) (xy 94.058994 -57.7215) (xy 98.757994 -57.7215) (xy 102.948994 -61.9125)
				(xy 103.329994 -61.9125) (xy 103.6955 -62.278006) (xy 103.6955 -62.943994) (xy 103.202994 -63.4365)
				(xy 93.042994 -63.4365) (xy 91.137994 -65.3415) (xy 83.009994 -65.3415) (xy 82.247994 -66.1035)
				(xy 79.804006 -66.1035) (xy 79.042006 -65.3415) (xy 67.231006 -65.3415) (xy 65.580006 -63.6905)
				(xy 54.942994 -63.6905) (xy 54.6735 -63.959994) (xy 54.6735 -65.834006) (xy 58.879994 -70.0405)
				(xy 74.470006 -70.0405) (xy 74.978006 -69.5325) (xy 85.519006 -69.5325) (xy 86.916006 -68.1355)
				(xy 93.139006 -68.1355) (xy 93.901006 -67.3735) (xy 99.616006 -67.3735) (xy 100.886006 -66.1035)
				(xy 103.934006 -66.1035) (xy 105.6005 -64.437006) (xy 105.6005 -62.278006) (xy 105.8545 -62.024006)
				(xy 105.8545 -61.419994) (xy 105.585006 -61.1505) (xy 104.696006 -61.1505) (xy 101.1555 -57.609994)
				(xy 101.1555 -57.452006) (xy 101.1936 -57.413906) (xy 101.1936 -56.832754) (xy 101.7016 -56.324754)
				(xy 101.7016 -54.165246) (xy 98.3996 -50.863246) (xy 98.3996 -45.275754) (xy 98.996754 -44.6786)
				(xy 100.7745 -44.6786) (xy 100.7745 -42.369994) (xy 100.124006 -41.7195) (xy 98.092006 -41.7195)
				(xy 97.457006 -41.0845) (xy 96.949006 -41.0845) (xy 96.060006 -40.1955) (xy 95.425006 -40.1955)
				(xy 94.536006 -39.3065)
			)
		)
	)
	(zone
		(layer "In10.Cu")
		(hatch none 0.5)
		(connect_pads
			(clearance 0)
		)
		(min_thickness 0.25)
		(keepout
			(tracks not_allowed)
			(vias allowed)
			(pads allowed)
			(copperpour not_allowed)
			(footprints allowed)
		)
		(placement
			(enabled no)
			(sheetname "")
		)
		(fill
			(thermal_gap 0.5)
			(thermal_bridge_width 0.5)
			(island_removal_mode 0)
		)
		(polygon
			(pts
				(arc
					(start 20.69846 -13.2588)
					(mid 20.714083 -13.296517)
					(end 20.7518 -13.31214)
				)
				(arc
					(start 21.1582 -13.31214)
					(mid 21.195917 -13.296517)
					(end 21.21154 -13.2588)
				)
				(arc
					(start 21.21154 -12.9032)
					(mid 21.195917 -12.865483)
					(end 21.1582 -12.84986)
				)
				(arc
					(start 20.7518 -12.84986)
					(mid 20.714083 -12.865483)
					(end 20.69846 -12.9032)
				)
			)
		)
	)
	(zone
		(layer "In10.Cu")
		(hatch none 0.5)
		(connect_pads
			(clearance 0)
		)
		(min_thickness 0.25)
		(keepout
			(tracks not_allowed)
			(vias allowed)
			(pads allowed)
			(copperpour not_allowed)
			(footprints allowed)
		)
		(placement
			(enabled no)
			(sheetname "")
		)
		(fill
			(thermal_gap 0.5)
			(thermal_bridge_width 0.5)
			(island_removal_mode 0)
		)
		(polygon
			(pts
				(xy 68.991734 -4.097528) (xy 69.708014 -4.097528) (xy 69.708014 -8.293608) (xy 68.991734 -8.293608)
			)
		)
	)
	(zone
		(layer "In10.Cu")
		(hatch none 0.5)
		(connect_pads
			(clearance 0)
		)
		(min_thickness 0.25)
		(keepout
			(tracks not_allowed)
			(vias allowed)
			(pads allowed)
			(copperpour not_allowed)
			(footprints allowed)
		)
		(placement
			(enabled no)
			(sheetname "")
		)
		(fill
			(thermal_gap 0.5)
			(thermal_bridge_width 0.5)
			(island_removal_mode 0)
		)
		(polygon
			(pts
				(arc
					(start 29.20746 -12.4968)
					(mid 29.223083 -12.534517)
					(end 29.2608 -12.55014)
				)
				(arc
					(start 29.6672 -12.55014)
					(mid 29.704917 -12.534517)
					(end 29.72054 -12.4968)
				)
				(arc
					(start 29.72054 -12.1412)
					(mid 29.704917 -12.103483)
					(end 29.6672 -12.08786)
				)
				(arc
					(start 29.2608 -12.08786)
					(mid 29.223083 -12.103483)
					(end 29.20746 -12.1412)
				)
			)
		)
	)
	(zone
		(layer "In10.Cu")
		(hatch none 0.5)
		(connect_pads
			(clearance 0)
		)
		(min_thickness 0.25)
		(keepout
			(tracks not_allowed)
			(vias allowed)
			(pads allowed)
			(copperpour not_allowed)
			(footprints allowed)
		)
		(placement
			(enabled no)
			(sheetname "")
		)
		(fill
			(thermal_gap 0.5)
			(thermal_bridge_width 0.5)
			(island_removal_mode 0)
		)
		(polygon
			(pts
				(xy 76.991718 -4.097528) (xy 77.707998 -4.097528) (xy 77.707998 -8.293608) (xy 76.991718 -8.293608)
			)
		)
	)
	(zone
		(layer "In10.Cu")
		(hatch none 0.5)
		(connect_pads
			(clearance 0)
		)
		(min_thickness 0.25)
		(keepout
			(tracks not_allowed)
			(vias allowed)
			(pads allowed)
			(copperpour not_allowed)
			(footprints allowed)
		)
		(placement
			(enabled no)
			(sheetname "")
		)
		(fill
			(thermal_gap 0.5)
			(thermal_bridge_width 0.5)
			(island_removal_mode 0)
		)
		(polygon
			(pts
				(arc
					(start 19.93646 -12.4968)
					(mid 19.952083 -12.534517)
					(end 19.9898 -12.55014)
				)
				(arc
					(start 20.3962 -12.55014)
					(mid 20.433917 -12.534517)
					(end 20.44954 -12.4968)
				)
				(arc
					(start 20.44954 -12.1412)
					(mid 20.433917 -12.103483)
					(end 20.3962 -12.08786)
				)
				(arc
					(start 19.9898 -12.08786)
					(mid 19.952083 -12.103483)
					(end 19.93646 -12.1412)
				)
			)
		)
	)
	(zone
		(layer "In10.Cu")
		(hatch none 0.5)
		(connect_pads
			(clearance 0)
		)
		(min_thickness 0.25)
		(keepout
			(tracks not_allowed)
			(vias allowed)
			(pads allowed)
			(copperpour not_allowed)
			(footprints allowed)
		)
		(placement
			(enabled no)
			(sheetname "")
		)
		(fill
			(thermal_gap 0.5)
			(thermal_bridge_width 0.5)
			(island_removal_mode 0)
		)
		(polygon
			(pts
				(xy 33.991804 -4.097528) (xy 34.708084 -4.097528) (xy 34.708084 -8.293608) (xy 33.991804 -8.293608)
			)
		)
	)
	(zone
		(layer "In10.Cu")
		(hatch none 0.5)
		(connect_pads
			(clearance 0)
		)
		(min_thickness 0.25)
		(keepout
			(tracks not_allowed)
			(vias allowed)
			(pads allowed)
			(copperpour not_allowed)
			(footprints allowed)
		)
		(placement
			(enabled no)
			(sheetname "")
		)
		(fill
			(thermal_gap 0.5)
			(thermal_bridge_width 0.5)
			(island_removal_mode 0)
		)
		(polygon
			(pts
				(xy 45.99178 -4.097528) (xy 46.70806 -4.097528) (xy 46.70806 -8.293608) (xy 45.99178 -8.293608)
			)
		)
	)
	(zone
		(layer "In10.Cu")
		(hatch none 0.5)
		(connect_pads
			(clearance 0)
		)
		(min_thickness 0.25)
		(keepout
			(tracks not_allowed)
			(vias allowed)
			(pads allowed)
			(copperpour not_allowed)
			(footprints allowed)
		)
		(placement
			(enabled no)
			(sheetname "")
		)
		(fill
			(thermal_gap 0.5)
			(thermal_bridge_width 0.5)
			(island_removal_mode 0)
		)
		(polygon
			(pts
				(arc
					(start 72.64146 -14.1478)
					(mid 72.657083 -14.185517)
					(end 72.6948 -14.20114)
				)
				(arc
					(start 73.1012 -14.20114)
					(mid 73.138917 -14.185517)
					(end 73.15454 -14.1478)
				)
				(arc
					(start 73.15454 -13.7922)
					(mid 73.138917 -13.754483)
					(end 73.1012 -13.73886)
				)
				(arc
					(start 72.6948 -13.73886)
					(mid 72.657083 -13.754483)
					(end 72.64146 -13.7922)
				)
			)
		)
	)
	(zone
		(layer "In10.Cu")
		(hatch none 0.5)
		(connect_pads
			(clearance 0)
		)
		(min_thickness 0.25)
		(keepout
			(tracks not_allowed)
			(vias allowed)
			(pads allowed)
			(copperpour not_allowed)
			(footprints allowed)
		)
		(placement
			(enabled no)
			(sheetname "")
		)
		(fill
			(thermal_gap 0.5)
			(thermal_bridge_width 0.5)
			(island_removal_mode 0)
		)
		(polygon
			(pts
				(xy 61.991748 -4.097528) (xy 62.708028 -4.097528) (xy 62.708028 -8.293608) (xy 61.991748 -8.293608)
			)
		)
	)
	(zone
		(layer "In10.Cu")
		(hatch none 0.5)
		(connect_pads
			(clearance 0)
		)
		(min_thickness 0.25)
		(keepout
			(tracks not_allowed)
			(vias allowed)
			(pads allowed)
			(copperpour not_allowed)
			(footprints allowed)
		)
		(placement
			(enabled no)
			(sheetname "")
		)
		(fill
			(thermal_gap 0.5)
			(thermal_bridge_width 0.5)
			(island_removal_mode 0)
		)
		(polygon
			(pts
				(xy 6.349746 -55.102252) (xy 6.349746 -54.29758) (xy 4.800346 -54.29758) (xy 4.800346 -55.101998)
				(xy 4.8006 -55.102252)
			)
		)
	)
	(zone
		(layer "In10.Cu")
		(hatch none 0.5)
		(connect_pads
			(clearance 0)
		)
		(min_thickness 0.25)
		(keepout
			(tracks not_allowed)
			(vias allowed)
			(pads allowed)
			(copperpour not_allowed)
			(footprints allowed)
		)
		(placement
			(enabled no)
			(sheetname "")
		)
		(fill
			(thermal_gap 0.5)
			(thermal_bridge_width 0.5)
			(island_removal_mode 0)
		)
		(polygon
			(pts
				(arc
					(start 41.974262 -13.2588)
					(mid 41.989885 -13.296517)
					(end 42.027602 -13.31214)
				)
				(arc
					(start 42.434002 -13.31214)
					(mid 42.471719 -13.296517)
					(end 42.487342 -13.2588)
				)
				(arc
					(start 42.487342 -12.9032)
					(mid 42.471719 -12.865483)
					(end 42.434002 -12.84986)
				)
				(arc
					(start 42.027602 -12.84986)
					(mid 41.989885 -12.865483)
					(end 41.974262 -12.9032)
				)
			)
		)
	)
	(zone
		(layer "In10.Cu")
		(hatch none 0.5)
		(connect_pads
			(clearance 0)
		)
		(min_thickness 0.25)
		(keepout
			(tracks not_allowed)
			(vias allowed)
			(pads allowed)
			(copperpour not_allowed)
			(footprints allowed)
		)
		(placement
			(enabled no)
			(sheetname "")
		)
		(fill
			(thermal_gap 0.5)
			(thermal_bridge_width 0.5)
			(island_removal_mode 0)
		)
		(polygon
			(pts
				(arc
					(start 37.97427 -12.4968)
					(mid 37.989893 -12.534517)
					(end 38.02761 -12.55014)
				)
				(arc
					(start 38.43401 -12.55014)
					(mid 38.471727 -12.534517)
					(end 38.48735 -12.4968)
				)
				(arc
					(start 38.48735 -12.1412)
					(mid 38.471727 -12.103483)
					(end 38.43401 -12.08786)
				)
				(arc
					(start 38.02761 -12.08786)
					(mid 37.989893 -12.103483)
					(end 37.97427 -12.1412)
				)
			)
		)
	)
	(zone
		(layer "In10.Cu")
		(hatch none 0.5)
		(connect_pads
			(clearance 0)
		)
		(min_thickness 0.25)
		(keepout
			(tracks not_allowed)
			(vias allowed)
			(pads allowed)
			(copperpour not_allowed)
			(footprints allowed)
		)
		(placement
			(enabled no)
			(sheetname "")
		)
		(fill
			(thermal_gap 0.5)
			(thermal_bridge_width 0.5)
			(island_removal_mode 0)
		)
		(polygon
			(pts
				(arc
					(start 67.7418 -30.78734)
					(mid 67.779517 -30.771717)
					(end 67.79514 -30.734)
				)
				(arc
					(start 67.79514 -30.3276)
					(mid 67.779517 -30.289883)
					(end 67.7418 -30.27426)
				)
				(arc
					(start 67.3862 -30.27426)
					(mid 67.348483 -30.289883)
					(end 67.33286 -30.3276)
				)
				(arc
					(start 67.33286 -30.734)
					(mid 67.348483 -30.771717)
					(end 67.3862 -30.78734)
				)
			)
		)
	)
	(zone
		(layer "In10.Cu")
		(hatch none 0.5)
		(connect_pads
			(clearance 0)
		)
		(min_thickness 0.25)
		(keepout
			(tracks not_allowed)
			(vias allowed)
			(pads allowed)
			(copperpour not_allowed)
			(footprints allowed)
		)
		(placement
			(enabled no)
			(sheetname "")
		)
		(fill
			(thermal_gap 0.5)
			(thermal_bridge_width 0.5)
			(island_removal_mode 0)
		)
		(polygon
			(pts
				(arc
					(start 80.00746 -14.0208)
					(mid 80.023083 -14.058517)
					(end 80.0608 -14.07414)
				)
				(arc
					(start 80.4672 -14.07414)
					(mid 80.504917 -14.058517)
					(end 80.52054 -14.0208)
				)
				(arc
					(start 80.52054 -13.6652)
					(mid 80.504917 -13.627483)
					(end 80.4672 -13.61186)
				)
				(arc
					(start 80.0608 -13.61186)
					(mid 80.023083 -13.627483)
					(end 80.00746 -13.6652)
				)
			)
		)
	)
	(zone
		(layer "In10.Cu")
		(hatch none 0.5)
		(connect_pads
			(clearance 0)
		)
		(min_thickness 0.25)
		(keepout
			(tracks not_allowed)
			(vias allowed)
			(pads allowed)
			(copperpour not_allowed)
			(footprints allowed)
		)
		(placement
			(enabled no)
			(sheetname "")
		)
		(fill
			(thermal_gap 0.5)
			(thermal_bridge_width 0.5)
			(island_removal_mode 0)
		)
		(polygon
			(pts
				(arc
					(start 19.93646 -13.2588)
					(mid 19.952083 -13.296517)
					(end 19.9898 -13.31214)
				)
				(arc
					(start 20.3962 -13.31214)
					(mid 20.433917 -13.296517)
					(end 20.44954 -13.2588)
				)
				(arc
					(start 20.44954 -12.9032)
					(mid 20.433917 -12.865483)
					(end 20.3962 -12.84986)
				)
				(arc
					(start 19.9898 -12.84986)
					(mid 19.952083 -12.865483)
					(end 19.93646 -12.9032)
				)
			)
		)
	)
	(zone
		(layer "In10.Cu")
		(hatch none 0.5)
		(connect_pads
			(clearance 0)
		)
		(min_thickness 0.25)
		(keepout
			(tracks not_allowed)
			(vias allowed)
			(pads allowed)
			(copperpour not_allowed)
			(footprints allowed)
		)
		(placement
			(enabled no)
			(sheetname "")
		)
		(fill
			(thermal_gap 0.5)
			(thermal_bridge_width 0.5)
			(island_removal_mode 0)
		)
		(polygon
			(pts
				(arc
					(start 68.57746 -13.3858)
					(mid 68.593083 -13.423517)
					(end 68.6308 -13.43914)
				)
				(arc
					(start 69.0372 -13.43914)
					(mid 69.074917 -13.423517)
					(end 69.09054 -13.3858)
				)
				(arc
					(start 69.09054 -13.0302)
					(mid 69.074917 -12.992483)
					(end 69.0372 -12.97686)
				)
				(arc
					(start 68.6308 -12.97686)
					(mid 68.593083 -12.992483)
					(end 68.57746 -13.0302)
				)
			)
		)
	)
	(zone
		(layer "In10.Cu")
		(hatch none 0.5)
		(connect_pads
			(clearance 0)
		)
		(min_thickness 0.25)
		(keepout
			(tracks not_allowed)
			(vias allowed)
			(pads allowed)
			(copperpour not_allowed)
			(footprints allowed)
		)
		(placement
			(enabled no)
			(sheetname "")
		)
		(fill
			(thermal_gap 0.5)
			(thermal_bridge_width 0.5)
			(island_removal_mode 0)
		)
		(polygon
			(pts
				(xy 60.99175 -4.097528) (xy 61.70803 -4.097528) (xy 61.70803 -8.293608) (xy 60.99175 -8.293608)
			)
		)
	)
	(zone
		(layer "In10.Cu")
		(hatch none 0.5)
		(connect_pads
			(clearance 0)
		)
		(min_thickness 0.25)
		(keepout
			(tracks not_allowed)
			(vias allowed)
			(pads allowed)
			(copperpour not_allowed)
			(footprints allowed)
		)
		(placement
			(enabled no)
			(sheetname "")
		)
		(fill
			(thermal_gap 0.5)
			(thermal_bridge_width 0.5)
			(island_removal_mode 0)
		)
		(polygon
			(pts
				(xy 65.99174 -4.097528) (xy 66.70802 -4.097528) (xy 66.70802 -8.293608) (xy 65.99174 -8.293608)
			)
		)
	)
	(zone
		(layer "In10.Cu")
		(hatch none 0.5)
		(connect_pads
			(clearance 0)
		)
		(min_thickness 0.25)
		(keepout
			(tracks not_allowed)
			(vias allowed)
			(pads allowed)
			(copperpour not_allowed)
			(footprints allowed)
		)
		(placement
			(enabled no)
			(sheetname "")
		)
		(fill
			(thermal_gap 0.5)
			(thermal_bridge_width 0.5)
			(island_removal_mode 0)
		)
		(polygon
			(pts
				(xy 77.991716 -4.097528) (xy 78.707996 -4.097528) (xy 78.707996 -8.293608) (xy 77.991716 -8.293608)
			)
		)
	)
	(zone
		(layer "In10.Cu")
		(hatch none 0.5)
		(connect_pads
			(clearance 0)
		)
		(min_thickness 0.25)
		(keepout
			(tracks not_allowed)
			(vias allowed)
			(pads allowed)
			(copperpour not_allowed)
			(footprints allowed)
		)
		(placement
			(enabled no)
			(sheetname "")
		)
		(fill
			(thermal_gap 0.5)
			(thermal_bridge_width 0.5)
			(island_removal_mode 0)
		)
		(polygon
			(pts
				(arc
					(start 33.22066 -13.2588)
					(mid 33.236283 -13.296517)
					(end 33.274 -13.31214)
				)
				(arc
					(start 33.6804 -13.31214)
					(mid 33.718117 -13.296517)
					(end 33.73374 -13.2588)
				)
				(arc
					(start 33.73374 -12.9032)
					(mid 33.718117 -12.865483)
					(end 33.6804 -12.84986)
				)
				(arc
					(start 33.274 -12.84986)
					(mid 33.236283 -12.865483)
					(end 33.22066 -12.9032)
				)
			)
		)
	)
	(zone
		(layer "In10.Cu")
		(hatch none 0.5)
		(connect_pads
			(clearance 0)
		)
		(min_thickness 0.25)
		(keepout
			(tracks not_allowed)
			(vias allowed)
			(pads allowed)
			(copperpour not_allowed)
			(footprints allowed)
		)
		(placement
			(enabled no)
			(sheetname "")
		)
		(fill
			(thermal_gap 0.5)
			(thermal_bridge_width 0.5)
			(island_removal_mode 0)
		)
		(polygon
			(pts
				(arc
					(start 33.98266 -13.2588)
					(mid 33.998283 -13.296517)
					(end 34.036 -13.31214)
				)
				(arc
					(start 34.4424 -13.31214)
					(mid 34.480117 -13.296517)
					(end 34.49574 -13.2588)
				)
				(arc
					(start 34.49574 -12.9032)
					(mid 34.480117 -12.865483)
					(end 34.4424 -12.84986)
				)
				(arc
					(start 34.036 -12.84986)
					(mid 33.998283 -12.865483)
					(end 33.98266 -12.9032)
				)
			)
		)
	)
	(zone
		(layer "In10.Cu")
		(hatch none 0.5)
		(connect_pads
			(clearance 0)
		)
		(min_thickness 0.25)
		(keepout
			(tracks not_allowed)
			(vias allowed)
			(pads allowed)
			(copperpour not_allowed)
			(footprints allowed)
		)
		(placement
			(enabled no)
			(sheetname "")
		)
		(fill
			(thermal_gap 0.5)
			(thermal_bridge_width 0.5)
			(island_removal_mode 0)
		)
		(polygon
			(pts
				(arc
					(start 41.212262 -13.2588)
					(mid 41.227885 -13.296517)
					(end 41.265602 -13.31214)
				)
				(arc
					(start 41.672002 -13.31214)
					(mid 41.709719 -13.296517)
					(end 41.725342 -13.2588)
				)
				(arc
					(start 41.725342 -12.9032)
					(mid 41.709719 -12.865483)
					(end 41.672002 -12.84986)
				)
				(arc
					(start 41.265602 -12.84986)
					(mid 41.227885 -12.865483)
					(end 41.212262 -12.9032)
				)
			)
		)
	)
	(zone
		(layer "In10.Cu")
		(hatch none 0.5)
		(connect_pads
			(clearance 0)
		)
		(min_thickness 0.25)
		(keepout
			(tracks not_allowed)
			(vias allowed)
			(pads allowed)
			(copperpour not_allowed)
			(footprints allowed)
		)
		(placement
			(enabled no)
			(sheetname "")
		)
		(fill
			(thermal_gap 0.5)
			(thermal_bridge_width 0.5)
			(island_removal_mode 0)
		)
		(polygon
			(pts
				(arc
					(start 25.96896 -12.4968)
					(mid 25.984583 -12.534517)
					(end 26.0223 -12.55014)
				)
				(arc
					(start 26.4287 -12.55014)
					(mid 26.466417 -12.534517)
					(end 26.48204 -12.4968)
				)
				(arc
					(start 26.48204 -12.1412)
					(mid 26.466417 -12.103483)
					(end 26.4287 -12.08786)
				)
				(arc
					(start 26.0223 -12.08786)
					(mid 25.984583 -12.103483)
					(end 25.96896 -12.1412)
				)
			)
		)
	)
	(zone
		(layer "In10.Cu")
		(hatch none 0.5)
		(connect_pads
			(clearance 0)
		)
		(min_thickness 0.25)
		(keepout
			(tracks not_allowed)
			(vias allowed)
			(pads allowed)
			(copperpour not_allowed)
			(footprints allowed)
		)
		(placement
			(enabled no)
			(sheetname "")
		)
		(fill
			(thermal_gap 0.5)
			(thermal_bridge_width 0.5)
			(island_removal_mode 0)
		)
		(polygon
			(pts
				(arc
					(start 66.9798 -30.78734)
					(mid 67.017517 -30.771717)
					(end 67.03314 -30.734)
				)
				(arc
					(start 67.03314 -30.3276)
					(mid 67.017517 -30.289883)
					(end 66.9798 -30.27426)
				)
				(arc
					(start 66.6242 -30.27426)
					(mid 66.586483 -30.289883)
					(end 66.57086 -30.3276)
				)
				(arc
					(start 66.57086 -30.734)
					(mid 66.586483 -30.771717)
					(end 66.6242 -30.78734)
				)
			)
		)
	)
	(zone
		(layer "In10.Cu")
		(hatch none 0.5)
		(connect_pads
			(clearance 0)
		)
		(min_thickness 0.25)
		(keepout
			(tracks not_allowed)
			(vias allowed)
			(pads allowed)
			(copperpour not_allowed)
			(footprints allowed)
		)
		(placement
			(enabled no)
			(sheetname "")
		)
		(fill
			(thermal_gap 0.5)
			(thermal_bridge_width 0.5)
			(island_removal_mode 0)
		)
		(polygon
			(pts
				(xy 72.991726 -4.097528) (xy 73.708006 -4.097528) (xy 73.708006 -8.293608) (xy 72.991726 -8.293608)
			)
		)
	)
	(zone
		(layer "In10.Cu")
		(hatch none 0.5)
		(connect_pads
			(clearance 0)
		)
		(min_thickness 0.25)
		(keepout
			(tracks not_allowed)
			(vias allowed)
			(pads allowed)
			(copperpour not_allowed)
			(footprints allowed)
		)
		(placement
			(enabled no)
			(sheetname "")
		)
		(fill
			(thermal_gap 0.5)
			(thermal_bridge_width 0.5)
			(island_removal_mode 0)
		)
		(polygon
			(pts
				(xy 36.991798 -4.097528) (xy 37.708078 -4.097528) (xy 37.708078 -8.293608) (xy 36.991798 -8.293608)
			)
		)
	)
	(zone
		(layer "In10.Cu")
		(hatch none 0.5)
		(connect_pads
			(clearance 0)
		)
		(min_thickness 0.25)
		(keepout
			(tracks not_allowed)
			(vias allowed)
			(pads allowed)
			(copperpour not_allowed)
			(footprints allowed)
		)
		(placement
			(enabled no)
			(sheetname "")
		)
		(fill
			(thermal_gap 0.5)
			(thermal_bridge_width 0.5)
			(island_removal_mode 0)
		)
		(polygon
			(pts
				(xy 6.349746 -64.102234) (xy 6.349746 -63.297562) (xy 4.800346 -63.297562) (xy 4.800346 -64.10198)
				(xy 4.8006 -64.102234)
			)
		)
	)
	(zone
		(layer "In10.Cu")
		(hatch none 0.5)
		(connect_pads
			(clearance 0)
		)
		(min_thickness 0.25)
		(keepout
			(tracks not_allowed)
			(vias allowed)
			(pads allowed)
			(copperpour not_allowed)
			(footprints allowed)
		)
		(placement
			(enabled no)
			(sheetname "")
		)
		(fill
			(thermal_gap 0.5)
			(thermal_bridge_width 0.5)
			(island_removal_mode 0)
		)
		(polygon
			(pts
				(xy 37.991796 -4.097528) (xy 38.708076 -4.097528) (xy 38.708076 -8.293608) (xy 37.991796 -8.293608)
			)
		)
	)
	(zone
		(layer "In10.Cu")
		(hatch none 0.5)
		(connect_pads
			(clearance 0)
		)
		(min_thickness 0.25)
		(keepout
			(tracks not_allowed)
			(vias allowed)
			(pads allowed)
			(copperpour not_allowed)
			(footprints allowed)
		)
		(placement
			(enabled no)
			(sheetname "")
		)
		(fill
			(thermal_gap 0.5)
			(thermal_bridge_width 0.5)
			(island_removal_mode 0)
		)
		(polygon
			(pts
				(xy 73.991724 -4.097528) (xy 74.708004 -4.097528) (xy 74.708004 -8.293608) (xy 73.991724 -8.293608)
			)
		)
	)
	(zone
		(layer "In10.Cu")
		(hatch none 0.5)
		(connect_pads
			(clearance 0)
		)
		(min_thickness 0.25)
		(keepout
			(tracks not_allowed)
			(vias allowed)
			(pads allowed)
			(copperpour not_allowed)
			(footprints allowed)
		)
		(placement
			(enabled no)
			(sheetname "")
		)
		(fill
			(thermal_gap 0.5)
			(thermal_bridge_width 0.5)
			(island_removal_mode 0)
		)
		(polygon
			(pts
				(arc
					(start 33.22066 -12.4968)
					(mid 33.236283 -12.534517)
					(end 33.274 -12.55014)
				)
				(arc
					(start 33.6804 -12.55014)
					(mid 33.718117 -12.534517)
					(end 33.73374 -12.4968)
				)
				(arc
					(start 33.73374 -12.1412)
					(mid 33.718117 -12.103483)
					(end 33.6804 -12.08786)
				)
				(arc
					(start 33.274 -12.08786)
					(mid 33.236283 -12.103483)
					(end 33.22066 -12.1412)
				)
			)
		)
	)
	(zone
		(layer "In10.Cu")
		(hatch none 0.5)
		(connect_pads
			(clearance 0)
		)
		(min_thickness 0.25)
		(keepout
			(tracks not_allowed)
			(vias allowed)
			(pads allowed)
			(copperpour not_allowed)
			(footprints allowed)
		)
		(placement
			(enabled no)
			(sheetname "")
		)
		(fill
			(thermal_gap 0.5)
			(thermal_bridge_width 0.5)
			(island_removal_mode 0)
		)
		(polygon
			(pts
				(xy 16.991838 -4.097528) (xy 17.708118 -4.097528) (xy 17.708118 -8.293608) (xy 16.991838 -8.293608)
			)
		)
	)
	(zone
		(layer "In10.Cu")
		(hatch none 0.5)
		(connect_pads
			(clearance 0)
		)
		(min_thickness 0.25)
		(keepout
			(tracks not_allowed)
			(vias allowed)
			(pads allowed)
			(copperpour not_allowed)
			(footprints allowed)
		)
		(placement
			(enabled no)
			(sheetname "")
		)
		(fill
			(thermal_gap 0.5)
			(thermal_bridge_width 0.5)
			(island_removal_mode 0)
		)
		(polygon
			(pts
				(arc
					(start 80.76946 -13.2588)
					(mid 80.785083 -13.296517)
					(end 80.8228 -13.31214)
				)
				(arc
					(start 81.2292 -13.31214)
					(mid 81.266917 -13.296517)
					(end 81.28254 -13.2588)
				)
				(arc
					(start 81.28254 -12.9032)
					(mid 81.266917 -12.865483)
					(end 81.2292 -12.84986)
				)
				(arc
					(start 80.8228 -12.84986)
					(mid 80.785083 -12.865483)
					(end 80.76946 -12.9032)
				)
			)
		)
	)
	(zone
		(layer "In10.Cu")
		(hatch none 0.5)
		(connect_pads
			(clearance 0)
		)
		(min_thickness 0.25)
		(keepout
			(tracks not_allowed)
			(vias allowed)
			(pads allowed)
			(copperpour not_allowed)
			(footprints allowed)
		)
		(placement
			(enabled no)
			(sheetname "")
		)
		(fill
			(thermal_gap 0.5)
			(thermal_bridge_width 0.5)
			(island_removal_mode 0)
		)
		(polygon
			(pts
				(arc
					(start 20.69846 -12.4968)
					(mid 20.714083 -12.534517)
					(end 20.7518 -12.55014)
				)
				(arc
					(start 21.1582 -12.55014)
					(mid 21.195917 -12.534517)
					(end 21.21154 -12.4968)
				)
				(arc
					(start 21.21154 -12.1412)
					(mid 21.195917 -12.103483)
					(end 21.1582 -12.08786)
				)
				(arc
					(start 20.7518 -12.08786)
					(mid 20.714083 -12.103483)
					(end 20.69846 -12.1412)
				)
			)
		)
	)
	(zone
		(layer "In10.Cu")
		(hatch none 0.5)
		(connect_pads
			(clearance 0)
		)
		(min_thickness 0.25)
		(keepout
			(tracks not_allowed)
			(vias allowed)
			(pads allowed)
			(copperpour not_allowed)
			(footprints allowed)
		)
		(placement
			(enabled no)
			(sheetname "")
		)
		(fill
			(thermal_gap 0.5)
			(thermal_bridge_width 0.5)
			(island_removal_mode 0)
		)
		(polygon
			(pts
				(xy 69.991732 -4.097528) (xy 70.708012 -4.097528) (xy 70.708012 -8.293608) (xy 69.991732 -8.293608)
			)
		)
	)
	(zone
		(net "GND")
		(layer "In10.Cu")
		(hatch none 0.5)
		(connect_pads
			(clearance 0.5)
		)
		(min_thickness 0.25)
		(fill yes
			(thermal_gap 0.5)
			(thermal_bridge_width 0.5)
			(island_removal_mode 0)
		)
		(polygon
			(pts
				(xy 22.4155 -71.676006) (xy 23.289006 -70.8025) (xy 42.212006 -70.8025) (xy 46.022006 -66.9925)
				(xy 53.769006 -66.9925) (xy 54.2925 -66.469006) (xy 54.2925 -63.802006) (xy 54.785006 -63.3095)
				(xy 65.737994 -63.3095) (xy 67.388994 -64.9605) (xy 79.199994 -64.9605) (xy 79.961994 -65.7225)
				(xy 82.090006 -65.7225) (xy 82.852006 -64.9605) (xy 90.980006 -64.9605) (xy 92.885006 -63.0555)
				(xy 103.045006 -63.0555) (xy 103.3145 -62.786006) (xy 103.3145 -62.435994) (xy 103.172006 -62.2935)
				(xy 102.791006 -62.2935) (xy 98.600006 -58.1025) (xy 93.901006 -58.1025) (xy 92.2655 -56.466994)
				(xy 92.2655 -55.577994) (xy 91.8845 -55.196994) (xy 91.8845 -39.418006) (xy 92.377006 -38.9255)
				(xy 94.693994 -38.9255) (xy 95.582994 -39.8145) (xy 96.217994 -39.8145) (xy 97.106994 -40.7035)
				(xy 97.614994 -40.7035) (xy 98.249994 -41.3385) (xy 100.281994 -41.3385) (xy 101.1555 -42.212006)
				(xy 101.1555 -44.6786) (xy 107.163362 -44.6786) (xy 107.199684 -44.666408) (xy 107.224068 -44.6786)
				(xy 107.251246 -44.6786) (xy 107.27817 -44.705778) (xy 107.478068 -44.8056) (xy 108.648246 -44.8056)
				(xy 108.7374 -44.894754) (xy 109.156246 -45.3136) (xy 114.109754 -45.3136) (xy 114.363754 -45.0596)
				(xy 117.030246 -45.0596) (xy 117.119146 -45.1485) (xy 151.589994 -45.1485) (xy 164.2745 -57.833006)
				(xy 164.2745 -61.292994) (xy 163.0045 -62.562994) (xy 163.0045 -71.706994) (xy 162.6235 -72.087994)
				(xy 162.511994 -72.1995) (xy 148.765006 -72.1995) (xy 148.2725 -71.706994) (xy 148.2725 -68.912994)
				(xy 147.8915 -68.531994) (xy 147.8915 -65.326006) (xy 148.2725 -64.945006) (xy 148.2725 -62.435994)
				(xy 148.0185 -62.181994) (xy 147.622006 -61.7855) (xy 119.301006 -61.7855) (xy 119.047006 -61.5315)
				(xy 106.2355 -61.5315) (xy 106.2355 -62.181994) (xy 105.9815 -62.435994) (xy 105.9815 -64.594994)
				(xy 104.091994 -66.4845) (xy 101.043994 -66.4845) (xy 99.773994 -67.7545) (xy 94.058994 -67.7545)
				(xy 93.296994 -68.5165) (xy 87.073994 -68.5165) (xy 85.676994 -69.9135) (xy 75.135994 -69.9135)
				(xy 73.9775 -71.071994) (xy 73.9775 -73.036938)
				(arc
					(start 209.00009 -73.036938)
					(mid 209.167662 -72.967528)
					(end 209.237072 -72.799956)
				)
				(arc
					(start 209.237072 -0.999998)
					(mid 209.167662 -0.832426)
					(end 209.00009 -0.763016)
				)
				(xy 170.2435 -0.763016) (xy 170.2435 -3.731006) (xy 170.8785 -4.366006) (xy 170.8785 -5.539994)
				(xy 170.2435 -6.174994) (xy 170.2435 -10.208006) (xy 170.639994 -10.6045) (xy 172.417994 -10.6045)
				(xy 173.1645 -11.351006) (xy 173.1645 -15.318994) (xy 158.447994 -30.0355) (xy 119.077994 -30.0355)
				(xy 117.934994 -31.1785) (xy 117.777006 -31.1785) (xy 117.738906 -31.1404) (xy 114.617246 -31.1404)
				(xy 112.458246 -33.2994) (xy 111.036354 -33.2994) (xy 111.010954 -33.274) (xy 110.731554 -32.9946)
				(xy 110.008924 -32.9946) (xy 109.829092 -33.134554) (xy 109.791246 -33.1724) (xy 109.780324 -33.1724)
				(xy 109.771688 -33.179004) (xy 109.718602 -33.1724) (xy 104.711246 -33.1724) (xy 104.1654 -33.718246)
				(xy 104.076246 -33.8074) (xy 100.012754 -33.8074) (xy 99.123754 -32.9184) (xy 98.615754 -32.9184)
				(xy 98.107754 -32.4104) (xy 97.599754 -32.4104) (xy 97.2566 -32.067246) (xy 97.2566 -25.844754)
				(xy 97.7646 -25.336754) (xy 97.7646 -22.669754) (xy 98.107754 -22.3266) (xy 98.488754 -22.3266)
				(xy 98.6155 -22.199854) (xy 98.6155 -22.146006) (xy 101.267006 -19.4945) (xy 108.252006 -19.4945)
				(xy 114.094006 -13.6525) (xy 131.239006 -13.6525) (xy 133.779006 -11.1125) (xy 154.988006 -11.1125)
				(xy 155.5115 -10.589006) (xy 155.5115 -0.763016)
				(arc
					(start 106.000042 -0.763016)
					(mid 105.83247 -0.832426)
					(end 105.76306 -0.999998)
				)
				(arc
					(start 105.76306 -10.700004)
					(mid 105.246685 -11.946643)
					(end 104.000046 -12.463018)
				)
				(arc
					(start 100.000054 -12.463018)
					(mid 98.753415 -11.946643)
					(end 98.23704 -10.700004)
				)
				(xy 98.23704 -5.244592) (xy 97.448624 -5.244592) (xy 90.708226 -5.244592) (xy 90.708226 -8.293608)
				(xy 89.991946 -8.293608) (xy 89.991946 -5.244592) (xy 89.708228 -5.244592) (xy 89.708228 -8.293608)
				(xy 88.991948 -8.293608) (xy 88.991948 -5.244592) (xy 88.562942 -5.244592)
				(arc
					(start 88.562942 -10.150094)
					(mid 86.849966 -11.86307)
					(end 85.13699 -10.150094)
				)
				(xy 85.13699 -5.244592) (xy 82.707988 -5.244592) (xy 82.707988 -8.293608) (xy 81.991708 -8.293608)
				(xy 81.991708 -5.244592) (xy 81.70799 -5.244592) (xy 81.70799 -8.293608) (xy 80.99171 -8.293608)
				(xy 80.99171 -5.244592) (xy 78.707996 -5.244592) (xy 78.707996 -8.293608) (xy 77.991716 -8.293608)
				(xy 77.991716 -5.244592) (xy 77.707998 -5.244592) (xy 77.707998 -8.293608) (xy 76.991718 -8.293608)
				(xy 76.991718 -5.244592) (xy 74.708004 -5.244592) (xy 74.708004 -8.293608) (xy 73.991724 -8.293608)
				(xy 73.991724 -5.244592) (xy 73.708006 -5.244592) (xy 73.708006 -8.293608) (xy 72.991726 -8.293608)
				(xy 72.991726 -5.244592) (xy 70.708012 -5.244592) (xy 70.708012 -8.293608) (xy 69.991732 -8.293608)
				(xy 69.991732 -5.244592) (xy 69.708014 -5.244592) (xy 69.708014 -8.293608) (xy 68.991734 -8.293608)
				(xy 68.991734 -5.244592) (xy 66.70802 -5.244592) (xy 66.70802 -8.293608) (xy 65.99174 -8.293608)
				(xy 65.99174 -5.244592) (xy 65.708022 -5.244592) (xy 65.708022 -8.293608) (xy 64.991742 -8.293608)
				(xy 64.991742 -5.244592) (xy 62.708028 -5.244592) (xy 62.708028 -8.293608) (xy 61.991748 -8.293608)
				(xy 61.991748 -5.244592) (xy 61.70803 -5.244592) (xy 61.70803 -8.293608) (xy 60.99175 -8.293608)
				(xy 60.99175 -5.244592) (xy 50.708052 -5.244592) (xy 50.708052 -8.293608) (xy 49.991772 -8.293608)
				(xy 49.991772 -5.244592) (xy 49.708054 -5.244592) (xy 49.708054 -8.293608) (xy 48.991774 -8.293608)
				(xy 48.991774 -5.244592) (xy 46.70806 -5.244592) (xy 46.70806 -8.293608) (xy 45.99178 -8.293608)
				(xy 45.99178 -5.244592) (xy 45.708062 -5.244592) (xy 45.708062 -8.293608) (xy 44.991782 -8.293608)
				(xy 44.991782 -5.244592) (xy 42.708068 -5.244592) (xy 42.708068 -8.293608) (xy 41.991788 -8.293608)
				(xy 41.991788 -5.244592) (xy 41.70807 -5.244592) (xy 41.70807 -8.293608) (xy 40.99179 -8.293608)
				(xy 40.99179 -5.244592) (xy 38.708076 -5.244592) (xy 38.708076 -8.293608) (xy 37.991796 -8.293608)
				(xy 37.991796 -5.244592) (xy 37.708078 -5.244592) (xy 37.708078 -8.293608) (xy 36.991798 -8.293608)
				(xy 36.991798 -5.244592) (xy 34.708084 -5.244592) (xy 34.708084 -8.293608) (xy 33.991804 -8.293608)
				(xy 33.991804 -5.244592) (xy 33.708086 -5.244592) (xy 33.708086 -8.293608) (xy 32.991806 -8.293608)
				(xy 32.991806 -5.244592) (xy 30.708092 -5.244592) (xy 30.708092 -8.293608) (xy 29.991812 -8.293608)
				(xy 29.991812 -5.244592) (xy 29.708094 -5.244592) (xy 29.708094 -8.293608) (xy 28.991814 -8.293608)
				(xy 28.991814 -5.244592) (xy 26.7081 -5.244592) (xy 26.7081 -8.293608) (xy 25.99182 -8.293608) (xy 25.99182 -5.244592)
				(xy 25.708102 -5.244592) (xy 25.708102 -8.293608) (xy 24.991822 -8.293608) (xy 24.991822 -5.244592)
				(xy 22.708108 -5.244592) (xy 22.708108 -8.293608) (xy 21.991828 -8.293608) (xy 21.991828 -5.244592)
				(xy 21.70811 -5.244592) (xy 21.70811 -8.293608) (xy 20.99183 -8.293608) (xy 20.99183 -5.244592)
				(xy 18.708116 -5.244592) (xy 18.708116 -8.293608) (xy 17.991836 -8.293608) (xy 17.991836 -5.244592)
				(xy 17.708118 -5.244592) (xy 17.708118 -8.293608) (xy 16.991838 -8.293608) (xy 16.991838 -5.244592)
				(xy 15.463012 -5.244592)
				(arc
					(start 15.463012 -13.699998)
					(mid 14.946637 -14.946637)
					(end 13.699998 -15.463012)
				)
				(arc
					(start 0.999998 -15.463012)
					(mid 0.832426 -15.532422)
					(end 0.763016 -15.699994)
				)
				(arc
					(start 0.763016 -72.799956)
					(mid 0.832426 -72.967528)
					(end 0.999998 -73.036938)
				)
				(xy 22.4155 -73.036938)
			)
		)
		(polygon
			(pts
				(xy 6.349746 -66.297556) (xy 4.800346 -66.297556) (xy 4.800346 -67.101974) (xy 4.8006 -67.102228)
				(xy 6.349746 -67.102228)
			)
		)
		(polygon
			(pts
				(arc
					(start 2.31394 -66.220848)
					(mid 1.930273 -65.837562)
					(end 1.54686 -66.221102)
				)
				(arc
					(start 1.54686 -67.178682)
					(mid 1.9304 -67.562222)
					(end 2.31394 -67.178682)
				)
			)
		)
		(polygon
			(pts
				(xy 6.349746 -64.797432) (xy 4.800346 -64.797432) (xy 4.800346 -65.602104) (xy 4.8006 -65.602358)
				(xy 6.349746 -65.602358)
			)
		)
		(polygon
			(pts
				(arc
					(start 3.8354 -64.7065)
					(mid 3.451733 -64.323214)
					(end 3.06832 -64.706754)
				)
				(arc
					(start 3.06832 -65.664334)
					(mid 3.45186 -66.047874)
					(end 3.8354 -65.664334)
				)
			)
		)
		(polygon
			(pts
				(arc
					(start 10.01014 -64.515746)
					(mid 9.626473 -64.13246)
					(end 9.24306 -64.516)
				)
				(arc
					(start 9.24306 -65.405)
					(mid 9.6266 -65.78854)
					(end 10.01014 -65.405)
				)
			)
		)
		(polygon
			(pts
				(xy 6.349746 -63.297562) (xy 4.800346 -63.297562) (xy 4.800346 -64.10198) (xy 4.8006 -64.102234)
				(xy 6.349746 -64.102234)
			)
		)
		(polygon
			(pts
				(arc
					(start 2.31394 -63.221108)
					(mid 1.9304 -62.837568)
					(end 1.54686 -63.221108)
				)
				(arc
					(start 1.54686 -64.178942)
					(mid 1.930527 -64.562228)
					(end 2.31394 -64.178688)
				)
			)
		)
		(polygon
			(pts
				(arc
					(start 10.009886 -62.727078)
					(mid 9.615678 -62.354714)
					(end 9.243314 -62.748922)
				)
				(xy 9.240774 -62.748922) (xy 9.266174 -63.637668) (xy 9.266428 -63.637922)
				(arc
					(start 9.268714 -63.637922)
					(mid 9.662922 -64.010286)
					(end 10.035286 -63.616078)
				)
				(xy 10.037826 -63.616078) (xy 10.012426 -62.727078)
			)
		)
		(polygon
			(pts
				(xy 6.349746 -61.797438) (xy 4.800346 -61.797438) (xy 4.800346 -62.60211) (xy 4.8006 -62.602364)
				(xy 6.349746 -62.602364)
			)
		)
		(polygon
			(pts
				(arc
					(start 101.734366 -61.66993)
					(mid 101.189299 -61.660676)
					(end 101.185472 -62.20587)
				)
				(arc
					(start 101.795072 -62.817756)
					(mid 102.337616 -62.818772)
					(end 102.338632 -62.276228)
				)
			)
		)
		(polygon
			(pts
				(arc
					(start 3.8354 -61.706506)
					(mid 3.451733 -61.32322)
					(end 3.06832 -61.70676)
				)
				(arc
					(start 3.06832 -62.66434)
					(mid 3.45186 -63.04788)
					(end 3.8354 -62.66434)
				)
			)
		)
		(polygon
			(pts
				(arc
					(start 10.01014 -60.959746)
					(mid 9.626473 -60.57646)
					(end 9.24306 -60.96)
				)
				(arc
					(start 9.24306 -61.849)
					(mid 9.6266 -62.23254)
					(end 10.01014 -61.849)
				)
			)
		)
		(polygon
			(pts
				(xy 6.349746 -60.297568) (xy 4.800346 -60.297568) (xy 4.800346 -61.101986) (xy 4.8006 -61.10224)
				(xy 6.349746 -61.10224)
			)
		)
		(polygon
			(pts
				(arc
					(start 99.781106 -60.369704)
					(mid 99.238816 -60.378086)
					(end 99.247198 -60.920376)
				)
				(xy 99.24542 -60.922154) (xy 99.86518 -61.523372) (xy 99.865434 -61.523372)
				(arc
					(start 99.866958 -61.521848)
					(mid 100.409565 -61.513655)
					(end 100.40112 -60.971176)
				)
				(xy 100.402898 -60.969398) (xy 99.782884 -60.367926)
			)
		)
		(polygon
			(pts
				(arc
					(start 81.0514 -60.7187)
					(mid 81.3943 -60.3758)
					(end 81.0514 -60.0329)
				)
				(arc
					(start 80.263746 -60.0329)
					(mid 79.9211 -60.375927)
					(end 80.264 -60.7187)
				)
			)
		)
		(polygon
			(pts
				(arc
					(start 2.31394 -60.22086)
					(mid 1.930273 -59.837574)
					(end 1.54686 -60.221114)
				)
				(arc
					(start 1.54686 -61.178694)
					(mid 1.9304 -61.562234)
					(end 2.31394 -61.178694)
				)
			)
		)
		(polygon
			(pts
				(arc
					(start 84.348828 -59.595258)
					(mid 84.354625 -59.108766)
					(end 83.868006 -59.106054)
				)
				(arc
					(start 83.309968 -59.661806)
					(mid 83.308952 -60.146946)
					(end 83.794092 -60.147962)
				)
			)
		)
		(polygon
			(pts
				(arc
					(start 10.009886 -59.171078)
					(mid 9.615678 -58.798714)
					(end 9.243314 -59.192922)
				)
				(xy 9.240774 -59.192922) (xy 9.266174 -60.081668) (xy 9.266428 -60.081922)
				(arc
					(start 9.268714 -60.081922)
					(mid 9.662922 -60.454286)
					(end 10.035286 -60.060078)
				)
				(xy 10.037826 -60.060078) (xy 10.012426 -59.171078)
			)
		)
		(polygon
			(pts
				(xy 6.349746 -58.797444) (xy 4.800346 -58.797444) (xy 4.800346 -59.602116) (xy 4.8006 -59.60237)
				(xy 6.349746 -59.60237)
			)
		)
		(polygon
			(pts
				(arc
					(start 3.7084 -58.706766)
					(mid 3.32486 -58.323226)
					(end 2.94132 -58.706766)
				)
				(arc
					(start 2.94132 -59.6646)
					(mid 3.324987 -60.047886)
					(end 3.7084 -59.664346)
				)
			)
		)
		(polygon
			(pts
				(xy 6.349746 -57.297574) (xy 4.800346 -57.297574) (xy 4.800346 -58.101992) (xy 4.8006 -58.102246)
				(xy 6.349746 -58.102246)
			)
		)
		(polygon
			(pts
				(arc
					(start 10.01014 -57.403746)
					(mid 9.626473 -57.02046)
					(end 9.24306 -57.404)
				)
				(arc
					(start 9.24306 -58.293)
					(mid 9.6266 -58.67654)
					(end 10.01014 -58.293)
				)
			)
		)
		(polygon
			(pts
				(xy 6.349746 -55.79745) (xy 4.800346 -55.79745) (xy 4.800346 -56.602122) (xy 4.8006 -56.602376)
				(xy 6.349746 -56.602376)
			)
		)
		(polygon
			(pts
				(arc
					(start 10.01014 -55.625746)
					(mid 9.626473 -55.24246)
					(end 9.24306 -55.626)
				)
				(arc
					(start 9.24306 -56.515)
					(mid 9.6266 -56.89854)
					(end 10.01014 -56.515)
				)
			)
		)
		(polygon
			(pts
				(arc
					(start 83.701636 -55.68061)
					(mid 83.668625 -55.193446)
					(end 83.18119 -55.226204)
				)
				(arc
					(start 82.803746 -55.65902)
					(mid 82.83702 -56.146446)
					(end 83.324446 -56.113172)
				)
			)
		)
		(polygon
			(pts
				(arc
					(start 91.580462 -55.242714)
					(mid 91.688158 -54.76621)
					(end 91.211654 -54.658514)
				)
				(xy 91.210384 -54.656482) (xy 90.73769 -54.954678) (xy 90.73769 -54.954932)
				(arc
					(start 90.73896 -54.956964)
					(mid 90.631264 -55.433468)
					(end 91.107768 -55.541164)
				)
				(xy 91.109038 -55.543196) (xy 91.581732 -55.244746)
			)
		)
		(polygon
			(pts
				(arc
					(start 86.030054 -54.801008)
					(mid 85.689948 -54.450234)
					(end 85.339174 -54.79034)
				)
				(arc
					(start 85.330538 -55.356506)
					(mid 85.670517 -55.707536)
					(end 86.021418 -55.367428)
				)
			)
		)
		(polygon
			(pts
				(xy 6.349746 -54.29758) (xy 4.800346 -54.29758) (xy 4.800346 -55.101998) (xy 4.8006 -55.102252)
				(xy 6.349746 -55.102252)
			)
		)
		(polygon
			(pts
				(arc
					(start 87.528908 -54.284118)
					(mid 87.190326 -53.93182)
					(end 86.838028 -54.270402)
				)
				(arc
					(start 86.826852 -54.834028)
					(mid 87.165307 -55.186583)
					(end 87.517732 -54.847998)
				)
			)
		)
		(polygon
			(pts
				(arc
					(start 80.9117 -54.1274)
					(mid 80.5688 -53.7845)
					(end 80.2259 -54.1274)
				)
				(arc
					(start 80.2259 -54.686454)
					(mid 80.568927 -55.0291)
					(end 80.9117 -54.6862)
				)
			)
		)
		(polygon
			(pts
				(arc
					(start 84.586572 -54.022498)
					(mid 84.247863 -53.670456)
					(end 83.895692 -54.009036)
				)
				(arc
					(start 83.885024 -54.567836)
					(mid 84.22386 -54.91988)
					(end 84.575904 -54.581044)
				)
			)
		)
		(polygon
			(pts
				(arc
					(start 10.2616 -53.66766)
					(mid 10.2616 -54.38394)
					(end 10.2616 -53.66766)
				)
			)
		)
		(polygon
			(pts
				(arc
					(start 90.156792 -53.552598)
					(mid 89.845768 -53.175928)
					(end 89.46896 -53.486812)
				)
				(arc
					(start 89.415874 -54.043326)
					(mid 89.727024 -54.420008)
					(end 90.103706 -54.108858)
				)
			)
		)
		(polygon
			(pts
				(arc
					(start 88.633808 -53.399182)
					(mid 88.277446 -53.065172)
					(end 87.943436 -53.421534)
				)
				(xy 87.940896 -53.421534) (xy 87.95893 -53.98008)
				(arc
					(start 87.96147 -53.98008)
					(mid 88.317832 -54.31409)
					(end 88.651842 -53.957728)
				)
				(xy 88.654382 -53.957728) (xy 88.636348 -53.399436) (xy 88.636094 -53.399182)
			)
		)
		(polygon
			(pts
				(arc
					(start 91.403424 -53.414168)
					(mid 91.076653 -53.050941)
					(end 90.71356 -53.377846)
				)
				(xy 90.71102 -53.377592) (xy 90.681556 -53.93817)
				(arc
					(start 90.684096 -53.938424)
					(mid 91.010994 -54.30139)
					(end 91.37396 -53.974492)
				)
				(xy 91.3765 -53.974746) (xy 91.405964 -53.414422) (xy 91.40571 -53.414168)
			)
		)
		(polygon
			(pts
				(arc
					(start 86.443058 -53.20792)
					(mid 86.103968 -52.85613)
					(end 85.752178 -53.19522)
				)
				(arc
					(start 85.741764 -53.758592)
					(mid 86.080727 -54.110638)
					(end 86.432644 -53.771546)
				)
			)
		)
		(polygon
			(pts
				(arc
					(start 82.0293 -53.0098)
					(mid 81.6864 -52.6669)
					(end 81.3435 -53.0098)
				)
				(arc
					(start 81.3435 -53.594254)
					(mid 81.686527 -53.9369)
					(end 82.0293 -53.594)
				)
			)
		)
		(polygon
			(pts
				(arc
					(start 9.2202 -52.907946)
					(mid 8.839073 -52.5272)
					(end 8.4582 -52.9082)
				)
				(arc
					(start 8.4582 -53.8988)
					(mid 8.8392 -54.2798)
					(end 9.2202 -53.8988)
				)
			)
		)
		(polygon
			(pts
				(arc
					(start 10.2616 -52.42306)
					(mid 10.2616 -53.13934)
					(end 10.2616 -52.42306)
				)
			)
		)
		(polygon
			(pts
				(arc
					(start 9.5504 -51.38166)
					(mid 9.5504 -52.09794)
					(end 9.5504 -51.38166)
				)
			)
		)
		(polygon
			(pts
				(arc
					(start 8.509 -50.621946)
					(mid 8.127873 -50.2412)
					(end 7.747 -50.6222)
				)
				(arc
					(start 7.747 -51.6128)
					(mid 8.128 -51.9938)
					(end 8.509 -51.6128)
				)
			)
		)
		(polygon
			(pts
				(arc
					(start 9.5504 -50.13706)
					(mid 9.5504 -50.85334)
					(end 9.5504 -50.13706)
				)
			)
		)
		(polygon
			(pts
				(arc
					(start 13.55598 -47.66056)
					(mid 13.17244 -47.27702)
					(end 12.7889 -47.66056)
				)
				(arc
					(start 12.7889 -48.618394)
					(mid 13.172567 -49.00168)
					(end 13.55598 -48.61814)
				)
			)
		)
		(polygon
			(pts
				(arc
					(start 51.041554 -47.64278)
					(mid 50.663729 -47.253654)
					(end 50.274474 -47.63135)
				)
				(arc
					(start 50.262028 -48.49495)
					(mid 50.63998 -48.884078)
					(end 51.029108 -48.506126)
				)
			)
		)
		(polygon
			(pts
				(arc
					(start 15.082266 -47.21606)
					(mid 15.465806 -46.83252)
					(end 15.082266 -46.44898)
				)
				(arc
					(start 14.152626 -46.44898)
					(mid 13.76934 -46.832647)
					(end 14.15288 -47.21606)
				)
			)
		)
		(polygon
			(pts
				(arc
					(start 61.317378 -45.848016)
					(mid 60.910088 -45.489868)
					(end 60.551822 -45.897038)
				)
				(arc
					(start 60.607448 -46.75886)
					(mid 61.014864 -47.117)
					(end 61.373004 -46.709584)
				)
			)
		)
		(polygon
			(pts
				(arc
					(start 43.41114 -44.5389)
					(mid 43.79468 -44.15536)
					(end 43.41114 -43.77182)
				)
				(arc
					(start 42.453306 -43.77182)
					(mid 42.07002 -44.155487)
					(end 42.45356 -44.5389)
				)
			)
		)
		(polygon
			(pts
				(arc
					(start 45.007276 -43.53306)
					(mid 44.615103 -43.907837)
					(end 44.98975 -44.30014)
				)
				(arc
					(start 45.947838 -44.32173)
					(mid 46.340014 -43.946826)
					(end 45.96511 -43.55465)
				)
			)
		)
		(polygon
			(pts
				(arc
					(start 49.692052 -37.74567)
					(mid 49.15027 -37.771832)
					(end 49.176432 -38.313614)
				)
				(arc
					(start 49.81321 -38.892226)
					(mid 50.356403 -38.869633)
					(end 50.33137 -38.326568)
				)
			)
		)
		(polygon
			(pts
				(arc
					(start 60.04179 -35.379406)
					(mid 59.658123 -34.99612)
					(end 59.27471 -35.37966)
				)
				(arc
					(start 59.27471 -36.33724)
					(mid 59.65825 -36.72078)
					(end 60.04179 -36.33724)
				)
			)
		)
		(polygon
			(pts
				(arc
					(start 53.479954 -35.696652)
					(mid 53.862478 -35.311969)
					(end 53.477668 -34.929572)
				)
				(arc
					(start 52.52339 -34.93262)
					(mid 52.14112 -35.31743)
					(end 52.52593 -35.6997)
				)
			)
		)
		(polygon
			(pts
				(arc
					(start 52.16652 -34.47034)
					(mid 52.55006 -34.0868)
					(end 52.16652 -33.70326)
				)
				(arc
					(start 51.282092 -33.70326)
					(mid 50.898806 -34.086927)
					(end 51.282346 -34.47034)
				)
			)
		)
		(polygon
			(pts
				(arc
					(start 78.12024 -30.823154)
					(mid 77.762614 -31.150687)
					(end 78.090014 -31.508446)
				)
				(arc
					(start 78.648814 -31.53283)
					(mid 79.006446 -31.20517)
					(end 78.678786 -30.847538)
				)
			)
		)
		(polygon
			(pts
				(arc
					(start 67.79514 -30.3276)
					(mid 67.779517 -30.289883)
					(end 67.7418 -30.27426)
				)
				(arc
					(start 67.3862 -30.27426)
					(mid 67.348483 -30.289883)
					(end 67.33286 -30.3276)
				)
				(arc
					(start 67.33286 -30.734)
					(mid 67.348483 -30.771717)
					(end 67.3862 -30.78734)
				)
				(arc
					(start 67.7418 -30.78734)
					(mid 67.779517 -30.771717)
					(end 67.79514 -30.734)
				)
			)
		)
		(polygon
			(pts
				(arc
					(start 67.03314 -30.3276)
					(mid 67.017517 -30.289883)
					(end 66.9798 -30.27426)
				)
				(arc
					(start 66.6242 -30.27426)
					(mid 66.586483 -30.289883)
					(end 66.57086 -30.3276)
				)
				(arc
					(start 66.57086 -30.734)
					(mid 66.586483 -30.771717)
					(end 66.6242 -30.78734)
				)
				(arc
					(start 66.9798 -30.78734)
					(mid 67.017517 -30.771717)
					(end 67.03314 -30.734)
				)
			)
		)
		(polygon
			(pts
				(arc
					(start 78.538832 -30.2387)
					(mid 78.878175 -29.892117)
					(end 78.531466 -29.5529)
				)
				(arc
					(start 77.972666 -29.55925)
					(mid 77.633576 -29.90596)
					(end 77.980286 -30.24505)
				)
			)
		)
		(polygon
			(pts
				(arc
					(start 67.79514 -29.5656)
					(mid 67.779517 -29.527883)
					(end 67.7418 -29.51226)
				)
				(arc
					(start 67.3862 -29.51226)
					(mid 67.348483 -29.527883)
					(end 67.33286 -29.5656)
				)
				(arc
					(start 67.33286 -29.972)
					(mid 67.348483 -30.009717)
					(end 67.3862 -30.02534)
				)
				(arc
					(start 67.7418 -30.02534)
					(mid 67.779517 -30.009717)
					(end 67.79514 -29.972)
				)
			)
		)
		(polygon
			(pts
				(arc
					(start 67.03314 -29.5656)
					(mid 67.017517 -29.527883)
					(end 66.9798 -29.51226)
				)
				(arc
					(start 66.6242 -29.51226)
					(mid 66.586483 -29.527883)
					(end 66.57086 -29.5656)
				)
				(arc
					(start 66.57086 -29.972)
					(mid 66.586483 -30.009717)
					(end 66.6242 -30.02534)
				)
				(arc
					(start 66.9798 -30.02534)
					(mid 67.017517 -30.009717)
					(end 67.03314 -29.972)
				)
			)
		)
		(polygon
			(pts
				(arc
					(start 38.65372 -29.336746)
					(mid 38.270053 -28.95346)
					(end 37.88664 -29.337)
				)
				(arc
					(start 37.88664 -30.2006)
					(mid 38.27018 -30.58414)
					(end 38.65372 -30.2006)
				)
			)
		)
		(polygon
			(pts
				(arc
					(start 53.535326 -28.897834)
					(mid 53.151786 -28.514294)
					(end 52.768246 -28.897834)
				)
				(arc
					(start 52.768246 -29.827474)
					(mid 53.151913 -30.21076)
					(end 53.535326 -29.82722)
				)
			)
		)
		(polygon
			(pts
				(arc
					(start 67.79514 -28.1178)
					(mid 67.779517 -28.080083)
					(end 67.7418 -28.06446)
				)
				(arc
					(start 67.3862 -28.06446)
					(mid 67.348483 -28.080083)
					(end 67.33286 -28.1178)
				)
				(arc
					(start 67.33286 -28.5242)
					(mid 67.348483 -28.561917)
					(end 67.3862 -28.57754)
				)
				(arc
					(start 67.7418 -28.57754)
					(mid 67.779517 -28.561917)
					(end 67.79514 -28.5242)
				)
			)
		)
		(polygon
			(pts
				(arc
					(start 67.03314 -28.1178)
					(mid 67.017517 -28.080083)
					(end 66.9798 -28.06446)
				)
				(arc
					(start 66.6242 -28.06446)
					(mid 66.586483 -28.080083)
					(end 66.57086 -28.1178)
				)
				(arc
					(start 66.57086 -28.5242)
					(mid 66.586483 -28.561917)
					(end 66.6242 -28.57754)
				)
				(arc
					(start 66.9798 -28.57754)
					(mid 67.017517 -28.561917)
					(end 67.03314 -28.5242)
				)
			)
		)
		(polygon
			(pts
				(arc
					(start 67.79514 -27.3558)
					(mid 67.779517 -27.318083)
					(end 67.7418 -27.30246)
				)
				(arc
					(start 67.3862 -27.30246)
					(mid 67.348483 -27.318083)
					(end 67.33286 -27.3558)
				)
				(arc
					(start 67.33286 -27.7622)
					(mid 67.348483 -27.799917)
					(end 67.3862 -27.81554)
				)
				(arc
					(start 67.7418 -27.81554)
					(mid 67.779517 -27.799917)
					(end 67.79514 -27.7622)
				)
			)
		)
		(polygon
			(pts
				(arc
					(start 67.03314 -27.3558)
					(mid 67.017517 -27.318083)
					(end 66.9798 -27.30246)
				)
				(arc
					(start 66.6242 -27.30246)
					(mid 66.586483 -27.318083)
					(end 66.57086 -27.3558)
				)
				(arc
					(start 66.57086 -27.7622)
					(mid 66.586483 -27.799917)
					(end 66.6242 -27.81554)
				)
				(arc
					(start 66.9798 -27.81554)
					(mid 67.017517 -27.799917)
					(end 67.03314 -27.7622)
				)
			)
		)
		(polygon
			(pts
				(arc
					(start 69.52234 -27.52344)
					(mid 69.140705 -27.138123)
					(end 68.75526 -27.51963)
				)
				(arc
					(start 68.75145 -28.403296)
					(mid 69.133212 -28.788614)
					(end 69.51853 -28.406852)
				)
			)
		)
		(polygon
			(pts
				(arc
					(start 50.25263 -20.79498)
					(mid 50.63617 -20.41144)
					(end 50.25263 -20.0279)
				)
				(arc
					(start 49.294796 -20.0279)
					(mid 48.91151 -20.411567)
					(end 49.29505 -20.79498)
				)
			)
		)
		(polygon
			(pts
				(arc
					(start 21.053044 -15.872206)
					(mid 21.43633 -15.488539)
					(end 21.05279 -15.105126)
				)
				(arc
					(start 20.09521 -15.105126)
					(mid 19.71167 -15.488666)
					(end 20.09521 -15.872206)
				)
			)
		)
		(polygon
			(pts
				(arc
					(start 64.389 -15.0876)
					(mid 64.77 -14.7066)
					(end 64.389 -14.3256)
				)
				(arc
					(start 63.626746 -14.3256)
					(mid 63.246 -14.706727)
					(end 63.627 -15.0876)
				)
			)
		)
		(polygon
			(pts
				(arc
					(start 73.7108 -15.09014)
					(mid 74.09434 -14.7066)
					(end 73.7108 -14.32306)
				)
				(arc
					(start 72.846946 -14.32306)
					(mid 72.46366 -14.706727)
					(end 72.8472 -15.09014)
				)
			)
		)
		(polygon
			(pts
				(arc
					(start 66.548254 -15.0622)
					(mid 66.929 -14.681073)
					(end 66.548 -14.3002)
				)
				(arc
					(start 65.786 -14.3002)
					(mid 65.405 -14.6812)
					(end 65.786 -15.0622)
				)
			)
		)
		(polygon
			(pts
				(arc
					(start 68.834 -14.98854)
					(mid 69.21754 -14.605)
					(end 68.834 -14.22146)
				)
				(arc
					(start 68.071746 -14.22146)
					(mid 67.68846 -14.605127)
					(end 68.072 -14.98854)
				)
			)
		)
		(polygon
			(pts
				(arc
					(start 81.077054 -14.96314)
					(mid 81.46034 -14.579473)
					(end 81.0768 -14.19606)
				)
				(arc
					(start 80.2132 -14.19606)
					(mid 79.82966 -14.5796)
					(end 80.2132 -14.96314)
				)
			)
		)
		(polygon
			(pts
				(arc
					(start 78.2828 -14.96314)
					(mid 78.66634 -14.5796)
					(end 78.2828 -14.19606)
				)
				(arc
					(start 77.418946 -14.19606)
					(mid 77.03566 -14.579727)
					(end 77.4192 -14.96314)
				)
			)
		)
		(polygon
			(pts
				(arc
					(start 34.290254 -14.96314)
					(mid 34.67354 -14.579473)
					(end 34.29 -14.19606)
				)
				(arc
					(start 33.4264 -14.19606)
					(mid 33.04286 -14.5796)
					(end 33.4264 -14.96314)
				)
			)
		)
		(polygon
			(pts
				(arc
					(start 30.277054 -14.96314)
					(mid 30.66034 -14.579473)
					(end 30.2768 -14.19606)
				)
				(arc
					(start 29.4132 -14.19606)
					(mid 29.02966 -14.5796)
					(end 29.4132 -14.96314)
				)
			)
		)
		(polygon
			(pts
				(arc
					(start 73.91654 -13.7922)
					(mid 73.900917 -13.754483)
					(end 73.8632 -13.73886)
				)
				(arc
					(start 73.4568 -13.73886)
					(mid 73.419083 -13.754483)
					(end 73.40346 -13.7922)
				)
				(arc
					(start 73.40346 -14.1478)
					(mid 73.419083 -14.185517)
					(end 73.4568 -14.20114)
				)
				(arc
					(start 73.8632 -14.20114)
					(mid 73.900917 -14.185517)
					(end 73.91654 -14.1478)
				)
			)
		)
		(polygon
			(pts
				(arc
					(start 73.15454 -13.7922)
					(mid 73.138917 -13.754483)
					(end 73.1012 -13.73886)
				)
				(arc
					(start 72.6948 -13.73886)
					(mid 72.657083 -13.754483)
					(end 72.64146 -13.7922)
				)
				(arc
					(start 72.64146 -14.1478)
					(mid 72.657083 -14.185517)
					(end 72.6948 -14.20114)
				)
				(arc
					(start 73.1012 -14.20114)
					(mid 73.138917 -14.185517)
					(end 73.15454 -14.1478)
				)
			)
		)
		(polygon
			(pts
				(arc
					(start 69.09054 -13.7922)
					(mid 69.074917 -13.754483)
					(end 69.0372 -13.73886)
				)
				(arc
					(start 68.6308 -13.73886)
					(mid 68.593083 -13.754483)
					(end 68.57746 -13.7922)
				)
				(arc
					(start 68.57746 -14.1478)
					(mid 68.593083 -14.185517)
					(end 68.6308 -14.20114)
				)
				(arc
					(start 69.0372 -14.20114)
					(mid 69.074917 -14.185517)
					(end 69.09054 -14.1478)
				)
			)
		)
		(polygon
			(pts
				(arc
					(start 68.32854 -13.7922)
					(mid 68.312917 -13.754483)
					(end 68.2752 -13.73886)
				)
				(arc
					(start 67.8688 -13.73886)
					(mid 67.831083 -13.754483)
					(end 67.81546 -13.7922)
				)
				(arc
					(start 67.81546 -14.1478)
					(mid 67.831083 -14.185517)
					(end 67.8688 -14.20114)
				)
				(arc
					(start 68.2752 -14.20114)
					(mid 68.312917 -14.185517)
					(end 68.32854 -14.1478)
				)
			)
		)
		(polygon
			(pts
				(arc
					(start 66.80454 -13.7922)
					(mid 66.788917 -13.754483)
					(end 66.7512 -13.73886)
				)
				(arc
					(start 66.3448 -13.73886)
					(mid 66.307083 -13.754483)
					(end 66.29146 -13.7922)
				)
				(arc
					(start 66.29146 -14.1478)
					(mid 66.307083 -14.185517)
					(end 66.3448 -14.20114)
				)
				(arc
					(start 66.7512 -14.20114)
					(mid 66.788917 -14.185517)
					(end 66.80454 -14.1478)
				)
			)
		)
		(polygon
			(pts
				(arc
					(start 66.04254 -13.7922)
					(mid 66.026917 -13.754483)
					(end 65.9892 -13.73886)
				)
				(arc
					(start 65.5828 -13.73886)
					(mid 65.545083 -13.754483)
					(end 65.52946 -13.7922)
				)
				(arc
					(start 65.52946 -14.1478)
					(mid 65.545083 -14.185517)
					(end 65.5828 -14.20114)
				)
				(arc
					(start 65.9892 -14.20114)
					(mid 66.026917 -14.185517)
					(end 66.04254 -14.1478)
				)
			)
		)
		(polygon
			(pts
				(arc
					(start 81.28254 -13.6652)
					(mid 81.266917 -13.627483)
					(end 81.2292 -13.61186)
				)
				(arc
					(start 80.8228 -13.61186)
					(mid 80.785083 -13.627483)
					(end 80.76946 -13.6652)
				)
				(arc
					(start 80.76946 -14.0208)
					(mid 80.785083 -14.058517)
					(end 80.8228 -14.07414)
				)
				(arc
					(start 81.2292 -14.07414)
					(mid 81.266917 -14.058517)
					(end 81.28254 -14.0208)
				)
			)
		)
		(polygon
			(pts
				(arc
					(start 80.52054 -13.6652)
					(mid 80.504917 -13.627483)
					(end 80.4672 -13.61186)
				)
				(arc
					(start 80.0608 -13.61186)
					(mid 80.023083 -13.627483)
					(end 80.00746 -13.6652)
				)
				(arc
					(start 80.00746 -14.0208)
					(mid 80.023083 -14.058517)
					(end 80.0608 -14.07414)
				)
				(arc
					(start 80.4672 -14.07414)
					(mid 80.504917 -14.058517)
					(end 80.52054 -14.0208)
				)
			)
		)
		(polygon
			(pts
				(arc
					(start 78.48854 -13.6652)
					(mid 78.472917 -13.627483)
					(end 78.4352 -13.61186)
				)
				(arc
					(start 78.0288 -13.61186)
					(mid 77.991083 -13.627483)
					(end 77.97546 -13.6652)
				)
				(arc
					(start 77.97546 -14.0208)
					(mid 77.991083 -14.058517)
					(end 78.0288 -14.07414)
				)
				(arc
					(start 78.4352 -14.07414)
					(mid 78.472917 -14.058517)
					(end 78.48854 -14.0208)
				)
			)
		)
		(polygon
			(pts
				(arc
					(start 77.72654 -13.6652)
					(mid 77.710917 -13.627483)
					(end 77.6732 -13.61186)
				)
				(arc
					(start 77.2668 -13.61186)
					(mid 77.229083 -13.627483)
					(end 77.21346 -13.6652)
				)
				(arc
					(start 77.21346 -14.0208)
					(mid 77.229083 -14.058517)
					(end 77.2668 -14.07414)
				)
				(arc
					(start 77.6732 -14.07414)
					(mid 77.710917 -14.058517)
					(end 77.72654 -14.0208)
				)
			)
		)
		(polygon
			(pts
				(arc
					(start 83.1596 -14.32814)
					(mid 83.54314 -13.9446)
					(end 83.1596 -13.56106)
				)
				(arc
					(start 82.295746 -13.56106)
					(mid 81.91246 -13.944727)
					(end 82.296 -14.32814)
				)
			)
		)
		(polygon
			(pts
				(arc
					(start 53.010054 -14.32814)
					(mid 53.39334 -13.944473)
					(end 53.0098 -13.56106)
				)
				(arc
					(start 52.1462 -13.56106)
					(mid 51.76266 -13.9446)
					(end 52.1462 -14.32814)
				)
			)
		)
		(polygon
			(pts
				(arc
					(start 50.2158 -14.1986)
					(mid 50.5968 -13.8176)
					(end 50.2158 -13.4366)
				)
				(arc
					(start 49.453546 -13.4366)
					(mid 49.0728 -13.817727)
					(end 49.4538 -14.1986)
				)
			)
		)
		(polygon
			(pts
				(arc
					(start 46.177454 -14.1986)
					(mid 46.5582 -13.817473)
					(end 46.1772 -13.4366)
				)
				(arc
					(start 45.466 -13.4366)
					(mid 45.085 -13.8176)
					(end 45.466 -14.1986)
				)
			)
		)
		(polygon
			(pts
				(arc
					(start 42.281856 -14.20114)
					(mid 42.665142 -13.817473)
					(end 42.281602 -13.43406)
				)
				(arc
					(start 41.418002 -13.43406)
					(mid 41.034462 -13.8176)
					(end 41.418002 -14.20114)
				)
			)
		)
		(polygon
			(pts
				(arc
					(start 38.281864 -14.20114)
					(mid 38.66515 -13.817473)
					(end 38.28161 -13.43406)
				)
				(arc
					(start 37.41801 -13.43406)
					(mid 37.03447 -13.8176)
					(end 37.41801 -14.20114)
				)
			)
		)
		(polygon
			(pts
				(arc
					(start 26.276554 -14.20114)
					(mid 26.65984 -13.817473)
					(end 26.2763 -13.43406)
				)
				(arc
					(start 25.4127 -13.43406)
					(mid 25.02916 -13.8176)
					(end 25.4127 -14.20114)
				)
			)
		)
		(polygon
			(pts
				(arc
					(start 22.5298 -14.20114)
					(mid 22.91334 -13.8176)
					(end 22.5298 -13.43406)
				)
				(arc
					(start 21.665946 -13.43406)
					(mid 21.28266 -13.817727)
					(end 21.6662 -14.20114)
				)
			)
		)
		(polygon
			(pts
				(arc
					(start 48.184054 -14.1732)
					(mid 48.5648 -13.792073)
					(end 48.1838 -13.4112)
				)
				(arc
					(start 47.46371 -13.4112)
					(mid 47.08271 -13.7922)
					(end 47.46371 -14.1732)
				)
			)
		)
		(polygon
			(pts
				(arc
					(start 73.91654 -13.0302)
					(mid 73.900917 -12.992483)
					(end 73.8632 -12.97686)
				)
				(arc
					(start 73.4568 -12.97686)
					(mid 73.419083 -12.992483)
					(end 73.40346 -13.0302)
				)
				(arc
					(start 73.40346 -13.3858)
					(mid 73.419083 -13.423517)
					(end 73.4568 -13.43914)
				)
				(arc
					(start 73.8632 -13.43914)
					(mid 73.900917 -13.423517)
					(end 73.91654 -13.3858)
				)
			)
		)
		(polygon
			(pts
				(arc
					(start 73.15454 -13.0302)
					(mid 73.138917 -12.992483)
					(end 73.1012 -12.97686)
				)
				(arc
					(start 72.6948 -12.97686)
					(mid 72.657083 -12.992483)
					(end 72.64146 -13.0302)
				)
				(arc
					(start 72.64146 -13.3858)
					(mid 72.657083 -13.423517)
					(end 72.6948 -13.43914)
				)
				(arc
					(start 73.1012 -13.43914)
					(mid 73.138917 -13.423517)
					(end 73.15454 -13.3858)
				)
			)
		)
		(polygon
			(pts
				(arc
					(start 69.09054 -13.0302)
					(mid 69.074917 -12.992483)
					(end 69.0372 -12.97686)
				)
				(arc
					(start 68.6308 -12.97686)
					(mid 68.593083 -12.992483)
					(end 68.57746 -13.0302)
				)
				(arc
					(start 68.57746 -13.3858)
					(mid 68.593083 -13.423517)
					(end 68.6308 -13.43914)
				)
				(arc
					(start 69.0372 -13.43914)
					(mid 69.074917 -13.423517)
					(end 69.09054 -13.3858)
				)
			)
		)
		(polygon
			(pts
				(arc
					(start 68.32854 -13.0302)
					(mid 68.312917 -12.992483)
					(end 68.2752 -12.97686)
				)
				(arc
					(start 67.8688 -12.97686)
					(mid 67.831083 -12.992483)
					(end 67.81546 -13.0302)
				)
				(arc
					(start 67.81546 -13.3858)
					(mid 67.831083 -13.423517)
					(end 67.8688 -13.43914)
				)
				(arc
					(start 68.2752 -13.43914)
					(mid 68.312917 -13.423517)
					(end 68.32854 -13.3858)
				)
			)
		)
		(polygon
			(pts
				(arc
					(start 66.80454 -13.0302)
					(mid 66.788917 -12.992483)
					(end 66.7512 -12.97686)
				)
				(arc
					(start 66.3448 -12.97686)
					(mid 66.307083 -12.992483)
					(end 66.29146 -13.0302)
				)
				(arc
					(start 66.29146 -13.3858)
					(mid 66.307083 -13.423517)
					(end 66.3448 -13.43914)
				)
				(arc
					(start 66.7512 -13.43914)
					(mid 66.788917 -13.423517)
					(end 66.80454 -13.3858)
				)
			)
		)
		(polygon
			(pts
				(arc
					(start 66.04254 -13.0302)
					(mid 66.026917 -12.992483)
					(end 65.9892 -12.97686)
				)
				(arc
					(start 65.5828 -12.97686)
					(mid 65.545083 -12.992483)
					(end 65.52946 -13.0302)
				)
				(arc
					(start 65.52946 -13.3858)
					(mid 65.545083 -13.423517)
					(end 65.5828 -13.43914)
				)
				(arc
					(start 65.9892 -13.43914)
					(mid 66.026917 -13.423517)
					(end 66.04254 -13.3858)
				)
			)
		)
		(polygon
			(pts
				(arc
					(start 81.28254 -12.9032)
					(mid 81.266917 -12.865483)
					(end 81.2292 -12.84986)
				)
				(arc
					(start 80.8228 -12.84986)
					(mid 80.785083 -12.865483)
					(end 80.76946 -12.9032)
				)
				(arc
					(start 80.76946 -13.2588)
					(mid 80.785083 -13.296517)
					(end 80.8228 -13.31214)
				)
				(arc
					(start 81.2292 -13.31214)
					(mid 81.266917 -13.296517)
					(end 81.28254 -13.2588)
				)
			)
		)
		(polygon
			(pts
				(arc
					(start 80.52054 -12.9032)
					(mid 80.504917 -12.865483)
					(end 80.4672 -12.84986)
				)
				(arc
					(start 80.0608 -12.84986)
					(mid 80.023083 -12.865483)
					(end 80.00746 -12.9032)
				)
				(arc
					(start 80.00746 -13.2588)
					(mid 80.023083 -13.296517)
					(end 80.0608 -13.31214)
				)
				(arc
					(start 80.4672 -13.31214)
					(mid 80.504917 -13.296517)
					(end 80.52054 -13.2588)
				)
			)
		)
		(polygon
			(pts
				(arc
					(start 78.48854 -12.9032)
					(mid 78.472917 -12.865483)
					(end 78.4352 -12.84986)
				)
				(arc
					(start 78.0288 -12.84986)
					(mid 77.991083 -12.865483)
					(end 77.97546 -12.9032)
				)
				(arc
					(start 77.97546 -13.2588)
					(mid 77.991083 -13.296517)
					(end 78.0288 -13.31214)
				)
				(arc
					(start 78.4352 -13.31214)
					(mid 78.472917 -13.296517)
					(end 78.48854 -13.2588)
				)
			)
		)
		(polygon
			(pts
				(arc
					(start 77.72654 -12.9032)
					(mid 77.710917 -12.865483)
					(end 77.6732 -12.84986)
				)
				(arc
					(start 77.2668 -12.84986)
					(mid 77.229083 -12.865483)
					(end 77.21346 -12.9032)
				)
				(arc
					(start 77.21346 -13.2588)
					(mid 77.229083 -13.296517)
					(end 77.2668 -13.31214)
				)
				(arc
					(start 77.6732 -13.31214)
					(mid 77.710917 -13.296517)
					(end 77.72654 -13.2588)
				)
			)
		)
		(polygon
			(pts
				(arc
					(start 46.48454 -12.9032)
					(mid 46.468917 -12.865483)
					(end 46.4312 -12.84986)
				)
				(arc
					(start 46.0248 -12.84986)
					(mid 45.987083 -12.865483)
					(end 45.97146 -12.9032)
				)
				(arc
					(start 45.97146 -13.2588)
					(mid 45.987083 -13.296517)
					(end 46.0248 -13.31214)
				)
				(arc
					(start 46.4312 -13.31214)
					(mid 46.468917 -13.296517)
					(end 46.48454 -13.2588)
				)
			)
		)
		(polygon
			(pts
				(arc
					(start 45.72254 -12.9032)
					(mid 45.706917 -12.865483)
					(end 45.6692 -12.84986)
				)
				(arc
					(start 45.2628 -12.84986)
					(mid 45.225083 -12.865483)
					(end 45.20946 -12.9032)
				)
				(arc
					(start 45.20946 -13.2588)
					(mid 45.225083 -13.296517)
					(end 45.2628 -13.31214)
				)
				(arc
					(start 45.6692 -13.31214)
					(mid 45.706917 -13.296517)
					(end 45.72254 -13.2588)
				)
			)
		)
		(polygon
			(pts
				(arc
					(start 42.487342 -12.9032)
					(mid 42.471719 -12.865483)
					(end 42.434002 -12.84986)
				)
				(arc
					(start 42.027602 -12.84986)
					(mid 41.989885 -12.865483)
					(end 41.974262 -12.9032)
				)
				(arc
					(start 41.974262 -13.2588)
					(mid 41.989885 -13.296517)
					(end 42.027602 -13.31214)
				)
				(arc
					(start 42.434002 -13.31214)
					(mid 42.471719 -13.296517)
					(end 42.487342 -13.2588)
				)
			)
		)
		(polygon
			(pts
				(arc
					(start 41.725342 -12.9032)
					(mid 41.709719 -12.865483)
					(end 41.672002 -12.84986)
				)
				(arc
					(start 41.265602 -12.84986)
					(mid 41.227885 -12.865483)
					(end 41.212262 -12.9032)
				)
				(arc
					(start 41.212262 -13.2588)
					(mid 41.227885 -13.296517)
					(end 41.265602 -13.31214)
				)
				(arc
					(start 41.672002 -13.31214)
					(mid 41.709719 -13.296517)
					(end 41.725342 -13.2588)
				)
			)
		)
		(polygon
			(pts
				(arc
					(start 38.48735 -12.9032)
					(mid 38.471727 -12.865483)
					(end 38.43401 -12.84986)
				)
				(arc
					(start 38.02761 -12.84986)
					(mid 37.989893 -12.865483)
					(end 37.97427 -12.9032)
				)
				(arc
					(start 37.97427 -13.2588)
					(mid 37.989893 -13.296517)
					(end 38.02761 -13.31214)
				)
				(arc
					(start 38.43401 -13.31214)
					(mid 38.471727 -13.296517)
					(end 38.48735 -13.2588)
				)
			)
		)
		(polygon
			(pts
				(arc
					(start 37.72535 -12.9032)
					(mid 37.709727 -12.865483)
					(end 37.67201 -12.84986)
				)
				(arc
					(start 37.26561 -12.84986)
					(mid 37.227893 -12.865483)
					(end 37.21227 -12.9032)
				)
				(arc
					(start 37.21227 -13.2588)
					(mid 37.227893 -13.296517)
					(end 37.26561 -13.31214)
				)
				(arc
					(start 37.67201 -13.31214)
					(mid 37.709727 -13.296517)
					(end 37.72535 -13.2588)
				)
			)
		)
		(polygon
			(pts
				(arc
					(start 34.49574 -12.9032)
					(mid 34.480117 -12.865483)
					(end 34.4424 -12.84986)
				)
				(arc
					(start 34.036 -12.84986)
					(mid 33.998283 -12.865483)
					(end 33.98266 -12.9032)
				)
				(arc
					(start 33.98266 -13.2588)
					(mid 33.998283 -13.296517)
					(end 34.036 -13.31214)
				)
				(arc
					(start 34.4424 -13.31214)
					(mid 34.480117 -13.296517)
					(end 34.49574 -13.2588)
				)
			)
		)
		(polygon
			(pts
				(arc
					(start 33.73374 -12.9032)
					(mid 33.718117 -12.865483)
					(end 33.6804 -12.84986)
				)
				(arc
					(start 33.274 -12.84986)
					(mid 33.236283 -12.865483)
					(end 33.22066 -12.9032)
				)
				(arc
					(start 33.22066 -13.2588)
					(mid 33.236283 -13.296517)
					(end 33.274 -13.31214)
				)
				(arc
					(start 33.6804 -13.31214)
					(mid 33.718117 -13.296517)
					(end 33.73374 -13.2588)
				)
			)
		)
		(polygon
			(pts
				(arc
					(start 30.48254 -12.9032)
					(mid 30.466917 -12.865483)
					(end 30.4292 -12.84986)
				)
				(arc
					(start 30.0228 -12.84986)
					(mid 29.985083 -12.865483)
					(end 29.96946 -12.9032)
				)
				(arc
					(start 29.96946 -13.2588)
					(mid 29.985083 -13.296517)
					(end 30.0228 -13.31214)
				)
				(arc
					(start 30.4292 -13.31214)
					(mid 30.466917 -13.296517)
					(end 30.48254 -13.2588)
				)
			)
		)
		(polygon
			(pts
				(arc
					(start 29.72054 -12.9032)
					(mid 29.704917 -12.865483)
					(end 29.6672 -12.84986)
				)
				(arc
					(start 29.2608 -12.84986)
					(mid 29.223083 -12.865483)
					(end 29.20746 -12.9032)
				)
				(arc
					(start 29.20746 -13.2588)
					(mid 29.223083 -13.296517)
					(end 29.2608 -13.31214)
				)
				(arc
					(start 29.6672 -13.31214)
					(mid 29.704917 -13.296517)
					(end 29.72054 -13.2588)
				)
			)
		)
		(polygon
			(pts
				(arc
					(start 26.48204 -12.9032)
					(mid 26.466417 -12.865483)
					(end 26.4287 -12.84986)
				)
				(arc
					(start 26.0223 -12.84986)
					(mid 25.984583 -12.865483)
					(end 25.96896 -12.9032)
				)
				(arc
					(start 25.96896 -13.2588)
					(mid 25.984583 -13.296517)
					(end 26.0223 -13.31214)
				)
				(arc
					(start 26.4287 -13.31214)
					(mid 26.466417 -13.296517)
					(end 26.48204 -13.2588)
				)
			)
		)
		(polygon
			(pts
				(arc
					(start 25.72004 -12.9032)
					(mid 25.704417 -12.865483)
					(end 25.6667 -12.84986)
				)
				(arc
					(start 25.2603 -12.84986)
					(mid 25.222583 -12.865483)
					(end 25.20696 -12.9032)
				)
				(arc
					(start 25.20696 -13.2588)
					(mid 25.222583 -13.296517)
					(end 25.2603 -13.31214)
				)
				(arc
					(start 25.6667 -13.31214)
					(mid 25.704417 -13.296517)
					(end 25.72004 -13.2588)
				)
			)
		)
		(polygon
			(pts
				(arc
					(start 22.73554 -12.9032)
					(mid 22.719917 -12.865483)
					(end 22.6822 -12.84986)
				)
				(arc
					(start 22.2758 -12.84986)
					(mid 22.238083 -12.865483)
					(end 22.22246 -12.9032)
				)
				(arc
					(start 22.22246 -13.2588)
					(mid 22.238083 -13.296517)
					(end 22.2758 -13.31214)
				)
				(arc
					(start 22.6822 -13.31214)
					(mid 22.719917 -13.296517)
					(end 22.73554 -13.2588)
				)
			)
		)
		(polygon
			(pts
				(arc
					(start 21.97354 -12.9032)
					(mid 21.957917 -12.865483)
					(end 21.9202 -12.84986)
				)
				(arc
					(start 21.5138 -12.84986)
					(mid 21.476083 -12.865483)
					(end 21.46046 -12.9032)
				)
				(arc
					(start 21.46046 -13.2588)
					(mid 21.476083 -13.296517)
					(end 21.5138 -13.31214)
				)
				(arc
					(start 21.9202 -13.31214)
					(mid 21.957917 -13.296517)
					(end 21.97354 -13.2588)
				)
			)
		)
		(polygon
			(pts
				(arc
					(start 21.21154 -12.9032)
					(mid 21.195917 -12.865483)
					(end 21.1582 -12.84986)
				)
				(arc
					(start 20.7518 -12.84986)
					(mid 20.714083 -12.865483)
					(end 20.69846 -12.9032)
				)
				(arc
					(start 20.69846 -13.2588)
					(mid 20.714083 -13.296517)
					(end 20.7518 -13.31214)
				)
				(arc
					(start 21.1582 -13.31214)
					(mid 21.195917 -13.296517)
					(end 21.21154 -13.2588)
				)
			)
		)
		(polygon
			(pts
				(arc
					(start 20.44954 -12.9032)
					(mid 20.433917 -12.865483)
					(end 20.3962 -12.84986)
				)
				(arc
					(start 19.9898 -12.84986)
					(mid 19.952083 -12.865483)
					(end 19.93646 -12.9032)
				)
				(arc
					(start 19.93646 -13.2588)
					(mid 19.952083 -13.296517)
					(end 19.9898 -13.31214)
				)
				(arc
					(start 20.3962 -13.31214)
					(mid 20.433917 -13.296517)
					(end 20.44954 -13.2588)
				)
			)
		)
		(polygon
			(pts
				(arc
					(start 44.211494 -12.98194)
					(mid 44.59478 -12.598273)
					(end 44.21124 -12.21486)
				)
				(arc
					(start 43.25366 -12.21486)
					(mid 42.87012 -12.5984)
					(end 43.25366 -12.98194)
				)
			)
		)
		(polygon
			(pts
				(arc
					(start 46.48454 -12.1412)
					(mid 46.468917 -12.103483)
					(end 46.4312 -12.08786)
				)
				(arc
					(start 46.0248 -12.08786)
					(mid 45.987083 -12.103483)
					(end 45.97146 -12.1412)
				)
				(arc
					(start 45.97146 -12.4968)
					(mid 45.987083 -12.534517)
					(end 46.0248 -12.55014)
				)
				(arc
					(start 46.4312 -12.55014)
					(mid 46.468917 -12.534517)
					(end 46.48454 -12.4968)
				)
			)
		)
		(polygon
			(pts
				(arc
					(start 45.72254 -12.1412)
					(mid 45.706917 -12.103483)
					(end 45.6692 -12.08786)
				)
				(arc
					(start 45.2628 -12.08786)
					(mid 45.225083 -12.103483)
					(end 45.20946 -12.1412)
				)
				(arc
					(start 45.20946 -12.4968)
					(mid 45.225083 -12.534517)
					(end 45.2628 -12.55014)
				)
				(arc
					(start 45.6692 -12.55014)
					(mid 45.706917 -12.534517)
					(end 45.72254 -12.4968)
				)
			)
		)
		(polygon
			(pts
				(arc
					(start 42.487342 -12.1412)
					(mid 42.471719 -12.103483)
					(end 42.434002 -12.08786)
				)
				(arc
					(start 42.027602 -12.08786)
					(mid 41.989885 -12.103483)
					(end 41.974262 -12.1412)
				)
				(arc
					(start 41.974262 -12.4968)
					(mid 41.989885 -12.534517)
					(end 42.027602 -12.55014)
				)
				(arc
					(start 42.434002 -12.55014)
					(mid 42.471719 -12.534517)
					(end 42.487342 -12.4968)
				)
			)
		)
		(polygon
			(pts
				(arc
					(start 41.725342 -12.1412)
					(mid 41.709719 -12.103483)
					(end 41.672002 -12.08786)
				)
				(arc
					(start 41.265602 -12.08786)
					(mid 41.227885 -12.103483)
					(end 41.212262 -12.1412)
				)
				(arc
					(start 41.212262 -12.4968)
					(mid 41.227885 -12.534517)
					(end 41.265602 -12.55014)
				)
				(arc
					(start 41.672002 -12.55014)
					(mid 41.709719 -12.534517)
					(end 41.725342 -12.4968)
				)
			)
		)
		(polygon
			(pts
				(arc
					(start 38.48735 -12.1412)
					(mid 38.471727 -12.103483)
					(end 38.43401 -12.08786)
				)
				(arc
					(start 38.02761 -12.08786)
					(mid 37.989893 -12.103483)
					(end 37.97427 -12.1412)
				)
				(arc
					(start 37.97427 -12.4968)
					(mid 37.989893 -12.534517)
					(end 38.02761 -12.55014)
				)
				(arc
					(start 38.43401 -12.55014)
					(mid 38.471727 -12.534517)
					(end 38.48735 -12.4968)
				)
			)
		)
		(polygon
			(pts
				(arc
					(start 37.72535 -12.1412)
					(mid 37.709727 -12.103483)
					(end 37.67201 -12.08786)
				)
				(arc
					(start 37.26561 -12.08786)
					(mid 37.227893 -12.103483)
					(end 37.21227 -12.1412)
				)
				(arc
					(start 37.21227 -12.4968)
					(mid 37.227893 -12.534517)
					(end 37.26561 -12.55014)
				)
				(arc
					(start 37.67201 -12.55014)
					(mid 37.709727 -12.534517)
					(end 37.72535 -12.4968)
				)
			)
		)
		(polygon
			(pts
				(arc
					(start 34.49574 -12.1412)
					(mid 34.480117 -12.103483)
					(end 34.4424 -12.08786)
				)
				(arc
					(start 34.036 -12.08786)
					(mid 33.998283 -12.103483)
					(end 33.98266 -12.1412)
				)
				(arc
					(start 33.98266 -12.4968)
					(mid 33.998283 -12.534517)
					(end 34.036 -12.55014)
				)
				(arc
					(start 34.4424 -12.55014)
					(mid 34.480117 -12.534517)
					(end 34.49574 -12.4968)
				)
			)
		)
		(polygon
			(pts
				(arc
					(start 33.73374 -12.1412)
					(mid 33.718117 -12.103483)
					(end 33.6804 -12.08786)
				)
				(arc
					(start 33.274 -12.08786)
					(mid 33.236283 -12.103483)
					(end 33.22066 -12.1412)
				)
				(arc
					(start 33.22066 -12.4968)
					(mid 33.236283 -12.534517)
					(end 33.274 -12.55014)
				)
				(arc
					(start 33.6804 -12.55014)
					(mid 33.718117 -12.534517)
					(end 33.73374 -12.4968)
				)
			)
		)
		(polygon
			(pts
				(arc
					(start 30.48254 -12.1412)
					(mid 30.466917 -12.103483)
					(end 30.4292 -12.08786)
				)
				(arc
					(start 30.0228 -12.08786)
					(mid 29.985083 -12.103483)
					(end 29.96946 -12.1412)
				)
				(arc
					(start 29.96946 -12.4968)
					(mid 29.985083 -12.534517)
					(end 30.0228 -12.55014)
				)
				(arc
					(start 30.4292 -12.55014)
					(mid 30.466917 -12.534517)
					(end 30.48254 -12.4968)
				)
			)
		)
		(polygon
			(pts
				(arc
					(start 29.72054 -12.1412)
					(mid 29.704917 -12.103483)
					(end 29.6672 -12.08786)
				)
				(arc
					(start 29.2608 -12.08786)
					(mid 29.223083 -12.103483)
					(end 29.20746 -12.1412)
				)
				(arc
					(start 29.20746 -12.4968)
					(mid 29.223083 -12.534517)
					(end 29.2608 -12.55014)
				)
				(arc
					(start 29.6672 -12.55014)
					(mid 29.704917 -12.534517)
					(end 29.72054 -12.4968)
				)
			)
		)
		(polygon
			(pts
				(arc
					(start 26.48204 -12.1412)
					(mid 26.466417 -12.103483)
					(end 26.4287 -12.08786)
				)
				(arc
					(start 26.0223 -12.08786)
					(mid 25.984583 -12.103483)
					(end 25.96896 -12.1412)
				)
				(arc
					(start 25.96896 -12.4968)
					(mid 25.984583 -12.534517)
					(end 26.0223 -12.55014)
				)
				(arc
					(start 26.4287 -12.55014)
					(mid 26.466417 -12.534517)
					(end 26.48204 -12.4968)
				)
			)
		)
		(polygon
			(pts
				(arc
					(start 25.72004 -12.1412)
					(mid 25.704417 -12.103483)
					(end 25.6667 -12.08786)
				)
				(arc
					(start 25.2603 -12.08786)
					(mid 25.222583 -12.103483)
					(end 25.20696 -12.1412)
				)
				(arc
					(start 25.20696 -12.4968)
					(mid 25.222583 -12.534517)
					(end 25.2603 -12.55014)
				)
				(arc
					(start 25.6667 -12.55014)
					(mid 25.704417 -12.534517)
					(end 25.72004 -12.4968)
				)
			)
		)
		(polygon
			(pts
				(arc
					(start 22.73554 -12.1412)
					(mid 22.719917 -12.103483)
					(end 22.6822 -12.08786)
				)
				(arc
					(start 22.2758 -12.08786)
					(mid 22.238083 -12.103483)
					(end 22.22246 -12.1412)
				)
				(arc
					(start 22.22246 -12.4968)
					(mid 22.238083 -12.534517)
					(end 22.2758 -12.55014)
				)
				(arc
					(start 22.6822 -12.55014)
					(mid 22.719917 -12.534517)
					(end 22.73554 -12.4968)
				)
			)
		)
		(polygon
			(pts
				(arc
					(start 21.97354 -12.1412)
					(mid 21.957917 -12.103483)
					(end 21.9202 -12.08786)
				)
				(arc
					(start 21.5138 -12.08786)
					(mid 21.476083 -12.103483)
					(end 21.46046 -12.1412)
				)
				(arc
					(start 21.46046 -12.4968)
					(mid 21.476083 -12.534517)
					(end 21.5138 -12.55014)
				)
				(arc
					(start 21.9202 -12.55014)
					(mid 21.957917 -12.534517)
					(end 21.97354 -12.4968)
				)
			)
		)
		(polygon
			(pts
				(arc
					(start 21.21154 -12.1412)
					(mid 21.195917 -12.103483)
					(end 21.1582 -12.08786)
				)
				(arc
					(start 20.7518 -12.08786)
					(mid 20.714083 -12.103483)
					(end 20.69846 -12.1412)
				)
				(arc
					(start 20.69846 -12.4968)
					(mid 20.714083 -12.534517)
					(end 20.7518 -12.55014)
				)
				(arc
					(start 21.1582 -12.55014)
					(mid 21.195917 -12.534517)
					(end 21.21154 -12.4968)
				)
			)
		)
		(polygon
			(pts
				(arc
					(start 20.44954 -12.1412)
					(mid 20.433917 -12.103483)
					(end 20.3962 -12.08786)
				)
				(arc
					(start 19.9898 -12.08786)
					(mid 19.952083 -12.103483)
					(end 19.93646 -12.1412)
				)
				(arc
					(start 19.93646 -12.4968)
					(mid 19.952083 -12.534517)
					(end 19.9898 -12.55014)
				)
				(arc
					(start 20.3962 -12.55014)
					(mid 20.433917 -12.534517)
					(end 20.44954 -12.4968)
				)
			)
		)
		(polygon
			(pts
				(arc
					(start 40.40124 -12.73048)
					(mid 40.78478 -12.34694)
					(end 40.40124 -11.9634)
				)
				(arc
					(start 39.443406 -11.9634)
					(mid 39.06012 -12.347067)
					(end 39.44366 -12.73048)
				)
			)
		)
		(polygon
			(pts
				(arc
					(start 59.997594 -11.320018)
					(mid 60.381134 -10.936478)
					(end 59.997594 -10.552938)
				)
				(arc
					(start 59.07786 -10.552938)
					(mid 58.694574 -10.936605)
					(end 59.078114 -11.320018)
				)
			)
		)
		(polygon
			(pts
				(arc
					(start 84.310474 -10.79627)
					(mid 84.694014 -10.41273)
					(end 84.310474 -10.02919)
				)
				(arc
					(start 83.388708 -10.02919)
					(mid 83.005422 -10.412857)
					(end 83.388962 -10.79627)
				)
			)
		)
		(polygon
			(pts
				(arc
					(start 80.328516 -10.7188)
					(mid 80.712056 -10.33526)
					(end 80.328516 -9.95172)
				)
				(arc
					(start 79.370682 -9.95172)
					(mid 78.987396 -10.335387)
					(end 79.370936 -10.7188)
				)
			)
		)
		(polygon
			(pts
				(arc
					(start 76.328524 -10.668)
					(mid 76.712064 -10.28446)
					(end 76.328524 -9.90092)
				)
				(arc
					(start 75.37069 -9.90092)
					(mid 74.987404 -10.284587)
					(end 75.370944 -10.668)
				)
			)
		)
		(polygon
			(pts
				(arc
					(start 72.328532 -10.668)
					(mid 72.712072 -10.28446)
					(end 72.328532 -9.90092)
				)
				(arc
					(start 71.370698 -9.90092)
					(mid 70.987412 -10.284587)
					(end 71.370952 -10.668)
				)
			)
		)
		(polygon
			(pts
				(arc
					(start 68.303394 -10.668)
					(mid 68.68668 -10.284333)
					(end 68.30314 -9.90092)
				)
				(arc
					(start 67.34556 -9.90092)
					(mid 66.96202 -10.28446)
					(end 67.34556 -10.668)
				)
			)
		)
		(polygon
			(pts
				(arc
					(start 50.310542 -10.64387)
					(mid 50.694082 -10.26033)
					(end 50.310542 -9.87679)
				)
				(arc
					(start 49.388776 -9.87679)
					(mid 49.00549 -10.260457)
					(end 49.38903 -10.64387)
				)
			)
		)
		(polygon
			(pts
				(arc
					(start 62.328044 -10.634218)
					(mid 62.71133 -10.250551)
					(end 62.32779 -9.867138)
				)
				(arc
					(start 61.40831 -9.867138)
					(mid 61.02477 -10.250678)
					(end 61.40831 -10.634218)
				)
			)
		)
		(polygon
			(pts
				(arc
					(start 48.327818 -10.634218)
					(mid 48.711358 -10.250678)
					(end 48.327818 -9.867138)
				)
				(arc
					(start 47.408084 -9.867138)
					(mid 47.024798 -10.250805)
					(end 47.408338 -10.634218)
				)
			)
		)
		(polygon
			(pts
				(arc
					(start 44.327826 -10.634218)
					(mid 44.711366 -10.250678)
					(end 44.327826 -9.867138)
				)
				(arc
					(start 43.408092 -9.867138)
					(mid 43.024806 -10.250805)
					(end 43.408346 -10.634218)
				)
			)
		)
		(polygon
			(pts
				(arc
					(start 40.327834 -10.634218)
					(mid 40.711374 -10.250678)
					(end 40.327834 -9.867138)
				)
				(arc
					(start 39.4081 -9.867138)
					(mid 39.024814 -10.250805)
					(end 39.408354 -10.634218)
				)
			)
		)
		(polygon
			(pts
				(arc
					(start 36.328096 -10.634218)
					(mid 36.711382 -10.250551)
					(end 36.327842 -9.867138)
				)
				(arc
					(start 35.408362 -9.867138)
					(mid 35.024822 -10.250678)
					(end 35.408362 -10.634218)
				)
			)
		)
		(polygon
			(pts
				(arc
					(start 32.328104 -10.634218)
					(mid 32.71139 -10.250551)
					(end 32.32785 -9.867138)
				)
				(arc
					(start 31.40837 -9.867138)
					(mid 31.02483 -10.250678)
					(end 31.40837 -10.634218)
				)
			)
		)
		(polygon
			(pts
				(arc
					(start 28.328112 -10.634218)
					(mid 28.711398 -10.250551)
					(end 28.327858 -9.867138)
				)
				(arc
					(start 27.408378 -9.867138)
					(mid 27.024838 -10.250678)
					(end 27.408378 -10.634218)
				)
			)
		)
		(polygon
			(pts
				(arc
					(start 24.327866 -10.634218)
					(mid 24.711406 -10.250678)
					(end 24.327866 -9.867138)
				)
				(arc
					(start 23.408132 -9.867138)
					(mid 23.024846 -10.250805)
					(end 23.408386 -10.634218)
				)
			)
		)
		(polygon
			(pts
				(arc
					(start 20.327874 -10.634218)
					(mid 20.711414 -10.250678)
					(end 20.327874 -9.867138)
				)
				(arc
					(start 19.40814 -9.867138)
					(mid 19.024854 -10.250805)
					(end 19.408394 -10.634218)
				)
			)
		)
	)
	(zone
		(layer "In10.Cu")
		(hatch none 0.5)
		(connect_pads
			(clearance 0)
		)
		(min_thickness 0.25)
		(keepout
			(tracks not_allowed)
			(vias allowed)
			(pads allowed)
			(copperpour not_allowed)
			(footprints allowed)
		)
		(placement
			(enabled no)
			(sheetname "")
		)
		(fill
			(thermal_gap 0.5)
			(thermal_bridge_width 0.5)
			(island_removal_mode 0)
		)
		(polygon
			(pts
				(arc
					(start 73.40346 -13.3858)
					(mid 73.419083 -13.423517)
					(end 73.4568 -13.43914)
				)
				(arc
					(start 73.8632 -13.43914)
					(mid 73.900917 -13.423517)
					(end 73.91654 -13.3858)
				)
				(arc
					(start 73.91654 -13.0302)
					(mid 73.900917 -12.992483)
					(end 73.8632 -12.97686)
				)
				(arc
					(start 73.4568 -12.97686)
					(mid 73.419083 -12.992483)
					(end 73.40346 -13.0302)
				)
			)
		)
	)
	(zone
		(layer "In10.Cu")
		(hatch none 0.5)
		(connect_pads
			(clearance 0)
		)
		(min_thickness 0.25)
		(keepout
			(tracks not_allowed)
			(vias allowed)
			(pads allowed)
			(copperpour not_allowed)
			(footprints allowed)
		)
		(placement
			(enabled no)
			(sheetname "")
		)
		(fill
			(thermal_gap 0.5)
			(thermal_bridge_width 0.5)
			(island_removal_mode 0)
		)
		(polygon
			(pts
				(xy 49.991772 -4.097528) (xy 50.708052 -4.097528) (xy 50.708052 -8.293608) (xy 49.991772 -8.293608)
			)
		)
	)
	(zone
		(layer "In10.Cu")
		(hatch none 0.5)
		(connect_pads
			(clearance 0)
		)
		(min_thickness 0.25)
		(keepout
			(tracks not_allowed)
			(vias allowed)
			(pads allowed)
			(copperpour not_allowed)
			(footprints allowed)
		)
		(placement
			(enabled no)
			(sheetname "")
		)
		(fill
			(thermal_gap 0.5)
			(thermal_bridge_width 0.5)
			(island_removal_mode 0)
		)
		(polygon
			(pts
				(arc
					(start 45.20946 -13.2588)
					(mid 45.225083 -13.296517)
					(end 45.2628 -13.31214)
				)
				(arc
					(start 45.6692 -13.31214)
					(mid 45.706917 -13.296517)
					(end 45.72254 -13.2588)
				)
				(arc
					(start 45.72254 -12.9032)
					(mid 45.706917 -12.865483)
					(end 45.6692 -12.84986)
				)
				(arc
					(start 45.2628 -12.84986)
					(mid 45.225083 -12.865483)
					(end 45.20946 -12.9032)
				)
			)
		)
	)
	(zone
		(layer "In10.Cu")
		(hatch none 0.5)
		(connect_pads
			(clearance 0)
		)
		(min_thickness 0.25)
		(keepout
			(tracks not_allowed)
			(vias allowed)
			(pads allowed)
			(copperpour not_allowed)
			(footprints allowed)
		)
		(placement
			(enabled no)
			(sheetname "")
		)
		(fill
			(thermal_gap 0.5)
			(thermal_bridge_width 0.5)
			(island_removal_mode 0)
		)
		(polygon
			(pts
				(xy 6.349746 -61.10224) (xy 6.349746 -60.297568) (xy 4.800346 -60.297568) (xy 4.800346 -61.101986)
				(xy 4.8006 -61.10224)
			)
		)
	)
	(zone
		(layer "In10.Cu")
		(hatch none 0.5)
		(connect_pads
			(clearance 0)
		)
		(min_thickness 0.25)
		(keepout
			(tracks not_allowed)
			(vias allowed)
			(pads allowed)
			(copperpour not_allowed)
			(footprints allowed)
		)
		(placement
			(enabled no)
			(sheetname "")
		)
		(fill
			(thermal_gap 0.5)
			(thermal_bridge_width 0.5)
			(island_removal_mode 0)
		)
		(polygon
			(pts
				(arc
					(start 25.20696 -12.4968)
					(mid 25.222583 -12.534517)
					(end 25.2603 -12.55014)
				)
				(arc
					(start 25.6667 -12.55014)
					(mid 25.704417 -12.534517)
					(end 25.72004 -12.4968)
				)
				(arc
					(start 25.72004 -12.1412)
					(mid 25.704417 -12.103483)
					(end 25.6667 -12.08786)
				)
				(arc
					(start 25.2603 -12.08786)
					(mid 25.222583 -12.103483)
					(end 25.20696 -12.1412)
				)
			)
		)
	)
	(zone
		(layer "In10.Cu")
		(hatch none 0.5)
		(connect_pads
			(clearance 0)
		)
		(min_thickness 0.25)
		(keepout
			(tracks not_allowed)
			(vias allowed)
			(pads allowed)
			(copperpour not_allowed)
			(footprints allowed)
		)
		(placement
			(enabled no)
			(sheetname "")
		)
		(fill
			(thermal_gap 0.5)
			(thermal_bridge_width 0.5)
			(island_removal_mode 0)
		)
		(polygon
			(pts
				(arc
					(start 21.46046 -12.4968)
					(mid 21.476083 -12.534517)
					(end 21.5138 -12.55014)
				)
				(arc
					(start 21.9202 -12.55014)
					(mid 21.957917 -12.534517)
					(end 21.97354 -12.4968)
				)
				(arc
					(start 21.97354 -12.1412)
					(mid 21.957917 -12.103483)
					(end 21.9202 -12.08786)
				)
				(arc
					(start 21.5138 -12.08786)
					(mid 21.476083 -12.103483)
					(end 21.46046 -12.1412)
				)
			)
		)
	)
	(zone
		(layer "In10.Cu")
		(hatch none 0.5)
		(connect_pads
			(clearance 0)
		)
		(min_thickness 0.25)
		(keepout
			(tracks not_allowed)
			(vias allowed)
			(pads allowed)
			(copperpour not_allowed)
			(footprints allowed)
		)
		(placement
			(enabled no)
			(sheetname "")
		)
		(fill
			(thermal_gap 0.5)
			(thermal_bridge_width 0.5)
			(island_removal_mode 0)
		)
		(polygon
			(pts
				(arc
					(start 33.98266 -12.4968)
					(mid 33.998283 -12.534517)
					(end 34.036 -12.55014)
				)
				(arc
					(start 34.4424 -12.55014)
					(mid 34.480117 -12.534517)
					(end 34.49574 -12.4968)
				)
				(arc
					(start 34.49574 -12.1412)
					(mid 34.480117 -12.103483)
					(end 34.4424 -12.08786)
				)
				(arc
					(start 34.036 -12.08786)
					(mid 33.998283 -12.103483)
					(end 33.98266 -12.1412)
				)
			)
		)
	)
	(zone
		(layer "In10.Cu")
		(hatch none 0.5)
		(connect_pads
			(clearance 0)
		)
		(min_thickness 0.25)
		(keepout
			(tracks not_allowed)
			(vias allowed)
			(pads allowed)
			(copperpour not_allowed)
			(footprints allowed)
		)
		(placement
			(enabled no)
			(sheetname "")
		)
		(fill
			(thermal_gap 0.5)
			(thermal_bridge_width 0.5)
			(island_removal_mode 0)
		)
		(polygon
			(pts
				(arc
					(start 37.21227 -12.4968)
					(mid 37.227893 -12.534517)
					(end 37.26561 -12.55014)
				)
				(arc
					(start 37.67201 -12.55014)
					(mid 37.709727 -12.534517)
					(end 37.72535 -12.4968)
				)
				(arc
					(start 37.72535 -12.1412)
					(mid 37.709727 -12.103483)
					(end 37.67201 -12.08786)
				)
				(arc
					(start 37.26561 -12.08786)
					(mid 37.227893 -12.103483)
					(end 37.21227 -12.1412)
				)
			)
		)
	)
	(zone
		(layer "In10.Cu")
		(hatch none 0.5)
		(connect_pads
			(clearance 0)
		)
		(min_thickness 0.25)
		(keepout
			(tracks not_allowed)
			(vias allowed)
			(pads allowed)
			(copperpour not_allowed)
			(footprints allowed)
		)
		(placement
			(enabled no)
			(sheetname "")
		)
		(fill
			(thermal_gap 0.5)
			(thermal_bridge_width 0.5)
			(island_removal_mode 0)
		)
		(polygon
			(pts
				(arc
					(start 37.21227 -13.2588)
					(mid 37.227893 -13.296517)
					(end 37.26561 -13.31214)
				)
				(arc
					(start 37.67201 -13.31214)
					(mid 37.709727 -13.296517)
					(end 37.72535 -13.2588)
				)
				(arc
					(start 37.72535 -12.9032)
					(mid 37.709727 -12.865483)
					(end 37.67201 -12.84986)
				)
				(arc
					(start 37.26561 -12.84986)
					(mid 37.227893 -12.865483)
					(end 37.21227 -12.9032)
				)
			)
		)
	)
	(zone
		(layer "In10.Cu")
		(hatch none 0.5)
		(connect_pads
			(clearance 0)
		)
		(min_thickness 0.25)
		(keepout
			(tracks not_allowed)
			(vias allowed)
			(pads allowed)
			(copperpour not_allowed)
			(footprints allowed)
		)
		(placement
			(enabled no)
			(sheetname "")
		)
		(fill
			(thermal_gap 0.5)
			(thermal_bridge_width 0.5)
			(island_removal_mode 0)
		)
		(polygon
			(pts
				(xy 28.991814 -4.097528) (xy 29.708094 -4.097528) (xy 29.708094 -8.293608) (xy 28.991814 -8.293608)
			)
		)
	)
	(zone
		(layer "In10.Cu")
		(hatch none 0.5)
		(connect_pads
			(clearance 0)
		)
		(min_thickness 0.25)
		(keepout
			(tracks not_allowed)
			(vias allowed)
			(pads allowed)
			(copperpour not_allowed)
			(footprints allowed)
		)
		(placement
			(enabled no)
			(sheetname "")
		)
		(fill
			(thermal_gap 0.5)
			(thermal_bridge_width 0.5)
			(island_removal_mode 0)
		)
		(polygon
			(pts
				(arc
					(start 41.974262 -12.4968)
					(mid 41.989885 -12.534517)
					(end 42.027602 -12.55014)
				)
				(arc
					(start 42.434002 -12.55014)
					(mid 42.471719 -12.534517)
					(end 42.487342 -12.4968)
				)
				(arc
					(start 42.487342 -12.1412)
					(mid 42.471719 -12.103483)
					(end 42.434002 -12.08786)
				)
				(arc
					(start 42.027602 -12.08786)
					(mid 41.989885 -12.103483)
					(end 41.974262 -12.1412)
				)
			)
		)
	)
	(zone
		(layer "In10.Cu")
		(hatch none 0.5)
		(connect_pads
			(clearance 0)
		)
		(min_thickness 0.25)
		(keepout
			(tracks not_allowed)
			(vias allowed)
			(pads allowed)
			(copperpour not_allowed)
			(footprints allowed)
		)
		(placement
			(enabled no)
			(sheetname "")
		)
		(fill
			(thermal_gap 0.5)
			(thermal_bridge_width 0.5)
			(island_removal_mode 0)
		)
		(polygon
			(pts
				(arc
					(start 25.20696 -13.2588)
					(mid 25.222583 -13.296517)
					(end 25.2603 -13.31214)
				)
				(arc
					(start 25.6667 -13.31214)
					(mid 25.704417 -13.296517)
					(end 25.72004 -13.2588)
				)
				(arc
					(start 25.72004 -12.9032)
					(mid 25.704417 -12.865483)
					(end 25.6667 -12.84986)
				)
				(arc
					(start 25.2603 -12.84986)
					(mid 25.222583 -12.865483)
					(end 25.20696 -12.9032)
				)
			)
		)
	)
	(zone
		(layer "In10.Cu")
		(hatch none 0.5)
		(connect_pads
			(clearance 0)
		)
		(min_thickness 0.25)
		(keepout
			(tracks not_allowed)
			(vias allowed)
			(pads allowed)
			(copperpour not_allowed)
			(footprints allowed)
		)
		(placement
			(enabled no)
			(sheetname "")
		)
		(fill
			(thermal_gap 0.5)
			(thermal_bridge_width 0.5)
			(island_removal_mode 0)
		)
		(polygon
			(pts
				(arc
					(start 77.97546 -14.0208)
					(mid 77.991083 -14.058517)
					(end 78.0288 -14.07414)
				)
				(arc
					(start 78.4352 -14.07414)
					(mid 78.472917 -14.058517)
					(end 78.48854 -14.0208)
				)
				(arc
					(start 78.48854 -13.6652)
					(mid 78.472917 -13.627483)
					(end 78.4352 -13.61186)
				)
				(arc
					(start 78.0288 -13.61186)
					(mid 77.991083 -13.627483)
					(end 77.97546 -13.6652)
				)
			)
		)
	)
	(zone
		(layer "In10.Cu")
		(hatch none 0.5)
		(connect_pads
			(clearance 0)
		)
		(min_thickness 0.25)
		(keepout
			(tracks not_allowed)
			(vias allowed)
			(pads allowed)
			(copperpour not_allowed)
			(footprints allowed)
		)
		(placement
			(enabled no)
			(sheetname "")
		)
		(fill
			(thermal_gap 0.5)
			(thermal_bridge_width 0.5)
			(island_removal_mode 0)
		)
		(polygon
			(pts
				(arc
					(start 29.96946 -13.2588)
					(mid 29.985083 -13.296517)
					(end 30.0228 -13.31214)
				)
				(arc
					(start 30.4292 -13.31214)
					(mid 30.466917 -13.296517)
					(end 30.48254 -13.2588)
				)
				(arc
					(start 30.48254 -12.9032)
					(mid 30.466917 -12.865483)
					(end 30.4292 -12.84986)
				)
				(arc
					(start 30.0228 -12.84986)
					(mid 29.985083 -12.865483)
					(end 29.96946 -12.9032)
				)
			)
		)
	)
	(zone
		(layer "In10.Cu")
		(hatch none 0.5)
		(connect_pads
			(clearance 0)
		)
		(min_thickness 0.25)
		(keepout
			(tracks not_allowed)
			(vias allowed)
			(pads allowed)
			(copperpour not_allowed)
			(footprints allowed)
		)
		(placement
			(enabled no)
			(sheetname "")
		)
		(fill
			(thermal_gap 0.5)
			(thermal_bridge_width 0.5)
			(island_removal_mode 0)
		)
		(polygon
			(pts
				(xy 6.349746 -56.602376) (xy 6.349746 -55.79745) (xy 4.800346 -55.79745) (xy 4.800346 -56.602122)
				(xy 4.8006 -56.602376)
			)
		)
	)
	(zone
		(layer "In10.Cu")
		(hatch none 0.5)
		(connect_pads
			(clearance 0)
		)
		(min_thickness 0.25)
		(keepout
			(tracks not_allowed)
			(vias allowed)
			(pads allowed)
			(copperpour not_allowed)
			(footprints allowed)
		)
		(placement
			(enabled no)
			(sheetname "")
		)
		(fill
			(thermal_gap 0.5)
			(thermal_bridge_width 0.5)
			(island_removal_mode 0)
		)
		(polygon
			(pts
				(arc
					(start 22.22246 -13.2588)
					(mid 22.238083 -13.296517)
					(end 22.2758 -13.31214)
				)
				(arc
					(start 22.6822 -13.31214)
					(mid 22.719917 -13.296517)
					(end 22.73554 -13.2588)
				)
				(arc
					(start 22.73554 -12.9032)
					(mid 22.719917 -12.865483)
					(end 22.6822 -12.84986)
				)
				(arc
					(start 22.2758 -12.84986)
					(mid 22.238083 -12.865483)
					(end 22.22246 -12.9032)
				)
			)
		)
	)
	(zone
		(layer "In10.Cu")
		(hatch none 0.5)
		(connect_pads
			(clearance 0)
		)
		(min_thickness 0.25)
		(keepout
			(tracks not_allowed)
			(vias allowed)
			(pads allowed)
			(copperpour not_allowed)
			(footprints allowed)
		)
		(placement
			(enabled no)
			(sheetname "")
		)
		(fill
			(thermal_gap 0.5)
			(thermal_bridge_width 0.5)
			(island_removal_mode 0)
		)
		(polygon
			(pts
				(arc
					(start 66.04254 -13.7922)
					(mid 66.026917 -13.754483)
					(end 65.9892 -13.73886)
				)
				(arc
					(start 65.5828 -13.73886)
					(mid 65.545083 -13.754483)
					(end 65.52946 -13.7922)
				)
				(arc
					(start 65.52946 -14.1478)
					(mid 65.545083 -14.185517)
					(end 65.5828 -14.20114)
				)
				(arc
					(start 65.9892 -14.20114)
					(mid 66.026917 -14.185517)
					(end 66.04254 -14.1478)
				)
			)
		)
	)
	(zone
		(layer "In10.Cu")
		(hatch none 0.5)
		(connect_pads
			(clearance 0)
		)
		(min_thickness 0.25)
		(keepout
			(tracks not_allowed)
			(vias allowed)
			(pads allowed)
			(copperpour not_allowed)
			(footprints allowed)
		)
		(placement
			(enabled no)
			(sheetname "")
		)
		(fill
			(thermal_gap 0.5)
			(thermal_bridge_width 0.5)
			(island_removal_mode 0)
		)
		(polygon
			(pts
				(xy 6.349746 -59.60237) (xy 6.349746 -58.797444) (xy 4.800346 -58.797444) (xy 4.800346 -59.602116)
				(xy 4.8006 -59.60237)
			)
		)
	)
	(zone
		(layer "In10.Cu")
		(hatch none 0.5)
		(connect_pads
			(clearance 0)
		)
		(min_thickness 0.25)
		(keepout
			(tracks not_allowed)
			(vias allowed)
			(pads allowed)
			(copperpour not_allowed)
			(footprints allowed)
		)
		(placement
			(enabled no)
			(sheetname "")
		)
		(fill
			(thermal_gap 0.5)
			(thermal_bridge_width 0.5)
			(island_removal_mode 0)
		)
		(polygon
			(pts
				(xy 32.991806 -4.097528) (xy 33.708086 -4.097528) (xy 33.708086 -8.293608) (xy 32.991806 -8.293608)
			)
		)
	)
	(zone
		(layer "In10.Cu")
		(hatch none 0.5)
		(connect_pads
			(clearance 0)
		)
		(min_thickness 0.25)
		(keepout
			(tracks not_allowed)
			(vias allowed)
			(pads allowed)
			(copperpour not_allowed)
			(footprints allowed)
		)
		(placement
			(enabled no)
			(sheetname "")
		)
		(fill
			(thermal_gap 0.5)
			(thermal_bridge_width 0.5)
			(island_removal_mode 0)
		)
		(polygon
			(pts
				(arc
					(start 29.96946 -12.4968)
					(mid 29.985083 -12.534517)
					(end 30.0228 -12.55014)
				)
				(arc
					(start 30.4292 -12.55014)
					(mid 30.466917 -12.534517)
					(end 30.48254 -12.4968)
				)
				(arc
					(start 30.48254 -12.1412)
					(mid 30.466917 -12.103483)
					(end 30.4292 -12.08786)
				)
				(arc
					(start 30.0228 -12.08786)
					(mid 29.985083 -12.103483)
					(end 29.96946 -12.1412)
				)
			)
		)
	)
	(zone
		(layer "In10.Cu")
		(hatch none 0.5)
		(connect_pads
			(clearance 0)
		)
		(min_thickness 0.25)
		(keepout
			(tracks not_allowed)
			(vias allowed)
			(pads allowed)
			(copperpour not_allowed)
			(footprints allowed)
		)
		(placement
			(enabled no)
			(sheetname "")
		)
		(fill
			(thermal_gap 0.5)
			(thermal_bridge_width 0.5)
			(island_removal_mode 0)
		)
		(polygon
			(pts
				(arc
					(start 66.80454 -13.7922)
					(mid 66.788917 -13.754483)
					(end 66.7512 -13.73886)
				)
				(arc
					(start 66.3448 -13.73886)
					(mid 66.307083 -13.754483)
					(end 66.29146 -13.7922)
				)
				(arc
					(start 66.29146 -14.1478)
					(mid 66.307083 -14.185517)
					(end 66.3448 -14.20114)
				)
				(arc
					(start 66.7512 -14.20114)
					(mid 66.788917 -14.185517)
					(end 66.80454 -14.1478)
				)
			)
		)
	)
	(zone
		(layer "In10.Cu")
		(hatch none 0.5)
		(connect_pads
			(clearance 0)
		)
		(min_thickness 0.25)
		(keepout
			(tracks not_allowed)
			(vias allowed)
			(pads allowed)
			(copperpour not_allowed)
			(footprints allowed)
		)
		(placement
			(enabled no)
			(sheetname "")
		)
		(fill
			(thermal_gap 0.5)
			(thermal_bridge_width 0.5)
			(island_removal_mode 0)
		)
		(polygon
			(pts
				(xy 6.349746 -67.102228) (xy 6.349746 -66.297556) (xy 4.800346 -66.297556) (xy 4.800346 -67.101974)
				(xy 4.8006 -67.102228)
			)
		)
	)
	(zone
		(layer "In10.Cu")
		(hatch none 0.5)
		(connect_pads
			(clearance 0)
		)
		(min_thickness 0.25)
		(keepout
			(tracks not_allowed)
			(vias allowed)
			(pads allowed)
			(copperpour not_allowed)
			(footprints allowed)
		)
		(placement
			(enabled no)
			(sheetname "")
		)
		(fill
			(thermal_gap 0.5)
			(thermal_bridge_width 0.5)
			(island_removal_mode 0)
		)
		(polygon
			(pts
				(xy 40.99179 -4.097528) (xy 41.70807 -4.097528) (xy 41.70807 -8.293608) (xy 40.99179 -8.293608)
			)
		)
	)
	(zone
		(layer "In10.Cu")
		(hatch none 0.5)
		(connect_pads
			(clearance 0)
		)
		(min_thickness 0.25)
		(keepout
			(tracks not_allowed)
			(vias allowed)
			(pads allowed)
			(copperpour not_allowed)
			(footprints allowed)
		)
		(placement
			(enabled no)
			(sheetname "")
		)
		(fill
			(thermal_gap 0.5)
			(thermal_bridge_width 0.5)
			(island_removal_mode 0)
		)
		(polygon
			(pts
				(arc
					(start 66.80454 -13.0302)
					(mid 66.788917 -12.992483)
					(end 66.7512 -12.97686)
				)
				(arc
					(start 66.3448 -12.97686)
					(mid 66.307083 -12.992483)
					(end 66.29146 -13.0302)
				)
				(arc
					(start 66.29146 -13.3858)
					(mid 66.307083 -13.423517)
					(end 66.3448 -13.43914)
				)
				(arc
					(start 66.7512 -13.43914)
					(mid 66.788917 -13.423517)
					(end 66.80454 -13.3858)
				)
			)
		)
	)
	(zone
		(layer "In10.Cu")
		(hatch none 0.5)
		(connect_pads
			(clearance 0)
		)
		(min_thickness 0.25)
		(keepout
			(tracks not_allowed)
			(vias allowed)
			(pads allowed)
			(copperpour not_allowed)
			(footprints allowed)
		)
		(placement
			(enabled no)
			(sheetname "")
		)
		(fill
			(thermal_gap 0.5)
			(thermal_bridge_width 0.5)
			(island_removal_mode 0)
		)
		(polygon
			(pts
				(xy 41.991788 -4.097528) (xy 42.708068 -4.097528) (xy 42.708068 -8.293608) (xy 41.991788 -8.293608)
			)
		)
	)
	(zone
		(layer "In10.Cu")
		(hatch none 0.5)
		(connect_pads
			(clearance 0)
		)
		(min_thickness 0.25)
		(keepout
			(tracks not_allowed)
			(vias allowed)
			(pads allowed)
			(copperpour not_allowed)
			(footprints allowed)
		)
		(placement
			(enabled no)
			(sheetname "")
		)
		(fill
			(thermal_gap 0.5)
			(thermal_bridge_width 0.5)
			(island_removal_mode 0)
		)
		(polygon
			(pts
				(xy 64.991742 -4.097528) (xy 65.708022 -4.097528) (xy 65.708022 -8.293608) (xy 64.991742 -8.293608)
			)
		)
	)
	(zone
		(layer "In10.Cu")
		(hatch none 0.5)
		(connect_pads
			(clearance 0)
		)
		(min_thickness 0.25)
		(keepout
			(tracks not_allowed)
			(vias allowed)
			(pads allowed)
			(copperpour not_allowed)
			(footprints allowed)
		)
		(placement
			(enabled no)
			(sheetname "")
		)
		(fill
			(thermal_gap 0.5)
			(thermal_bridge_width 0.5)
			(island_removal_mode 0)
		)
		(polygon
			(pts
				(arc
					(start 66.04254 -13.0302)
					(mid 66.026917 -12.992483)
					(end 65.9892 -12.97686)
				)
				(arc
					(start 65.5828 -12.97686)
					(mid 65.545083 -12.992483)
					(end 65.52946 -13.0302)
				)
				(arc
					(start 65.52946 -13.3858)
					(mid 65.545083 -13.423517)
					(end 65.5828 -13.43914)
				)
				(arc
					(start 65.9892 -13.43914)
					(mid 66.026917 -13.423517)
					(end 66.04254 -13.3858)
				)
			)
		)
	)
	(zone
		(layer "In10.Cu")
		(hatch none 0.5)
		(connect_pads
			(clearance 0)
		)
		(min_thickness 0.25)
		(keepout
			(tracks not_allowed)
			(vias allowed)
			(pads allowed)
			(copperpour not_allowed)
			(footprints allowed)
		)
		(placement
			(enabled no)
			(sheetname "")
		)
		(fill
			(thermal_gap 0.5)
			(thermal_bridge_width 0.5)
			(island_removal_mode 0)
		)
		(polygon
			(pts
				(xy 6.349746 -58.102246) (xy 6.349746 -57.297574) (xy 4.800346 -57.297574) (xy 4.800346 -58.101992)
				(xy 4.8006 -58.102246)
			)
		)
	)
	(zone
		(layer "In10.Cu")
		(hatch none 0.5)
		(connect_pads
			(clearance 0)
		)
		(min_thickness 0.25)
		(keepout
			(tracks not_allowed)
			(vias allowed)
			(pads allowed)
			(copperpour not_allowed)
			(footprints allowed)
		)
		(placement
			(enabled no)
			(sheetname "")
		)
		(fill
			(thermal_gap 0.5)
			(thermal_bridge_width 0.5)
			(island_removal_mode 0)
		)
		(polygon
			(pts
				(arc
					(start 22.22246 -12.4968)
					(mid 22.238083 -12.534517)
					(end 22.2758 -12.55014)
				)
				(arc
					(start 22.6822 -12.55014)
					(mid 22.719917 -12.534517)
					(end 22.73554 -12.4968)
				)
				(arc
					(start 22.73554 -12.1412)
					(mid 22.719917 -12.103483)
					(end 22.6822 -12.08786)
				)
				(arc
					(start 22.2758 -12.08786)
					(mid 22.238083 -12.103483)
					(end 22.22246 -12.1412)
				)
			)
		)
	)
	(zone
		(layer "In10.Cu")
		(hatch none 0.5)
		(connect_pads
			(clearance 0)
		)
		(min_thickness 0.25)
		(keepout
			(tracks not_allowed)
			(vias allowed)
			(pads allowed)
			(copperpour not_allowed)
			(footprints allowed)
		)
		(placement
			(enabled no)
			(sheetname "")
		)
		(fill
			(thermal_gap 0.5)
			(thermal_bridge_width 0.5)
			(island_removal_mode 0)
		)
		(polygon
			(pts
				(xy 20.99183 -4.097528) (xy 21.70811 -4.097528) (xy 21.70811 -8.293608) (xy 20.99183 -8.293608)
			)
		)
	)
	(zone
		(layer "In10.Cu")
		(hatch none 0.5)
		(connect_pads
			(clearance 0)
		)
		(min_thickness 0.25)
		(keepout
			(tracks not_allowed)
			(vias allowed)
			(pads allowed)
			(copperpour not_allowed)
			(footprints allowed)
		)
		(placement
			(enabled no)
			(sheetname "")
		)
		(fill
			(thermal_gap 0.5)
			(thermal_bridge_width 0.5)
			(island_removal_mode 0)
		)
		(polygon
			(pts
				(xy 80.99171 -4.097528) (xy 81.70799 -4.097528) (xy 81.70799 -8.293608) (xy 80.99171 -8.293608)
			)
		)
	)
	(zone
		(layer "In10.Cu")
		(hatch none 0.5)
		(connect_pads
			(clearance 0)
		)
		(min_thickness 0.25)
		(keepout
			(tracks not_allowed)
			(vias allowed)
			(pads allowed)
			(copperpour not_allowed)
			(footprints allowed)
		)
		(placement
			(enabled no)
			(sheetname "")
		)
		(fill
			(thermal_gap 0.5)
			(thermal_bridge_width 0.5)
			(island_removal_mode 0)
		)
		(polygon
			(pts
				(arc
					(start 77.21346 -14.0208)
					(mid 77.229083 -14.058517)
					(end 77.2668 -14.07414)
				)
				(arc
					(start 77.6732 -14.07414)
					(mid 77.710917 -14.058517)
					(end 77.72654 -14.0208)
				)
				(arc
					(start 77.72654 -13.6652)
					(mid 77.710917 -13.627483)
					(end 77.6732 -13.61186)
				)
				(arc
					(start 77.2668 -13.61186)
					(mid 77.229083 -13.627483)
					(end 77.21346 -13.6652)
				)
			)
		)
	)
	(zone
		(layer "In10.Cu")
		(hatch none 0.5)
		(connect_pads
			(clearance 0)
		)
		(min_thickness 0.25)
		(keepout
			(tracks not_allowed)
			(vias allowed)
			(pads allowed)
			(copperpour not_allowed)
			(footprints allowed)
		)
		(placement
			(enabled no)
			(sheetname "")
		)
		(fill
			(thermal_gap 0.5)
			(thermal_bridge_width 0.5)
			(island_removal_mode 0)
		)
		(polygon
			(pts
				(arc
					(start 41.212262 -12.4968)
					(mid 41.227885 -12.534517)
					(end 41.265602 -12.55014)
				)
				(arc
					(start 41.672002 -12.55014)
					(mid 41.709719 -12.534517)
					(end 41.725342 -12.4968)
				)
				(arc
					(start 41.725342 -12.1412)
					(mid 41.709719 -12.103483)
					(end 41.672002 -12.08786)
				)
				(arc
					(start 41.265602 -12.08786)
					(mid 41.227885 -12.103483)
					(end 41.212262 -12.1412)
				)
			)
		)
	)
	(zone
		(layer "In10.Cu")
		(hatch none 0.5)
		(connect_pads
			(clearance 0)
		)
		(min_thickness 0.25)
		(keepout
			(tracks not_allowed)
			(vias allowed)
			(pads allowed)
			(copperpour not_allowed)
			(footprints allowed)
		)
		(placement
			(enabled no)
			(sheetname "")
		)
		(fill
			(thermal_gap 0.5)
			(thermal_bridge_width 0.5)
			(island_removal_mode 0)
		)
		(polygon
			(pts
				(arc
					(start 72.64146 -13.3858)
					(mid 72.657083 -13.423517)
					(end 72.6948 -13.43914)
				)
				(arc
					(start 73.1012 -13.43914)
					(mid 73.138917 -13.423517)
					(end 73.15454 -13.3858)
				)
				(arc
					(start 73.15454 -13.0302)
					(mid 73.138917 -12.992483)
					(end 73.1012 -12.97686)
				)
				(arc
					(start 72.6948 -12.97686)
					(mid 72.657083 -12.992483)
					(end 72.64146 -13.0302)
				)
			)
		)
	)
	(zone
		(layer "In10.Cu")
		(hatch none 0.5)
		(connect_pads
			(clearance 0)
		)
		(min_thickness 0.25)
		(keepout
			(tracks not_allowed)
			(vias allowed)
			(pads allowed)
			(copperpour not_allowed)
			(footprints allowed)
		)
		(placement
			(enabled no)
			(sheetname "")
		)
		(fill
			(thermal_gap 0.5)
			(thermal_bridge_width 0.5)
			(island_removal_mode 0)
		)
		(polygon
			(pts
				(arc
					(start 21.46046 -13.2588)
					(mid 21.476083 -13.296517)
					(end 21.5138 -13.31214)
				)
				(arc
					(start 21.9202 -13.31214)
					(mid 21.957917 -13.296517)
					(end 21.97354 -13.2588)
				)
				(arc
					(start 21.97354 -12.9032)
					(mid 21.957917 -12.865483)
					(end 21.9202 -12.84986)
				)
				(arc
					(start 21.5138 -12.84986)
					(mid 21.476083 -12.865483)
					(end 21.46046 -12.9032)
				)
			)
		)
	)
	(zone
		(layer "In10.Cu")
		(hatch none 0.5)
		(connect_pads
			(clearance 0)
		)
		(min_thickness 0.25)
		(keepout
			(tracks not_allowed)
			(vias allowed)
			(pads allowed)
			(copperpour not_allowed)
			(footprints allowed)
		)
		(placement
			(enabled no)
			(sheetname "")
		)
		(fill
			(thermal_gap 0.5)
			(thermal_bridge_width 0.5)
			(island_removal_mode 0)
		)
		(polygon
			(pts
				(xy 88.991948 -4.097528) (xy 89.708228 -4.097528) (xy 89.708228 -8.293608) (xy 88.991948 -8.293608)
			)
		)
	)
	(zone
		(layer "In10.Cu")
		(hatch none 0.5)
		(connect_pads
			(clearance 0)
		)
		(min_thickness 0.25)
		(keepout
			(tracks not_allowed)
			(vias allowed)
			(pads allowed)
			(copperpour not_allowed)
			(footprints allowed)
		)
		(placement
			(enabled no)
			(sheetname "")
		)
		(fill
			(thermal_gap 0.5)
			(thermal_bridge_width 0.5)
			(island_removal_mode 0)
		)
		(polygon
			(pts
				(xy 44.991782 -4.097528) (xy 45.708062 -4.097528) (xy 45.708062 -8.293608) (xy 44.991782 -8.293608)
			)
		)
	)
	(zone
		(layer "In10.Cu")
		(hatch none 0.5)
		(connect_pads
			(clearance 0)
		)
		(min_thickness 0.25)
		(keepout
			(tracks not_allowed)
			(vias allowed)
			(pads allowed)
			(copperpour not_allowed)
			(footprints allowed)
		)
		(placement
			(enabled no)
			(sheetname "")
		)
		(fill
			(thermal_gap 0.5)
			(thermal_bridge_width 0.5)
			(island_removal_mode 0)
		)
		(polygon
			(pts
				(arc
					(start 66.9798 -30.02534)
					(mid 67.017517 -30.009717)
					(end 67.03314 -29.972)
				)
				(arc
					(start 67.03314 -29.5656)
					(mid 67.017517 -29.527883)
					(end 66.9798 -29.51226)
				)
				(arc
					(start 66.6242 -29.51226)
					(mid 66.586483 -29.527883)
					(end 66.57086 -29.5656)
				)
				(arc
					(start 66.57086 -29.972)
					(mid 66.586483 -30.009717)
					(end 66.6242 -30.02534)
				)
			)
		)
	)
	(zone
		(layer "In10.Cu")
		(hatch none 0.5)
		(connect_pads
			(clearance 0)
		)
		(min_thickness 0.25)
		(keepout
			(tracks not_allowed)
			(vias allowed)
			(pads allowed)
			(copperpour not_allowed)
			(footprints allowed)
		)
		(placement
			(enabled no)
			(sheetname "")
		)
		(fill
			(thermal_gap 0.5)
			(thermal_bridge_width 0.5)
			(island_removal_mode 0)
		)
		(polygon
			(pts
				(xy 48.991774 -4.097528) (xy 49.708054 -4.097528) (xy 49.708054 -8.293608) (xy 48.991774 -8.293608)
			)
		)
	)
	(zone
		(layer "In10.Cu")
		(hatch none 0.5)
		(connect_pads
			(clearance 0)
		)
		(min_thickness 0.25)
		(keepout
			(tracks not_allowed)
			(vias allowed)
			(pads allowed)
			(copperpour not_allowed)
			(footprints allowed)
		)
		(placement
			(enabled no)
			(sheetname "")
		)
		(fill
			(thermal_gap 0.5)
			(thermal_bridge_width 0.5)
			(island_removal_mode 0)
		)
		(polygon
			(pts
				(xy 89.991946 -4.097528) (xy 90.708226 -4.097528) (xy 90.708226 -8.293608) (xy 89.991946 -8.293608)
			)
		)
	)
	(zone
		(layer "In10.Cu")
		(hatch none 0.5)
		(connect_pads
			(clearance 0)
		)
		(min_thickness 0.25)
		(keepout
			(tracks not_allowed)
			(vias allowed)
			(pads allowed)
			(copperpour not_allowed)
			(footprints allowed)
		)
		(placement
			(enabled no)
			(sheetname "")
		)
		(fill
			(thermal_gap 0.5)
			(thermal_bridge_width 0.5)
			(island_removal_mode 0)
		)
		(polygon
			(pts
				(arc
					(start 45.97146 -13.2588)
					(mid 45.987083 -13.296517)
					(end 46.0248 -13.31214)
				)
				(arc
					(start 46.4312 -13.31214)
					(mid 46.468917 -13.296517)
					(end 46.48454 -13.2588)
				)
				(arc
					(start 46.48454 -12.9032)
					(mid 46.468917 -12.865483)
					(end 46.4312 -12.84986)
				)
				(arc
					(start 46.0248 -12.84986)
					(mid 45.987083 -12.865483)
					(end 45.97146 -12.9032)
				)
			)
		)
	)
	(zone
		(layer "In10.Cu")
		(hatch none 0.5)
		(connect_pads
			(clearance 0)
		)
		(min_thickness 0.25)
		(keepout
			(tracks not_allowed)
			(vias allowed)
			(pads allowed)
			(copperpour not_allowed)
			(footprints allowed)
		)
		(placement
			(enabled no)
			(sheetname "")
		)
		(fill
			(thermal_gap 0.5)
			(thermal_bridge_width 0.5)
			(island_removal_mode 0)
		)
		(polygon
			(pts
				(arc
					(start 67.81546 -14.1478)
					(mid 67.831083 -14.185517)
					(end 67.8688 -14.20114)
				)
				(arc
					(start 68.2752 -14.20114)
					(mid 68.312917 -14.185517)
					(end 68.32854 -14.1478)
				)
				(arc
					(start 68.32854 -13.7922)
					(mid 68.312917 -13.754483)
					(end 68.2752 -13.73886)
				)
				(arc
					(start 67.8688 -13.73886)
					(mid 67.831083 -13.754483)
					(end 67.81546 -13.7922)
				)
			)
		)
	)
	(zone
		(layer "In10.Cu")
		(hatch none 0.5)
		(connect_pads
			(clearance 0)
		)
		(min_thickness 0.25)
		(keepout
			(tracks not_allowed)
			(vias allowed)
			(pads allowed)
			(copperpour not_allowed)
			(footprints allowed)
		)
		(placement
			(enabled no)
			(sheetname "")
		)
		(fill
			(thermal_gap 0.5)
			(thermal_bridge_width 0.5)
			(island_removal_mode 0)
		)
		(polygon
			(pts
				(arc
					(start 77.21346 -13.2588)
					(mid 77.229083 -13.296517)
					(end 77.2668 -13.31214)
				)
				(arc
					(start 77.6732 -13.31214)
					(mid 77.710917 -13.296517)
					(end 77.72654 -13.2588)
				)
				(arc
					(start 77.72654 -12.9032)
					(mid 77.710917 -12.865483)
					(end 77.6732 -12.84986)
				)
				(arc
					(start 77.2668 -12.84986)
					(mid 77.229083 -12.865483)
					(end 77.21346 -12.9032)
				)
			)
		)
	)
	(zone
		(layer "In10.Cu")
		(hatch none 0.5)
		(connect_pads
			(clearance 0)
		)
		(min_thickness 0.25)
		(keepout
			(tracks not_allowed)
			(vias allowed)
			(pads allowed)
			(copperpour not_allowed)
			(footprints allowed)
		)
		(placement
			(enabled no)
			(sheetname "")
		)
		(fill
			(thermal_gap 0.5)
			(thermal_bridge_width 0.5)
			(island_removal_mode 0)
		)
		(polygon
			(pts
				(arc
					(start 67.7418 -30.02534)
					(mid 67.779517 -30.009717)
					(end 67.79514 -29.972)
				)
				(arc
					(start 67.79514 -29.5656)
					(mid 67.779517 -29.527883)
					(end 67.7418 -29.51226)
				)
				(arc
					(start 67.3862 -29.51226)
					(mid 67.348483 -29.527883)
					(end 67.33286 -29.5656)
				)
				(arc
					(start 67.33286 -29.972)
					(mid 67.348483 -30.009717)
					(end 67.3862 -30.02534)
				)
			)
		)
	)
	(zone
		(layer "In10.Cu")
		(hatch none 0.5)
		(connect_pads
			(clearance 0)
		)
		(min_thickness 0.25)
		(keepout
			(tracks not_allowed)
			(vias allowed)
			(pads allowed)
			(copperpour not_allowed)
			(footprints allowed)
		)
		(placement
			(enabled no)
			(sheetname "")
		)
		(fill
			(thermal_gap 0.5)
			(thermal_bridge_width 0.5)
			(island_removal_mode 0)
		)
		(polygon
			(pts
				(xy 6.349746 -62.602364) (xy 6.349746 -61.797438) (xy 4.800346 -61.797438) (xy 4.800346 -62.60211)
				(xy 4.8006 -62.602364)
			)
		)
	)
	(zone
		(layer "In10.Cu")
		(hatch none 0.5)
		(connect_pads
			(clearance 0)
		)
		(min_thickness 0.25)
		(keepout
			(tracks not_allowed)
			(vias allowed)
			(pads allowed)
			(copperpour not_allowed)
			(footprints allowed)
		)
		(placement
			(enabled no)
			(sheetname "")
		)
		(fill
			(thermal_gap 0.5)
			(thermal_bridge_width 0.5)
			(island_removal_mode 0)
		)
		(polygon
			(pts
				(arc
					(start 77.97546 -13.2588)
					(mid 77.991083 -13.296517)
					(end 78.0288 -13.31214)
				)
				(arc
					(start 78.4352 -13.31214)
					(mid 78.472917 -13.296517)
					(end 78.48854 -13.2588)
				)
				(arc
					(start 78.48854 -12.9032)
					(mid 78.472917 -12.865483)
					(end 78.4352 -12.84986)
				)
				(arc
					(start 78.0288 -12.84986)
					(mid 77.991083 -12.865483)
					(end 77.97546 -12.9032)
				)
			)
		)
	)
	(zone
		(layer "In10.Cu")
		(hatch none 0.5)
		(connect_pads
			(clearance 0)
		)
		(min_thickness 0.25)
		(keepout
			(tracks not_allowed)
			(vias allowed)
			(pads allowed)
			(copperpour not_allowed)
			(footprints allowed)
		)
		(placement
			(enabled no)
			(sheetname "")
		)
		(fill
			(thermal_gap 0.5)
			(thermal_bridge_width 0.5)
			(island_removal_mode 0)
		)
		(polygon
			(pts
				(arc
					(start 80.00746 -13.2588)
					(mid 80.023083 -13.296517)
					(end 80.0608 -13.31214)
				)
				(arc
					(start 80.4672 -13.31214)
					(mid 80.504917 -13.296517)
					(end 80.52054 -13.2588)
				)
				(arc
					(start 80.52054 -12.9032)
					(mid 80.504917 -12.865483)
					(end 80.4672 -12.84986)
				)
				(arc
					(start 80.0608 -12.84986)
					(mid 80.023083 -12.865483)
					(end 80.00746 -12.9032)
				)
			)
		)
	)
	(zone
		(layer "In10.Cu")
		(hatch none 0.5)
		(connect_pads
			(clearance 0)
		)
		(min_thickness 0.25)
		(keepout
			(tracks not_allowed)
			(vias allowed)
			(pads allowed)
			(copperpour not_allowed)
			(footprints allowed)
		)
		(placement
			(enabled no)
			(sheetname "")
		)
		(fill
			(thermal_gap 0.5)
			(thermal_bridge_width 0.5)
			(island_removal_mode 0)
		)
		(polygon
			(pts
				(arc
					(start 66.9798 -28.57754)
					(mid 67.017517 -28.561917)
					(end 67.03314 -28.5242)
				)
				(arc
					(start 67.03314 -28.1178)
					(mid 67.017517 -28.080083)
					(end 66.9798 -28.06446)
				)
				(arc
					(start 66.6242 -28.06446)
					(mid 66.586483 -28.080083)
					(end 66.57086 -28.1178)
				)
				(arc
					(start 66.57086 -28.5242)
					(mid 66.586483 -28.561917)
					(end 66.6242 -28.57754)
				)
			)
		)
	)
	(zone
		(layer "In10.Cu")
		(hatch none 0.5)
		(connect_pads
			(clearance 0)
		)
		(min_thickness 0.25)
		(keepout
			(tracks not_allowed)
			(vias allowed)
			(pads allowed)
			(copperpour not_allowed)
			(footprints allowed)
		)
		(placement
			(enabled no)
			(sheetname "")
		)
		(fill
			(thermal_gap 0.5)
			(thermal_bridge_width 0.5)
			(island_removal_mode 0)
		)
		(polygon
			(pts
				(arc
					(start 25.96896 -13.2588)
					(mid 25.984583 -13.296517)
					(end 26.0223 -13.31214)
				)
				(arc
					(start 26.4287 -13.31214)
					(mid 26.466417 -13.296517)
					(end 26.48204 -13.2588)
				)
				(arc
					(start 26.48204 -12.9032)
					(mid 26.466417 -12.865483)
					(end 26.4287 -12.84986)
				)
				(arc
					(start 26.0223 -12.84986)
					(mid 25.984583 -12.865483)
					(end 25.96896 -12.9032)
				)
			)
		)
	)
	(zone
		(layer "In10.Cu")
		(hatch none 0.5)
		(connect_pads
			(clearance 0)
		)
		(min_thickness 0.25)
		(keepout
			(tracks not_allowed)
			(vias allowed)
			(pads allowed)
			(copperpour not_allowed)
			(footprints allowed)
		)
		(placement
			(enabled no)
			(sheetname "")
		)
		(fill
			(thermal_gap 0.5)
			(thermal_bridge_width 0.5)
			(island_removal_mode 0)
		)
		(polygon
			(pts
				(arc
					(start 29.20746 -13.2588)
					(mid 29.223083 -13.296517)
					(end 29.2608 -13.31214)
				)
				(arc
					(start 29.6672 -13.31214)
					(mid 29.704917 -13.296517)
					(end 29.72054 -13.2588)
				)
				(arc
					(start 29.72054 -12.9032)
					(mid 29.704917 -12.865483)
					(end 29.6672 -12.84986)
				)
				(arc
					(start 29.2608 -12.84986)
					(mid 29.223083 -12.865483)
					(end 29.20746 -12.9032)
				)
			)
		)
	)
	(zone
		(layer "In10.Cu")
		(hatch none 0.5)
		(connect_pads
			(clearance 0)
		)
		(min_thickness 0.25)
		(keepout
			(tracks not_allowed)
			(vias allowed)
			(pads allowed)
			(copperpour not_allowed)
			(footprints allowed)
		)
		(placement
			(enabled no)
			(sheetname "")
		)
		(fill
			(thermal_gap 0.5)
			(thermal_bridge_width 0.5)
			(island_removal_mode 0)
		)
		(polygon
			(pts
				(xy 81.991708 -4.097528) (xy 82.707988 -4.097528) (xy 82.707988 -8.293608) (xy 81.991708 -8.293608)
			)
		)
	)
	(zone
		(layer "In10.Cu")
		(hatch none 0.5)
		(connect_pads
			(clearance 0)
		)
		(min_thickness 0.25)
		(keepout
			(tracks not_allowed)
			(vias allowed)
			(pads allowed)
			(copperpour not_allowed)
			(footprints allowed)
		)
		(placement
			(enabled no)
			(sheetname "")
		)
		(fill
			(thermal_gap 0.5)
			(thermal_bridge_width 0.5)
			(island_removal_mode 0)
		)
		(polygon
			(pts
				(xy 17.991836 -4.097528) (xy 18.708116 -4.097528) (xy 18.708116 -8.293608) (xy 17.991836 -8.293608)
			)
		)
	)
	(zone
		(layer "In10.Cu")
		(hatch none 0.5)
		(connect_pads
			(clearance 0)
		)
		(min_thickness 0.25)
		(keepout
			(tracks not_allowed)
			(vias allowed)
			(pads allowed)
			(copperpour not_allowed)
			(footprints allowed)
		)
		(placement
			(enabled no)
			(sheetname "")
		)
		(fill
			(thermal_gap 0.5)
			(thermal_bridge_width 0.5)
			(island_removal_mode 0)
		)
		(polygon
			(pts
				(arc
					(start 73.40346 -14.1478)
					(mid 73.419083 -14.185517)
					(end 73.4568 -14.20114)
				)
				(arc
					(start 73.8632 -14.20114)
					(mid 73.900917 -14.185517)
					(end 73.91654 -14.1478)
				)
				(arc
					(start 73.91654 -13.7922)
					(mid 73.900917 -13.754483)
					(end 73.8632 -13.73886)
				)
				(arc
					(start 73.4568 -13.73886)
					(mid 73.419083 -13.754483)
					(end 73.40346 -13.7922)
				)
			)
		)
	)
	(zone
		(layer "In10.Cu")
		(hatch none 0.5)
		(connect_pads
			(clearance 0)
		)
		(min_thickness 0.25)
		(keepout
			(tracks not_allowed)
			(vias allowed)
			(pads allowed)
			(copperpour not_allowed)
			(footprints allowed)
		)
		(placement
			(enabled no)
			(sheetname "")
		)
		(fill
			(thermal_gap 0.5)
			(thermal_bridge_width 0.5)
			(island_removal_mode 0)
		)
		(polygon
			(pts
				(xy 21.991828 -4.097528) (xy 22.708108 -4.097528) (xy 22.708108 -8.293608) (xy 21.991828 -8.293608)
			)
		)
	)
	(zone
		(layer "In10.Cu")
		(hatch none 0.5)
		(connect_pads
			(clearance 0)
		)
		(min_thickness 0.25)
		(keepout
			(tracks not_allowed)
			(vias allowed)
			(pads allowed)
			(copperpour not_allowed)
			(footprints allowed)
		)
		(placement
			(enabled no)
			(sheetname "")
		)
		(fill
			(thermal_gap 0.5)
			(thermal_bridge_width 0.5)
			(island_removal_mode 0)
		)
		(polygon
			(pts
				(arc
					(start 67.81546 -13.3858)
					(mid 67.831083 -13.423517)
					(end 67.8688 -13.43914)
				)
				(arc
					(start 68.2752 -13.43914)
					(mid 68.312917 -13.423517)
					(end 68.32854 -13.3858)
				)
				(arc
					(start 68.32854 -13.0302)
					(mid 68.312917 -12.992483)
					(end 68.2752 -12.97686)
				)
				(arc
					(start 67.8688 -12.97686)
					(mid 67.831083 -12.992483)
					(end 67.81546 -13.0302)
				)
			)
		)
	)
	(zone
		(layer "In10.Cu")
		(hatch none 0.5)
		(connect_pads
			(clearance 0)
		)
		(min_thickness 0.25)
		(keepout
			(tracks not_allowed)
			(vias allowed)
			(pads allowed)
			(copperpour not_allowed)
			(footprints allowed)
		)
		(placement
			(enabled no)
			(sheetname "")
		)
		(fill
			(thermal_gap 0.5)
			(thermal_bridge_width 0.5)
			(island_removal_mode 0)
		)
		(polygon
			(pts
				(arc
					(start 45.20946 -12.4968)
					(mid 45.225083 -12.534517)
					(end 45.2628 -12.55014)
				)
				(arc
					(start 45.6692 -12.55014)
					(mid 45.706917 -12.534517)
					(end 45.72254 -12.4968)
				)
				(arc
					(start 45.72254 -12.1412)
					(mid 45.706917 -12.103483)
					(end 45.6692 -12.08786)
				)
				(arc
					(start 45.2628 -12.08786)
					(mid 45.225083 -12.103483)
					(end 45.20946 -12.1412)
				)
			)
		)
	)
	(zone
		(layer "In10.Cu")
		(hatch none 0.5)
		(connect_pads
			(clearance 0)
		)
		(min_thickness 0.25)
		(keepout
			(tracks not_allowed)
			(vias allowed)
			(pads allowed)
			(copperpour not_allowed)
			(footprints allowed)
		)
		(placement
			(enabled no)
			(sheetname "")
		)
		(fill
			(thermal_gap 0.5)
			(thermal_bridge_width 0.5)
			(island_removal_mode 0)
		)
		(polygon
			(pts
				(arc
					(start 37.97427 -13.2588)
					(mid 37.989893 -13.296517)
					(end 38.02761 -13.31214)
				)
				(arc
					(start 38.43401 -13.31214)
					(mid 38.471727 -13.296517)
					(end 38.48735 -13.2588)
				)
				(arc
					(start 38.48735 -12.9032)
					(mid 38.471727 -12.865483)
					(end 38.43401 -12.84986)
				)
				(arc
					(start 38.02761 -12.84986)
					(mid 37.989893 -12.865483)
					(end 37.97427 -12.9032)
				)
			)
		)
	)
	(zone
		(layer "In10.Cu")
		(hatch none 0.5)
		(connect_pads
			(clearance 0)
		)
		(min_thickness 0.25)
		(keepout
			(tracks not_allowed)
			(vias allowed)
			(pads allowed)
			(copperpour not_allowed)
			(footprints allowed)
		)
		(placement
			(enabled no)
			(sheetname "")
		)
		(fill
			(thermal_gap 0.5)
			(thermal_bridge_width 0.5)
			(island_removal_mode 0)
		)
		(polygon
			(pts
				(xy 24.991822 -4.097528) (xy 25.708102 -4.097528) (xy 25.708102 -8.293608) (xy 24.991822 -8.293608)
			)
		)
	)
	(zone
		(layer "In10.Cu")
		(hatch none 0.5)
		(connect_pads
			(clearance 0)
		)
		(min_thickness 0.25)
		(keepout
			(tracks not_allowed)
			(vias allowed)
			(pads allowed)
			(copperpour not_allowed)
			(footprints allowed)
		)
		(placement
			(enabled no)
			(sheetname "")
		)
		(fill
			(thermal_gap 0.5)
			(thermal_bridge_width 0.5)
			(island_removal_mode 0)
		)
		(polygon
			(pts
				(arc
					(start 67.7418 -28.57754)
					(mid 67.779517 -28.561917)
					(end 67.79514 -28.5242)
				)
				(arc
					(start 67.79514 -28.1178)
					(mid 67.779517 -28.080083)
					(end 67.7418 -28.06446)
				)
				(arc
					(start 67.3862 -28.06446)
					(mid 67.348483 -28.080083)
					(end 67.33286 -28.1178)
				)
				(arc
					(start 67.33286 -28.5242)
					(mid 67.348483 -28.561917)
					(end 67.3862 -28.57754)
				)
			)
		)
	)
	(zone
		(net "PV_VDDR")
		(layer "In10.Cu")
		(hatch none 0.5)
		(connect_pads
			(clearance 0.5)
		)
		(min_thickness 0.25)
		(fill yes
			(thermal_gap 0.5)
			(thermal_bridge_width 0.5)
			(island_removal_mode 0)
		)
		(polygon
			(pts
				(xy 99.123246 -44.9834) (xy 98.7044 -45.402246) (xy 98.7044 -50.736754) (xy 102.0064 -54.038754)
				(xy 102.0064 -56.451246) (xy 101.4984 -56.959246) (xy 101.4984 -57.413906) (xy 104.853994 -60.7695)
				(xy 105.742994 -60.7695) (xy 106.123994 -61.1505) (xy 119.204994 -61.1505) (xy 119.458994 -61.4045)
				(xy 147.779994 -61.4045) (xy 148.6535 -62.278006) (xy 148.6535 -65.102994) (xy 148.2725 -65.483994)
				(xy 148.2725 -68.374006) (xy 148.6535 -68.755006) (xy 148.6535 -71.549006) (xy 148.922994 -71.8185)
				(xy 162.354006 -71.8185) (xy 162.6235 -71.549006) (xy 162.6235 -62.405006) (xy 162.7505 -62.278006)
				(xy 163.8935 -61.135006) (xy 163.8935 -57.990994) (xy 162.353752 -56.451246) (xy 159.941514 -54.038754)
				(xy 151.432006 -45.5295) (xy 117.015006 -45.5295) (xy 116.9035 -45.417994) (xy 116.9035 -45.3644)
				(xy 114.490246 -45.3644) (xy 114.3254 -45.529246) (xy 114.236246 -45.6184) (xy 109.029754 -45.6184)
				(xy 108.521754 -45.1104) (xy 107.466638 -45.1104) (xy 107.430316 -45.122592) (xy 107.405932 -45.1104)
				(xy 107.378754 -45.1104) (xy 107.35183 -45.083222) (xy 107.151932 -44.9834) (xy 101.082094 -44.9834)
				(xy 101.043994 -45.0215) (xy 100.886006 -45.0215) (xy 100.847906 -44.9834)
			)
		)
	)
	(zone
		(layer "In10.Cu")
		(hatch none 0.5)
		(connect_pads
			(clearance 0)
		)
		(min_thickness 0.25)
		(keepout
			(tracks not_allowed)
			(vias allowed)
			(pads allowed)
			(copperpour not_allowed)
			(footprints allowed)
		)
		(placement
			(enabled no)
			(sheetname "")
		)
		(fill
			(thermal_gap 0.5)
			(thermal_bridge_width 0.5)
			(island_removal_mode 0)
		)
		(polygon
			(pts
				(arc
					(start 66.9798 -27.81554)
					(mid 67.017517 -27.799917)
					(end 67.03314 -27.7622)
				)
				(arc
					(start 67.03314 -27.3558)
					(mid 67.017517 -27.318083)
					(end 66.9798 -27.30246)
				)
				(arc
					(start 66.6242 -27.30246)
					(mid 66.586483 -27.318083)
					(end 66.57086 -27.3558)
				)
				(arc
					(start 66.57086 -27.7622)
					(mid 66.586483 -27.799917)
					(end 66.6242 -27.81554)
				)
			)
		)
	)
)
